G04 ================== begin FILE IDENTIFICATION RECORD ==================*
G04 Layout Name:  9052_F0T_PDB_Converter_Brick_F_V03_1208_1600.brd*
G04 Film Name:    fab*
G04 File Format:  Gerber RS274X*
G04 File Origin:  Cadence Allegro 17.2-S081*
G04 Origin Date:  Wed Dec 21 09:54:59 2022*
G04 *
G04 Layer:  DRAWING FORMAT/TITLE_BLOCK_A*
G04 Layer:  MANUFACTURING/NCLEGEND-1-10*
G04 Layer:  BOARD GEOMETRY/DESIGN_OUTLINE*
G04 Layer:  BOARD GEOMETRY/CUTOUT*
G04 Layer:  PIN/SPECIAL_DRILL*
G04 Layer:  MANUFACTURING/NCDRILL_LEGEND*
G04 Layer:  MANUFACTURING/NCDRILL_FIGURE*
G04 Layer:  MANUFACTURING/PHOTOPLOT_OUTLINE*
G04 Layer:  MANUFACTURING/DIMENSION*
G04 Layer:  MANUFACTURING/DETAILS*
G04 Layer:  DRAWING FORMAT/TITLE_BLOCK*
G04 Layer:  DRAWING FORMAT/TITLE_DATA_FAB*
G04 Layer:  BOARD GEOMETRY/OUTLINE*
G04 *
G04 Offset:    (0.00 0.00)*
G04 Mirror:    No*
G04 Mode:      Positive*
G04 Rotation:  0*
G04 FullContactRelief:  No*
G04 UndefLineWidth:     6.00*
G04 ================== end FILE IDENTIFICATION RECORD ====================*
%FSLAX25Y25*MOIN*%
%IR0*IPPOS*OFA0.00000B0.00000*MIA0B0*SFA1.00000B1.00000*%
%AMMACRO26*
1,1,.006,.014497,-.035*
20,1,.006,.014497,-.035,-.014497,-.035,0.0*
1,1,.006,-.014497,-.035*
20,1,.006,-.014497,-.035,-.035,-.014497,0.0*
1,1,.006,-.035,-.014497*
20,1,.006,-.035,-.014497,-.035,.014497,0.0*
1,1,.006,-.035,.014497*
20,1,.006,-.035,.014497,-.014497,.035,0.0*
1,1,.006,-.014497,.035*
20,1,.006,-.014497,.035,.014497,.035,0.0*
1,1,.006,.014497,.035*
20,1,.006,.014497,.035,.035,.014497,0.0*
1,1,.006,.035,.014497*
20,1,.006,.035,.014497,.035,-.014497,0.0*
1,1,.006,.035,-.014497*
20,1,.006,.035,-.014497,.014497,-.035,0.0*
1,1,.006,.014497,-.035*
1,1,.006,-.0229,-.01041*
20,1,.006,-.0229,-.01041,-.0229,.00729,0.0*
1,1,.006,-.0229,.00729*
20,1,.006,-.0229,.00729,-.02221,.00902,0.0*
1,1,.006,-.02221,.00902*
20,1,.006,-.02221,.00902,-.02082,.01006,0.0*
1,1,.006,-.02082,.01006*
20,1,.006,-.02082,.01006,-.01874,.01041,0.0*
1,1,.006,-.01874,.01041*
20,1,.006,-.01874,.01041,-.01666,.00972,0.0*
1,1,.006,-.01666,.00972*
20,1,.006,-.01666,.00972,-.01562,.00798,0.0*
1,1,.006,-.01562,.00798*
1,1,.006,-.01978,.00208*
20,1,.006,-.01978,.00208,-.02672,.00208,0.0*
1,1,.006,-.02672,.00208*
1,1,.006,.00001,.00347*
20,1,.006,.00001,.00347,.00001,-.01041,0.0*
1,1,.006,.00001,-.01041*
1,1,.006,.00001,.00902*
20,1,.006,.00001,.00902,-.00068,.00937,0.0*
1,1,.006,-.00068,.00937*
20,1,.006,-.00068,.00937,-.00068,.01006,0.0*
1,1,.006,-.00068,.01006*
20,1,.006,-.00068,.01006,.00001,.01041,0.0*
1,1,.006,.00001,.01041*
20,1,.006,.00001,.01041,.0007,.01006,0.0*
1,1,.006,.0007,.01006*
20,1,.006,.0007,.01006,.0007,.00937,0.0*
1,1,.006,.0007,.00937*
20,1,.006,.0007,.00937,.00001,.00902,0.0*
1,1,.006,.00001,.00902*
1,1,.006,.02084,.01041*
20,1,.006,.02084,.01041,.02084,-.01041,0.0*
1,1,.006,.02084,-.01041*
1,1,.006,.01598,.00347*
20,1,.006,.01598,.00347,.0257,.00347,0.0*
1,1,.006,.0257,.00347*
%
%ADD26MACRO26*%
%AMMACRO12*
4,1,41,.45275,-.05906,
.463006,-.058163,
.47295,-.055498,
.48228,-.051147,
.490713,-.045243,
.497993,-.037963,
.503897,-.02953,
.508248,-.0202,
.510913,-.010256,
.51181,0.0,
.510913,.010256,
.508248,.0202,
.503897,.02953,
.497993,.037963,
.490713,.045243,
.48228,.051147,
.47295,.055498,
.463006,.058163,
.45275,.05906,
.33464,.05906,
-.4082,.09829,
-.425347,.097699,
-.442131,.09414,
-.458041,.08772,
-.472595,.078635,
-.485351,.06716,
-.49592,.053645,
-.503981,.0385,
-.509291,.022185,
-.511686,.005196,
-.511095,-.011951,
-.507536,-.028734,
-.501116,-.044645,
-.492031,-.059199,
-.480557,-.071954,
-.467041,-.082523,
-.451896,-.090585,
-.435582,-.095894,
-.418593,-.09829,
-.4082,-.09829,
.33464,-.05906,
.45275,-.05906,
0.0*
%
%ADD12MACRO12*%
%AMMACRO18*
1,1,.006,.035,0.0*
20,1,.006,.035,0.0,.034468,-.006078,0.0*
1,1,.006,.034468,-.006078*
20,1,.006,.034468,-.006078,.032889,-.011971,0.0*
1,1,.006,.032889,-.011971*
20,1,.006,.032889,-.011971,.030311,-.0175,0.0*
1,1,.006,.030311,-.0175*
20,1,.006,.030311,-.0175,.026812,-.022498,0.0*
1,1,.006,.026812,-.022498*
20,1,.006,.026812,-.022498,.022498,-.026812,0.0*
1,1,.006,.022498,-.026812*
20,1,.006,.022498,-.026812,.0175,-.030311,0.0*
1,1,.006,.0175,-.030311*
20,1,.006,.0175,-.030311,.011971,-.032889,0.0*
1,1,.006,.011971,-.032889*
20,1,.006,.011971,-.032889,.006078,-.034468,0.0*
1,1,.006,.006078,-.034468*
20,1,.006,.006078,-.034468,0.0,-.035,0.0*
1,1,.006,0.0,-.035*
20,1,.006,0.0,-.035,-.006078,-.034468,0.0*
1,1,.006,-.006078,-.034468*
20,1,.006,-.006078,-.034468,-.011971,-.032889,0.0*
1,1,.006,-.011971,-.032889*
20,1,.006,-.011971,-.032889,-.0175,-.030311,0.0*
1,1,.006,-.0175,-.030311*
20,1,.006,-.0175,-.030311,-.022498,-.026812,0.0*
1,1,.006,-.022498,-.026812*
20,1,.006,-.022498,-.026812,-.026812,-.022498,0.0*
1,1,.006,-.026812,-.022498*
20,1,.006,-.026812,-.022498,-.030311,-.0175,0.0*
1,1,.006,-.030311,-.0175*
20,1,.006,-.030311,-.0175,-.032889,-.011971,0.0*
1,1,.006,-.032889,-.011971*
20,1,.006,-.032889,-.011971,-.034468,-.006078,0.0*
1,1,.006,-.034468,-.006078*
20,1,.006,-.034468,-.006078,-.035,0.0,0.0*
1,1,.006,-.035,0.0*
20,1,.006,-.035,0.0,-.034468,.006078,0.0*
1,1,.006,-.034468,.006078*
20,1,.006,-.034468,.006078,-.032889,.011971,0.0*
1,1,.006,-.032889,.011971*
20,1,.006,-.032889,.011971,-.030311,.0175,0.0*
1,1,.006,-.030311,.0175*
20,1,.006,-.030311,.0175,-.026812,.022498,0.0*
1,1,.006,-.026812,.022498*
20,1,.006,-.026812,.022498,-.022498,.026812,0.0*
1,1,.006,-.022498,.026812*
20,1,.006,-.022498,.026812,-.0175,.030311,0.0*
1,1,.006,-.0175,.030311*
20,1,.006,-.0175,.030311,-.011971,.032889,0.0*
1,1,.006,-.011971,.032889*
20,1,.006,-.011971,.032889,-.006078,.034468,0.0*
1,1,.006,-.006078,.034468*
20,1,.006,-.006078,.034468,0.0,.035,0.0*
1,1,.006,0.0,.035*
20,1,.006,0.0,.035,.006078,.034468,0.0*
1,1,.006,.006078,.034468*
20,1,.006,.006078,.034468,.011971,.032889,0.0*
1,1,.006,.011971,.032889*
20,1,.006,.011971,.032889,.0175,.030311,0.0*
1,1,.006,.0175,.030311*
20,1,.006,.0175,.030311,.022498,.026812,0.0*
1,1,.006,.022498,.026812*
20,1,.006,.022498,.026812,.026812,.022498,0.0*
1,1,.006,.026812,.022498*
20,1,.006,.026812,.022498,.030311,.0175,0.0*
1,1,.006,.030311,.0175*
20,1,.006,.030311,.0175,.032889,.011971,0.0*
1,1,.006,.032889,.011971*
20,1,.006,.032889,.011971,.034468,.006078,0.0*
1,1,.006,.034468,.006078*
20,1,.006,.034468,.006078,.035,0.0,0.0*
1,1,.006,.035,0.0*
1,1,.006,-.02082,.01041*
20,1,.006,-.02082,.01041,-.02082,-.01041,0.0*
1,1,.006,-.02082,-.01041*
1,1,.006,-.0288,.01041*
20,1,.006,-.0288,.01041,-.01284,.01041,0.0*
1,1,.006,-.01284,.01041*
1,1,.006,-.00693,-.01041*
20,1,.006,-.00693,-.01041,-.00693,.01041,0.0*
1,1,.006,-.00693,.01041*
20,1,.006,-.00693,.01041,.0014,.01041,0.0*
1,1,.006,.0014,.01041*
20,1,.006,.0014,.01041,.00417,.00937,0.0*
1,1,.006,.00417,.00937*
20,1,.006,.00417,.00937,.00626,.00694,0.0*
1,1,.006,.00626,.00694*
20,1,.006,.00626,.00694,.00695,.00416,0.0*
1,1,.006,.00695,.00416*
20,1,.006,.00695,.00416,.00626,.00139,0.0*
1,1,.006,.00626,.00139*
20,1,.006,.00626,.00139,.00452,-.00069,0.0*
1,1,.006,.00452,-.00069*
20,1,.006,.00452,-.00069,.0014,-.00174,0.0*
1,1,.006,.0014,-.00174*
20,1,.006,.0014,-.00174,-.00693,-.00174,0.0*
1,1,.006,-.00693,-.00174*
1,1,.006,.01216,.01041*
20,1,.006,.01216,.01041,.02084,-.01041,0.0*
1,1,.006,.02084,-.01041*
20,1,.006,.02084,-.01041,.02952,.01041,0.0*
1,1,.006,.02952,.01041*
%
%ADD18MACRO18*%
%AMMACRO25*
1,1,.006,.035,.035*
20,1,.006,.035,.035,.035,-.035,0.0*
1,1,.006,.035,-.035*
20,1,.006,.035,-.035,-.035,-.035,0.0*
1,1,.006,-.035,-.035*
20,1,.006,-.035,-.035,-.035,.035,0.0*
1,1,.006,-.035,.035*
20,1,.006,-.035,.035,.035,.035,0.0*
1,1,.006,.035,.035*
1,1,.006,-.0245,.01225*
20,1,.006,-.0245,.01225,-.02777,.01143,0.0*
1,1,.006,-.02777,.01143*
20,1,.006,-.02777,.01143,-.03022,.00939,0.0*
1,1,.006,-.03022,.00939*
20,1,.006,-.03022,.00939,-.03185,.00694,0.0*
1,1,.006,-.03185,.00694*
20,1,.006,-.03185,.00694,-.03308,.00367,0.0*
1,1,.006,-.03308,.00367*
20,1,.006,-.03308,.00367,-.03348,0.0,0.0*
1,1,.006,-.03348,0.0*
20,1,.006,-.03348,0.0,-.03308,-.00368,0.0*
1,1,.006,-.03308,-.00368*
20,1,.006,-.03308,-.00368,-.03185,-.00694,0.0*
1,1,.006,-.03185,-.00694*
20,1,.006,-.03185,-.00694,-.03022,-.00939,0.0*
1,1,.006,-.03022,-.00939*
20,1,.006,-.03022,-.00939,-.02777,-.01143,0.0*
1,1,.006,-.02777,-.01143*
20,1,.006,-.02777,-.01143,-.0245,-.01225,0.0*
1,1,.006,-.0245,-.01225*
20,1,.006,-.0245,-.01225,-.02123,-.01143,0.0*
1,1,.006,-.02123,-.01143*
20,1,.006,-.02123,-.01143,-.01878,-.00939,0.0*
1,1,.006,-.01878,-.00939*
20,1,.006,-.01878,-.00939,-.01715,-.00694,0.0*
1,1,.006,-.01715,-.00694*
20,1,.006,-.01715,-.00694,-.01592,-.00368,0.0*
1,1,.006,-.01592,-.00368*
20,1,.006,-.01592,-.00368,-.01552,0.0,0.0*
1,1,.006,-.01552,0.0*
20,1,.006,-.01552,0.0,-.01592,.00367,0.0*
1,1,.006,-.01592,.00367*
20,1,.006,-.01592,.00367,-.01715,.00694,0.0*
1,1,.006,-.01715,.00694*
20,1,.006,-.01715,.00694,-.01878,.00939,0.0*
1,1,.006,-.01878,.00939*
20,1,.006,-.01878,.00939,-.02123,.01143,0.0*
1,1,.006,-.02123,.01143*
20,1,.006,-.02123,.01143,-.0245,.01225,0.0*
1,1,.006,-.0245,.01225*
1,1,.006,.00491,-.01225*
20,1,.006,.00491,-.01225,.00491,.01225,0.0*
1,1,.006,.00491,.01225*
20,1,.006,.00491,.01225,-.0102,-.00531,0.0*
1,1,.006,-.0102,-.00531*
20,1,.006,-.0102,-.00531,.01022,-.00531,0.0*
1,1,.006,.01022,-.00531*
1,1,.006,.02452,.01225*
20,1,.006,.02452,.01225,.02125,.01143,0.0*
1,1,.006,.02125,.01143*
20,1,.006,.02125,.01143,.0188,.00939,0.0*
1,1,.006,.0188,.00939*
20,1,.006,.0188,.00939,.01717,.00694,0.0*
1,1,.006,.01717,.00694*
20,1,.006,.01717,.00694,.01594,.00367,0.0*
1,1,.006,.01594,.00367*
20,1,.006,.01594,.00367,.01554,0.0,0.0*
1,1,.006,.01554,0.0*
20,1,.006,.01554,0.0,.01594,-.00368,0.0*
1,1,.006,.01594,-.00368*
20,1,.006,.01594,-.00368,.01717,-.00694,0.0*
1,1,.006,.01717,-.00694*
20,1,.006,.01717,-.00694,.0188,-.00939,0.0*
1,1,.006,.0188,-.00939*
20,1,.006,.0188,-.00939,.02125,-.01143,0.0*
1,1,.006,.02125,-.01143*
20,1,.006,.02125,-.01143,.02452,-.01225,0.0*
1,1,.006,.02452,-.01225*
20,1,.006,.02452,-.01225,.02779,-.01143,0.0*
1,1,.006,.02779,-.01143*
20,1,.006,.02779,-.01143,.03024,-.00939,0.0*
1,1,.006,.03024,-.00939*
20,1,.006,.03024,-.00939,.03187,-.00694,0.0*
1,1,.006,.03187,-.00694*
20,1,.006,.03187,-.00694,.0331,-.00368,0.0*
1,1,.006,.0331,-.00368*
20,1,.006,.0331,-.00368,.0335,0.0,0.0*
1,1,.006,.0335,0.0*
20,1,.006,.0335,0.0,.0331,.00367,0.0*
1,1,.006,.0331,.00367*
20,1,.006,.0331,.00367,.03187,.00694,0.0*
1,1,.006,.03187,.00694*
20,1,.006,.03187,.00694,.03024,.00939,0.0*
1,1,.006,.03024,.00939*
20,1,.006,.03024,.00939,.02779,.01143,0.0*
1,1,.006,.02779,.01143*
20,1,.006,.02779,.01143,.02452,.01225,0.0*
1,1,.006,.02452,.01225*
%
%ADD25MACRO25*%
%AMMACRO29*
1,1,.006,.126,0.0*
20,1,.006,.126,0.0,.124086,-.02188,0.0*
1,1,.006,.124086,-.02188*
20,1,.006,.124086,-.02188,.118401,-.043095,0.0*
1,1,.006,.118401,-.043095*
20,1,.006,.118401,-.043095,.109119,-.063,0.0*
1,1,.006,.109119,-.063*
20,1,.006,.109119,-.063,.096522,-.080991,0.0*
1,1,.006,.096522,-.080991*
20,1,.006,.096522,-.080991,.080991,-.096522,0.0*
1,1,.006,.080991,-.096522*
20,1,.006,.080991,-.096522,.063,-.109119,0.0*
1,1,.006,.063,-.109119*
20,1,.006,.063,-.109119,.043095,-.118401,0.0*
1,1,.006,.043095,-.118401*
20,1,.006,.043095,-.118401,.02188,-.124086,0.0*
1,1,.006,.02188,-.124086*
20,1,.006,.02188,-.124086,0.0,-.126,0.0*
1,1,.006,0.0,-.126*
20,1,.006,0.0,-.126,-.02188,-.124086,0.0*
1,1,.006,-.02188,-.124086*
20,1,.006,-.02188,-.124086,-.043095,-.118401,0.0*
1,1,.006,-.043095,-.118401*
20,1,.006,-.043095,-.118401,-.063,-.109119,0.0*
1,1,.006,-.063,-.109119*
20,1,.006,-.063,-.109119,-.080991,-.096522,0.0*
1,1,.006,-.080991,-.096522*
20,1,.006,-.080991,-.096522,-.096522,-.080991,0.0*
1,1,.006,-.096522,-.080991*
20,1,.006,-.096522,-.080991,-.109119,-.063,0.0*
1,1,.006,-.109119,-.063*
20,1,.006,-.109119,-.063,-.118401,-.043095,0.0*
1,1,.006,-.118401,-.043095*
20,1,.006,-.118401,-.043095,-.124086,-.02188,0.0*
1,1,.006,-.124086,-.02188*
20,1,.006,-.124086,-.02188,-.126,0.0,0.0*
1,1,.006,-.126,0.0*
20,1,.006,-.126,0.0,-.124086,.02188,0.0*
1,1,.006,-.124086,.02188*
20,1,.006,-.124086,.02188,-.118401,.043095,0.0*
1,1,.006,-.118401,.043095*
20,1,.006,-.118401,.043095,-.109119,.063,0.0*
1,1,.006,-.109119,.063*
20,1,.006,-.109119,.063,-.096522,.080991,0.0*
1,1,.006,-.096522,.080991*
20,1,.006,-.096522,.080991,-.080991,.096522,0.0*
1,1,.006,-.080991,.096522*
20,1,.006,-.080991,.096522,-.063,.109119,0.0*
1,1,.006,-.063,.109119*
20,1,.006,-.063,.109119,-.043095,.118401,0.0*
1,1,.006,-.043095,.118401*
20,1,.006,-.043095,.118401,-.02188,.124086,0.0*
1,1,.006,-.02188,.124086*
20,1,.006,-.02188,.124086,0.0,.126,0.0*
1,1,.006,0.0,.126*
20,1,.006,0.0,.126,.02188,.124086,0.0*
1,1,.006,.02188,.124086*
20,1,.006,.02188,.124086,.043095,.118401,0.0*
1,1,.006,.043095,.118401*
20,1,.006,.043095,.118401,.063,.109119,0.0*
1,1,.006,.063,.109119*
20,1,.006,.063,.109119,.080991,.096522,0.0*
1,1,.006,.080991,.096522*
20,1,.006,.080991,.096522,.096522,.080991,0.0*
1,1,.006,.096522,.080991*
20,1,.006,.096522,.080991,.109119,.063,0.0*
1,1,.006,.109119,.063*
20,1,.006,.109119,.063,.118401,.043095,0.0*
1,1,.006,.118401,.043095*
20,1,.006,.118401,.043095,.124086,.02188,0.0*
1,1,.006,.124086,.02188*
20,1,.006,.124086,.02188,.126,0.0,0.0*
1,1,.006,.126,0.0*
1,1,.006,-.09871,.025*
20,1,.006,-.09871,.025,-.09121,.03249,0.0*
1,1,.006,-.09121,.03249*
20,1,.006,-.09121,.03249,-.08246,.03624,0.0*
1,1,.006,-.08246,.03624*
20,1,.006,-.08246,.03624,-.07247,.03749,0.0*
1,1,.006,-.07247,.03749*
20,1,.006,-.07247,.03749,-.05997,.03499,0.0*
1,1,.006,-.05997,.03499*
20,1,.006,-.05997,.03499,-.05122,.02874,0.0*
1,1,.006,-.05122,.02874*
20,1,.006,-.05122,.02874,-.04873,.02125,0.0*
1,1,.006,-.04873,.02125*
20,1,.006,-.04873,.02125,-.04997,.01375,0.0*
1,1,.006,-.04997,.01375*
20,1,.006,-.04997,.01375,-.05497,.0075,0.0*
1,1,.006,-.05497,.0075*
20,1,.006,-.05497,.0075,-.07996,-.00499,0.0*
1,1,.006,-.07996,-.00499*
20,1,.006,-.07996,-.00499,-.09121,-.01374,0.0*
1,1,.006,-.09121,-.01374*
20,1,.006,-.09121,-.01374,-.09871,-.02624,0.0*
1,1,.006,-.09871,-.02624*
20,1,.006,-.09871,-.02624,-.1012,-.03748,0.0*
1,1,.006,-.1012,-.03748*
20,1,.006,-.1012,-.03748,-.04873,-.03748,0.0*
1,1,.006,-.04873,-.03748*
1,1,.006,-.02747,-.02624*
20,1,.006,-.02747,-.02624,-.01998,-.03248,0.0*
1,1,.006,-.01998,-.03248*
20,1,.006,-.01998,-.03248,-.01123,-.03623,0.0*
1,1,.006,-.01123,-.03623*
20,1,.006,-.01123,-.03623,.00001,-.03748,0.0*
1,1,.006,.00001,-.03748*
20,1,.006,.00001,-.03748,.01126,-.03498,0.0*
1,1,.006,.01126,-.03498*
20,1,.006,.01126,-.03498,.02001,-.02998,0.0*
1,1,.006,.02001,-.02998*
20,1,.006,.02001,-.02998,.02625,-.02124,0.0*
1,1,.006,.02625,-.02124*
20,1,.006,.02625,-.02124,.0275,-.01124,0.0*
1,1,.006,.0275,-.01124*
20,1,.006,.0275,-.01124,.02501,-.00125,0.0*
1,1,.006,.02501,-.00125*
20,1,.006,.02501,-.00125,.01876,.005,0.0*
1,1,.006,.01876,.005*
20,1,.006,.01876,.005,.01001,.01,0.0*
1,1,.006,.01001,.01*
20,1,.006,.01001,.01,.00127,.01125,0.0*
1,1,.006,.00127,.01125*
20,1,.006,.00127,.01125,-.00748,.01,0.0*
1,1,.006,-.00748,.01*
20,1,.006,-.00748,.01,-.01873,.005,0.0*
1,1,.006,-.01873,.005*
20,1,.006,-.01873,.005,-.01498,.03749,0.0*
1,1,.006,-.01498,.03749*
20,1,.006,-.01498,.03749,.01876,.03749,0.0*
1,1,.006,.01876,.03749*
1,1,.006,.05125,.025*
20,1,.006,.05125,.025,.05875,.03249,0.0*
1,1,.006,.05875,.03249*
20,1,.006,.05875,.03249,.0675,.03624,0.0*
1,1,.006,.0675,.03624*
20,1,.006,.0675,.03624,.07749,.03749,0.0*
1,1,.006,.07749,.03749*
20,1,.006,.07749,.03749,.08999,.03499,0.0*
1,1,.006,.08999,.03499*
20,1,.006,.08999,.03499,.09874,.02874,0.0*
1,1,.006,.09874,.02874*
20,1,.006,.09874,.02874,.10123,.02125,0.0*
1,1,.006,.10123,.02125*
20,1,.006,.10123,.02125,.09999,.01375,0.0*
1,1,.006,.09999,.01375*
20,1,.006,.09999,.01375,.09499,.0075,0.0*
1,1,.006,.09499,.0075*
20,1,.006,.09499,.0075,.07,-.00499,0.0*
1,1,.006,.07,-.00499*
20,1,.006,.07,-.00499,.05875,-.01374,0.0*
1,1,.006,.05875,-.01374*
20,1,.006,.05875,-.01374,.05125,-.02624,0.0*
1,1,.006,.05125,-.02624*
20,1,.006,.05125,-.02624,.04876,-.03748,0.0*
1,1,.006,.04876,-.03748*
20,1,.006,.04876,-.03748,.10123,-.03748,0.0*
1,1,.006,.10123,-.03748*
%
%ADD29MACRO29*%
%AMMACRO14*
1,1,.006,.0435,0.0*
20,1,.006,.0435,0.0,0.0,-.0435,0.0*
1,1,.006,0.0,-.0435*
20,1,.006,0.0,-.0435,-.0435,0.0,0.0*
1,1,.006,-.0435,0.0*
20,1,.006,-.0435,0.0,0.0,.0435,0.0*
1,1,.006,0.0,.0435*
20,1,.006,0.0,.0435,.0435,0.0,0.0*
1,1,.006,.0435,0.0*
1,1,.006,-.03958,-.02537*
20,1,.006,-.03958,-.02537,-.03958,.00508,0.0*
1,1,.006,-.03958,.00508*
1,1,.006,-.03958,.00051*
20,1,.006,-.03958,.00051,-.03704,.00305,0.0*
1,1,.006,-.03704,.00305*
20,1,.006,-.03704,.00305,-.03451,.00457,0.0*
1,1,.006,-.03451,.00457*
20,1,.006,-.03451,.00457,-.03045,.00508,0.0*
1,1,.006,-.03045,.00508*
20,1,.006,-.03045,.00508,-.02689,.00457,0.0*
1,1,.006,-.02689,.00457*
20,1,.006,-.02689,.00457,-.02334,.00204,0.0*
1,1,.006,-.02334,.00204*
20,1,.006,-.02334,.00204,-.02182,-.00152,0.0*
1,1,.006,-.02182,-.00152*
20,1,.006,-.02182,-.00152,-.02131,-.00507,0.0*
1,1,.006,-.02131,-.00507*
20,1,.006,-.02131,-.00507,-.02182,-.00862,0.0*
1,1,.006,-.02182,-.00862*
20,1,.006,-.02182,-.00862,-.02334,-.01218,0.0*
1,1,.006,-.02334,-.01218*
20,1,.006,-.02334,-.01218,-.02639,-.01421,0.0*
1,1,.006,-.02639,-.01421*
20,1,.006,-.02639,-.01421,-.03045,-.01522,0.0*
1,1,.006,-.03045,-.01522*
20,1,.006,-.03045,-.01522,-.034,-.01471,0.0*
1,1,.006,-.034,-.01471*
20,1,.006,-.034,-.01471,-.03755,-.01319,0.0*
1,1,.006,-.03755,-.01319*
20,1,.006,-.03755,-.01319,-.03958,-.01116,0.0*
1,1,.006,-.03958,-.01116*
1,1,.006,.00001,.00508*
20,1,.006,.00001,.00508,.00001,-.01522,0.0*
1,1,.006,.00001,-.01522*
1,1,.006,.00001,.0132*
20,1,.006,.00001,.0132,-.001,.01371,0.0*
1,1,.006,-.001,.01371*
20,1,.006,-.001,.01371,-.001,.01472,0.0*
1,1,.006,-.001,.01472*
20,1,.006,-.001,.01472,.00001,.01523,0.0*
1,1,.006,.00001,.01523*
20,1,.006,.00001,.01523,.00103,.01472,0.0*
1,1,.006,.00103,.01472*
20,1,.006,.00103,.01472,.00103,.01371,0.0*
1,1,.006,.00103,.01371*
20,1,.006,.00103,.01371,.00001,.0132,0.0*
1,1,.006,.00001,.0132*
1,1,.006,.02185,.00508*
20,1,.006,.02185,.00508,.02185,-.00913,0.0*
1,1,.006,.02185,-.00913*
20,1,.006,.02185,-.00913,.02388,-.01268,0.0*
1,1,.006,.02388,-.01268*
20,1,.006,.02388,-.01268,.02692,-.01471,0.0*
1,1,.006,.02692,-.01471*
20,1,.006,.02692,-.01471,.03047,-.01522,0.0*
1,1,.006,.03047,-.01522*
20,1,.006,.03047,-.01522,.03403,-.01471,0.0*
1,1,.006,.03403,-.01471*
20,1,.006,.03403,-.01471,.03707,-.01268,0.0*
1,1,.006,.03707,-.01268*
20,1,.006,.03707,-.01268,.0391,-.00913,0.0*
1,1,.006,.0391,-.00913*
1,1,.006,.0391,-.01522*
20,1,.006,.0391,-.01522,.0391,.00508,0.0*
1,1,.006,.0391,.00508*
%
%ADD14MACRO14*%
%AMMACRO16*
1,1,.006,.035,.035*
20,1,.006,.035,.035,.035,-.035,0.0*
1,1,.006,.035,-.035*
20,1,.006,.035,-.035,-.035,-.035,0.0*
1,1,.006,-.035,-.035*
20,1,.006,-.035,-.035,-.035,.035,0.0*
1,1,.006,-.035,.035*
20,1,.006,-.035,.035,.035,.035,0.0*
1,1,.006,.035,.035*
1,1,.006,-.0245,.01225*
20,1,.006,-.0245,.01225,-.02777,.01143,0.0*
1,1,.006,-.02777,.01143*
20,1,.006,-.02777,.01143,-.03022,.00939,0.0*
1,1,.006,-.03022,.00939*
20,1,.006,-.03022,.00939,-.03185,.00694,0.0*
1,1,.006,-.03185,.00694*
20,1,.006,-.03185,.00694,-.03308,.00367,0.0*
1,1,.006,-.03308,.00367*
20,1,.006,-.03308,.00367,-.03348,0.0,0.0*
1,1,.006,-.03348,0.0*
20,1,.006,-.03348,0.0,-.03308,-.00368,0.0*
1,1,.006,-.03308,-.00368*
20,1,.006,-.03308,-.00368,-.03185,-.00694,0.0*
1,1,.006,-.03185,-.00694*
20,1,.006,-.03185,-.00694,-.03022,-.00939,0.0*
1,1,.006,-.03022,-.00939*
20,1,.006,-.03022,-.00939,-.02777,-.01143,0.0*
1,1,.006,-.02777,-.01143*
20,1,.006,-.02777,-.01143,-.0245,-.01225,0.0*
1,1,.006,-.0245,-.01225*
20,1,.006,-.0245,-.01225,-.02123,-.01143,0.0*
1,1,.006,-.02123,-.01143*
20,1,.006,-.02123,-.01143,-.01878,-.00939,0.0*
1,1,.006,-.01878,-.00939*
20,1,.006,-.01878,-.00939,-.01715,-.00694,0.0*
1,1,.006,-.01715,-.00694*
20,1,.006,-.01715,-.00694,-.01592,-.00368,0.0*
1,1,.006,-.01592,-.00368*
20,1,.006,-.01592,-.00368,-.01552,0.0,0.0*
1,1,.006,-.01552,0.0*
20,1,.006,-.01552,0.0,-.01592,.00367,0.0*
1,1,.006,-.01592,.00367*
20,1,.006,-.01592,.00367,-.01715,.00694,0.0*
1,1,.006,-.01715,.00694*
20,1,.006,-.01715,.00694,-.01878,.00939,0.0*
1,1,.006,-.01878,.00939*
20,1,.006,-.01878,.00939,-.02123,.01143,0.0*
1,1,.006,-.02123,.01143*
20,1,.006,-.02123,.01143,-.0245,.01225,0.0*
1,1,.006,-.0245,.01225*
1,1,.006,-.00897,-.00735*
20,1,.006,-.00897,-.00735,-.00652,-.01021,0.0*
1,1,.006,-.00652,-.01021*
20,1,.006,-.00652,-.01021,-.00326,-.01184,0.0*
1,1,.006,-.00326,-.01184*
20,1,.006,-.00326,-.01184,.00042,-.01225,0.0*
1,1,.006,.00042,-.01225*
20,1,.006,.00042,-.01225,.00369,-.01184,0.0*
1,1,.006,.00369,-.01184*
20,1,.006,.00369,-.01184,.00695,-.0098,0.0*
1,1,.006,.00695,-.0098*
20,1,.006,.00695,-.0098,.00899,-.00735,0.0*
1,1,.006,.00899,-.00735*
20,1,.006,.00899,-.00735,.0094,-.0049,0.0*
1,1,.006,.0094,-.0049*
20,1,.006,.0094,-.0049,.00859,-.00204,0.0*
1,1,.006,.00859,-.00204*
20,1,.006,.00859,-.00204,.00573,0.0,0.0*
1,1,.006,.00573,0.0*
20,1,.006,.00573,0.0,.00287,.00082,0.0*
1,1,.006,.00287,.00082*
20,1,.006,.00287,.00082,-.00081,.00082,0.0*
1,1,.006,-.00081,.00082*
1,1,.006,.00287,.00082*
20,1,.006,.00287,.00082,.00532,.00204,0.0*
1,1,.006,.00532,.00204*
20,1,.006,.00532,.00204,.00736,.00408,0.0*
1,1,.006,.00736,.00408*
20,1,.006,.00736,.00408,.00818,.00653,0.0*
1,1,.006,.00818,.00653*
20,1,.006,.00818,.00653,.00736,.00898,0.0*
1,1,.006,.00736,.00898*
20,1,.006,.00736,.00898,.00532,.01102,0.0*
1,1,.006,.00532,.01102*
20,1,.006,.00532,.01102,.00164,.01225,0.0*
1,1,.006,.00164,.01225*
20,1,.006,.00164,.01225,-.00203,.01184,0.0*
1,1,.006,-.00203,.01184*
20,1,.006,-.00203,.01184,-.00571,.01021,0.0*
1,1,.006,-.00571,.01021*
1,1,.006,.02942,-.01225*
20,1,.006,.02942,-.01225,.02942,.01225,0.0*
1,1,.006,.02942,.01225*
20,1,.006,.02942,.01225,.01431,-.00531,0.0*
1,1,.006,.01431,-.00531*
20,1,.006,.01431,-.00531,.03473,-.00531,0.0*
1,1,.006,.03473,-.00531*
%
%ADD16MACRO16*%
%AMMACRO22*
1,1,.006,.035,.035*
20,1,.006,.035,.035,.035,-.035,0.0*
1,1,.006,.035,-.035*
20,1,.006,.035,-.035,-.035,-.035,0.0*
1,1,.006,-.035,-.035*
20,1,.006,-.035,-.035,-.035,.035,0.0*
1,1,.006,-.035,.035*
20,1,.006,-.035,.035,.035,.035,0.0*
1,1,.006,.035,.035*
1,1,.006,-.0245,.01225*
20,1,.006,-.0245,.01225,-.02777,.01143,0.0*
1,1,.006,-.02777,.01143*
20,1,.006,-.02777,.01143,-.03022,.00939,0.0*
1,1,.006,-.03022,.00939*
20,1,.006,-.03022,.00939,-.03185,.00694,0.0*
1,1,.006,-.03185,.00694*
20,1,.006,-.03185,.00694,-.03308,.00367,0.0*
1,1,.006,-.03308,.00367*
20,1,.006,-.03308,.00367,-.03348,0.0,0.0*
1,1,.006,-.03348,0.0*
20,1,.006,-.03348,0.0,-.03308,-.00368,0.0*
1,1,.006,-.03308,-.00368*
20,1,.006,-.03308,-.00368,-.03185,-.00694,0.0*
1,1,.006,-.03185,-.00694*
20,1,.006,-.03185,-.00694,-.03022,-.00939,0.0*
1,1,.006,-.03022,-.00939*
20,1,.006,-.03022,-.00939,-.02777,-.01143,0.0*
1,1,.006,-.02777,-.01143*
20,1,.006,-.02777,-.01143,-.0245,-.01225,0.0*
1,1,.006,-.0245,-.01225*
20,1,.006,-.0245,-.01225,-.02123,-.01143,0.0*
1,1,.006,-.02123,-.01143*
20,1,.006,-.02123,-.01143,-.01878,-.00939,0.0*
1,1,.006,-.01878,-.00939*
20,1,.006,-.01878,-.00939,-.01715,-.00694,0.0*
1,1,.006,-.01715,-.00694*
20,1,.006,-.01715,-.00694,-.01592,-.00368,0.0*
1,1,.006,-.01592,-.00368*
20,1,.006,-.01592,-.00368,-.01552,0.0,0.0*
1,1,.006,-.01552,0.0*
20,1,.006,-.01552,0.0,-.01592,.00367,0.0*
1,1,.006,-.01592,.00367*
20,1,.006,-.01592,.00367,-.01715,.00694,0.0*
1,1,.006,-.01715,.00694*
20,1,.006,-.01715,.00694,-.01878,.00939,0.0*
1,1,.006,-.01878,.00939*
20,1,.006,-.01878,.00939,-.02123,.01143,0.0*
1,1,.006,-.02123,.01143*
20,1,.006,-.02123,.01143,-.0245,.01225,0.0*
1,1,.006,-.0245,.01225*
1,1,.006,-.00897,-.00735*
20,1,.006,-.00897,-.00735,-.00652,-.01021,0.0*
1,1,.006,-.00652,-.01021*
20,1,.006,-.00652,-.01021,-.00326,-.01184,0.0*
1,1,.006,-.00326,-.01184*
20,1,.006,-.00326,-.01184,.00042,-.01225,0.0*
1,1,.006,.00042,-.01225*
20,1,.006,.00042,-.01225,.00369,-.01184,0.0*
1,1,.006,.00369,-.01184*
20,1,.006,.00369,-.01184,.00695,-.0098,0.0*
1,1,.006,.00695,-.0098*
20,1,.006,.00695,-.0098,.00899,-.00735,0.0*
1,1,.006,.00899,-.00735*
20,1,.006,.00899,-.00735,.0094,-.0049,0.0*
1,1,.006,.0094,-.0049*
20,1,.006,.0094,-.0049,.00859,-.00204,0.0*
1,1,.006,.00859,-.00204*
20,1,.006,.00859,-.00204,.00573,0.0,0.0*
1,1,.006,.00573,0.0*
20,1,.006,.00573,0.0,.00287,.00082,0.0*
1,1,.006,.00287,.00082*
20,1,.006,.00287,.00082,-.00081,.00082,0.0*
1,1,.006,-.00081,.00082*
1,1,.006,.00287,.00082*
20,1,.006,.00287,.00082,.00532,.00204,0.0*
1,1,.006,.00532,.00204*
20,1,.006,.00532,.00204,.00736,.00408,0.0*
1,1,.006,.00736,.00408*
20,1,.006,.00736,.00408,.00818,.00653,0.0*
1,1,.006,.00818,.00653*
20,1,.006,.00818,.00653,.00736,.00898,0.0*
1,1,.006,.00736,.00898*
20,1,.006,.00736,.00898,.00532,.01102,0.0*
1,1,.006,.00532,.01102*
20,1,.006,.00532,.01102,.00164,.01225,0.0*
1,1,.006,.00164,.01225*
20,1,.006,.00164,.01225,-.00203,.01184,0.0*
1,1,.006,-.00203,.01184*
20,1,.006,-.00203,.01184,-.00571,.01021,0.0*
1,1,.006,-.00571,.01021*
1,1,.006,.01676,-.00204*
20,1,.006,.01676,-.00204,.01962,.00082,0.0*
1,1,.006,.01962,.00082*
20,1,.006,.01962,.00082,.02207,.00245,0.0*
1,1,.006,.02207,.00245*
20,1,.006,.02207,.00245,.02534,.00327,0.0*
1,1,.006,.02534,.00327*
20,1,.006,.02534,.00327,.0282,.00245,0.0*
1,1,.006,.0282,.00245*
20,1,.006,.0282,.00245,.03024,.00082,0.0*
1,1,.006,.03024,.00082*
20,1,.006,.03024,.00082,.03187,-.00163,0.0*
1,1,.006,.03187,-.00163*
20,1,.006,.03187,-.00163,.03228,-.00449,0.0*
1,1,.006,.03228,-.00449*
20,1,.006,.03228,-.00449,.03187,-.00694,0.0*
1,1,.006,.03187,-.00694*
20,1,.006,.03187,-.00694,.03024,-.00939,0.0*
1,1,.006,.03024,-.00939*
20,1,.006,.03024,-.00939,.02779,-.01143,0.0*
1,1,.006,.02779,-.01143*
20,1,.006,.02779,-.01143,.02493,-.01225,0.0*
1,1,.006,.02493,-.01225*
20,1,.006,.02493,-.01225,.02166,-.01143,0.0*
1,1,.006,.02166,-.01143*
20,1,.006,.02166,-.01143,.0188,-.00898,0.0*
1,1,.006,.0188,-.00898*
20,1,.006,.0188,-.00898,.01717,-.00531,0.0*
1,1,.006,.01717,-.00531*
20,1,.006,.01717,-.00531,.01676,-.00123,0.0*
1,1,.006,.01676,-.00123*
20,1,.006,.01676,-.00123,.01758,.00408,0.0*
1,1,.006,.01758,.00408*
20,1,.006,.01758,.00408,.0188,.00694,0.0*
1,1,.006,.0188,.00694*
20,1,.006,.0188,.00694,.02084,.0098,0.0*
1,1,.006,.02084,.0098*
20,1,.006,.02084,.0098,.0237,.01184,0.0*
1,1,.006,.0237,.01184*
20,1,.006,.0237,.01184,.02656,.01225,0.0*
1,1,.006,.02656,.01225*
20,1,.006,.02656,.01225,.02942,.01143,0.0*
1,1,.006,.02942,.01143*
20,1,.006,.02942,.01143,.03146,.00939,0.0*
1,1,.006,.03146,.00939*
%
%ADD22MACRO22*%
%AMMACRO13*
1,1,.006,.0595,0.0*
20,1,.006,.0595,0.0,0.0,-.0595,0.0*
1,1,.006,0.0,-.0595*
20,1,.006,0.0,-.0595,-.0595,0.0,0.0*
1,1,.006,-.0595,0.0*
20,1,.006,-.0595,0.0,0.0,.0595,0.0*
1,1,.006,0.0,.0595*
20,1,.006,0.0,.0595,.0595,0.0,0.0*
1,1,.006,.0595,0.0*
1,1,.006,-.04165,-.02082*
20,1,.006,-.04165,-.02082,-.04165,.02083,0.0*
1,1,.006,-.04165,.02083*
20,1,.006,-.04165,.02083,-.04998,.0125,0.0*
1,1,.006,-.04998,.0125*
1,1,.006,-.04998,-.02082*
20,1,.006,-.04998,-.02082,-.03332,-.02082,0.0*
1,1,.006,-.03332,-.02082*
1,1,.006,.00001,-.02082*
20,1,.006,.00001,-.02082,.00001,.02083,0.0*
1,1,.006,.00001,.02083*
20,1,.006,.00001,.02083,-.00832,.0125,0.0*
1,1,.006,-.00832,.0125*
1,1,.006,-.00832,-.02082*
20,1,.006,-.00832,-.02082,.00834,-.02082,0.0*
1,1,.006,.00834,-.02082*
1,1,.006,.02987,-.01596*
20,1,.006,.02987,-.01596,.03473,-.01943,0.0*
1,1,.006,.03473,-.01943*
20,1,.006,.03473,-.01943,.04029,-.02082,0.0*
1,1,.006,.04029,-.02082*
20,1,.006,.04029,-.02082,.04584,-.01943,0.0*
1,1,.006,.04584,-.01943*
20,1,.006,.04584,-.01943,.0507,-.01527,0.0*
1,1,.006,.0507,-.01527*
20,1,.006,.0507,-.01527,.05417,-.00902,0.0*
1,1,.006,.05417,-.00902*
20,1,.006,.05417,-.00902,.05556,-.00277,0.0*
1,1,.006,.05556,-.00277*
20,1,.006,.05556,-.00277,.05556,.00486,0.0*
1,1,.006,.05556,.00486*
20,1,.006,.05556,.00486,.05417,.01111,0.0*
1,1,.006,.05417,.01111*
20,1,.006,.05417,.01111,.0507,.01666,0.0*
1,1,.006,.0507,.01666*
20,1,.006,.0507,.01666,.04653,.01944,0.0*
1,1,.006,.04653,.01944*
20,1,.006,.04653,.01944,.04167,.02083,0.0*
1,1,.006,.04167,.02083*
20,1,.006,.04167,.02083,.03612,.01944,0.0*
1,1,.006,.03612,.01944*
20,1,.006,.03612,.01944,.03196,.01666,0.0*
1,1,.006,.03196,.01666*
20,1,.006,.03196,.01666,.02918,.0125,0.0*
1,1,.006,.02918,.0125*
20,1,.006,.02918,.0125,.02779,.00695,0.0*
1,1,.006,.02779,.00695*
20,1,.006,.02779,.00695,.02918,.00209,0.0*
1,1,.006,.02918,.00209*
20,1,.006,.02918,.00209,.03265,-.00277,0.0*
1,1,.006,.03265,-.00277*
20,1,.006,.03265,-.00277,.03682,-.00555,0.0*
1,1,.006,.03682,-.00555*
20,1,.006,.03682,-.00555,.04167,-.00624,0.0*
1,1,.006,.04167,-.00624*
20,1,.006,.04167,-.00624,.04723,-.00486,0.0*
1,1,.006,.04723,-.00486*
20,1,.006,.04723,-.00486,.05139,-.00138,0.0*
1,1,.006,.05139,-.00138*
20,1,.006,.05139,-.00138,.05556,.00486,0.0*
1,1,.006,.05556,.00486*
%
%ADD13MACRO13*%
%AMMACRO30*
1,1,.006,-.167,-.0835*
20,1,.006,-.167,-.0835,-.167,.0835,0.0*
1,1,.006,-.167,.0835*
20,1,.006,-.167,.0835,-.2004,.0501,0.0*
1,1,.006,-.2004,.0501*
1,1,.006,-.2004,-.0835*
20,1,.006,-.2004,-.0835,-.1336,-.0835,0.0*
1,1,.006,-.1336,-.0835*
1,1,.006,-.05287,-.01392*
20,1,.006,-.05287,-.01392,-.03339,.00557,0.0*
1,1,.006,-.03339,.00557*
20,1,.006,-.03339,.00557,-.01669,.0167,0.0*
1,1,.006,-.01669,.0167*
20,1,.006,-.01669,.0167,.00558,.02226,0.0*
1,1,.006,.00558,.02226*
20,1,.006,.00558,.02226,.02506,.0167,0.0*
1,1,.006,.02506,.0167*
20,1,.006,.02506,.0167,.03898,.00557,0.0*
1,1,.006,.03898,.00557*
20,1,.006,.03898,.00557,.05011,-.01113,0.0*
1,1,.006,.05011,-.01113*
20,1,.006,.05011,-.01113,.05289,-.03062,0.0*
1,1,.006,.05289,-.03062*
20,1,.006,.05289,-.03062,.05011,-.04732,0.0*
1,1,.006,.05011,-.04732*
20,1,.006,.05011,-.04732,.03898,-.06402,0.0*
1,1,.006,.03898,-.06402*
20,1,.006,.03898,-.06402,.02227,-.07793,0.0*
1,1,.006,.02227,-.07793*
20,1,.006,.02227,-.07793,.0028,-.0835,0.0*
1,1,.006,.0028,-.0835*
20,1,.006,.0028,-.0835,-.01947,-.07793,0.0*
1,1,.006,-.01947,-.07793*
20,1,.006,-.01947,-.07793,-.03896,-.06124,0.0*
1,1,.006,-.03896,-.06124*
20,1,.006,-.03896,-.06124,-.05009,-.03618,0.0*
1,1,.006,-.05009,-.03618*
20,1,.006,-.05009,-.03618,-.05287,-.00835,0.0*
1,1,.006,-.05287,-.00835*
20,1,.006,-.05287,-.00835,-.04731,.02783,0.0*
1,1,.006,-.04731,.02783*
20,1,.006,-.04731,.02783,-.03896,.04732,0.0*
1,1,.006,-.03896,.04732*
20,1,.006,-.03896,.04732,-.02504,.0668,0.0*
1,1,.006,-.02504,.0668*
20,1,.006,-.02504,.0668,-.00556,.08072,0.0*
1,1,.006,-.00556,.08072*
20,1,.006,-.00556,.08072,.01393,.0835,0.0*
1,1,.006,.01393,.0835*
20,1,.006,.01393,.0835,.03341,.07793,0.0*
1,1,.006,.03341,.07793*
20,1,.006,.03341,.07793,.04733,.06402,0.0*
1,1,.006,.04733,.06402*
1,1,.006,.16145,-.0835*
20,1,.006,.16145,-.0835,.16702,-.04732,0.0*
1,1,.006,.16702,-.04732*
20,1,.006,.16702,-.04732,.17537,-.0167,0.0*
1,1,.006,.17537,-.0167*
20,1,.006,.17537,-.0167,.1865,.01113,0.0*
1,1,.006,.1865,.01113*
20,1,.006,.1865,.01113,.20042,.04175,0.0*
1,1,.006,.20042,.04175*
20,1,.006,.20042,.04175,.22269,.0835,0.0*
1,1,.006,.22269,.0835*
20,1,.006,.22269,.0835,.11135,.0835,0.0*
1,1,.006,.11135,.0835*
%
%ADD30MACRO30*%
%AMMACRO20*
1,1,.006,.0415,0.0*
20,1,.006,.0415,0.0,0.0,-.0415,0.0*
1,1,.006,0.0,-.0415*
20,1,.006,0.0,-.0415,-.0415,0.0,0.0*
1,1,.006,-.0415,0.0*
20,1,.006,-.0415,0.0,0.0,.0415,0.0*
1,1,.006,0.0,.0415*
20,1,.006,0.0,.0415,.0415,0.0,0.0*
1,1,.006,.0415,0.0*
1,1,.006,-.02905,.01453*
20,1,.006,-.02905,.01453,-.03292,.01356,0.0*
1,1,.006,-.03292,.01356*
20,1,.006,-.03292,.01356,-.03582,.01114,0.0*
1,1,.006,-.03582,.01114*
20,1,.006,-.03582,.01114,-.03776,.00824,0.0*
1,1,.006,-.03776,.00824*
20,1,.006,-.03776,.00824,-.03921,.00436,0.0*
1,1,.006,-.03921,.00436*
20,1,.006,-.03921,.00436,-.0397,0.0,0.0*
1,1,.006,-.0397,0.0*
20,1,.006,-.0397,0.0,-.03921,-.00435,0.0*
1,1,.006,-.03921,-.00435*
20,1,.006,-.03921,-.00435,-.03776,-.00823,0.0*
1,1,.006,-.03776,-.00823*
20,1,.006,-.03776,-.00823,-.03582,-.01113,0.0*
1,1,.006,-.03582,-.01113*
20,1,.006,-.03582,-.01113,-.03292,-.01355,0.0*
1,1,.006,-.03292,-.01355*
20,1,.006,-.03292,-.01355,-.02905,-.01452,0.0*
1,1,.006,-.02905,-.01452*
20,1,.006,-.02905,-.01452,-.02517,-.01355,0.0*
1,1,.006,-.02517,-.01355*
20,1,.006,-.02517,-.01355,-.02227,-.01113,0.0*
1,1,.006,-.02227,-.01113*
20,1,.006,-.02227,-.01113,-.02033,-.00823,0.0*
1,1,.006,-.02033,-.00823*
20,1,.006,-.02033,-.00823,-.01888,-.00435,0.0*
1,1,.006,-.01888,-.00435*
20,1,.006,-.01888,-.00435,-.01839,0.0,0.0*
1,1,.006,-.01839,0.0*
20,1,.006,-.01839,0.0,-.01888,.00436,0.0*
1,1,.006,-.01888,.00436*
20,1,.006,-.01888,.00436,-.02033,.00824,0.0*
1,1,.006,-.02033,.00824*
20,1,.006,-.02033,.00824,-.02227,.01114,0.0*
1,1,.006,-.02227,.01114*
20,1,.006,-.02227,.01114,-.02517,.01356,0.0*
1,1,.006,-.02517,.01356*
20,1,.006,-.02517,.01356,-.02905,.01453,0.0*
1,1,.006,-.02905,.01453*
1,1,.006,.00001,-.01452*
20,1,.006,.00001,-.01452,.0034,-.01404,0.0*
1,1,.006,.0034,-.01404*
20,1,.006,.0034,-.01404,.00728,-.01258,0.0*
1,1,.006,.00728,-.01258*
20,1,.006,.00728,-.01258,.0097,-.01016,0.0*
1,1,.006,.0097,-.01016*
20,1,.006,.0097,-.01016,.01067,-.00677,0.0*
1,1,.006,.01067,-.00677*
20,1,.006,.01067,-.00677,.0097,-.00338,0.0*
1,1,.006,.0097,-.00338*
20,1,.006,.0097,-.00338,.00679,-.00048,0.0*
1,1,.006,.00679,-.00048*
20,1,.006,.00679,-.00048,.00244,.00097,0.0*
1,1,.006,.00244,.00097*
20,1,.006,.00244,.00097,-.00241,.00097,0.0*
1,1,.006,-.00241,.00097*
20,1,.006,-.00241,.00097,-.00531,.00194,0.0*
1,1,.006,-.00531,.00194*
20,1,.006,-.00531,.00194,-.00773,.00436,0.0*
1,1,.006,-.00773,.00436*
20,1,.006,-.00773,.00436,-.0087,.00775,0.0*
1,1,.006,-.0087,.00775*
20,1,.006,-.0087,.00775,-.00725,.01114,0.0*
1,1,.006,-.00725,.01114*
20,1,.006,-.00725,.01114,-.00386,.01356,0.0*
1,1,.006,-.00386,.01356*
20,1,.006,-.00386,.01356,.00001,.01453,0.0*
1,1,.006,.00001,.01453*
20,1,.006,.00001,.01453,.00389,.01356,0.0*
1,1,.006,.00389,.01356*
20,1,.006,.00389,.01356,.00728,.01114,0.0*
1,1,.006,.00728,.01114*
20,1,.006,.00728,.01114,.00873,.00775,0.0*
1,1,.006,.00873,.00775*
20,1,.006,.00873,.00775,.00776,.00436,0.0*
1,1,.006,.00776,.00436*
20,1,.006,.00776,.00436,.00534,.00194,0.0*
1,1,.006,.00534,.00194*
20,1,.006,.00534,.00194,.00244,.00097,0.0*
1,1,.006,.00244,.00097*
20,1,.006,.00244,.00097,-.00241,.00097,0.0*
1,1,.006,-.00241,.00097*
20,1,.006,-.00241,.00097,-.00676,-.00048,0.0*
1,1,.006,-.00676,-.00048*
20,1,.006,-.00676,-.00048,-.00967,-.00338,0.0*
1,1,.006,-.00967,-.00338*
20,1,.006,-.00967,-.00338,-.01064,-.00677,0.0*
1,1,.006,-.01064,-.00677*
20,1,.006,-.01064,-.00677,-.00967,-.01016,0.0*
1,1,.006,-.00967,-.01016*
20,1,.006,-.00967,-.01016,-.00725,-.01258,0.0*
1,1,.006,-.00725,-.01258*
20,1,.006,-.00725,-.01258,-.00337,-.01404,0.0*
1,1,.006,-.00337,-.01404*
20,1,.006,-.00337,-.01404,.00001,-.01452,0.0*
1,1,.006,.00001,-.01452*
1,1,.006,.01842,-.00871*
20,1,.006,.01842,-.00871,.02133,-.0121,0.0*
1,1,.006,.02133,-.0121*
20,1,.006,.02133,-.0121,.0252,-.01404,0.0*
1,1,.006,.0252,-.01404*
20,1,.006,.0252,-.01404,.02956,-.01452,0.0*
1,1,.006,.02956,-.01452*
20,1,.006,.02956,-.01452,.03343,-.01404,0.0*
1,1,.006,.03343,-.01404*
20,1,.006,.03343,-.01404,.03731,-.01162,0.0*
1,1,.006,.03731,-.01162*
20,1,.006,.03731,-.01162,.03973,-.00871,0.0*
1,1,.006,.03973,-.00871*
20,1,.006,.03973,-.00871,.04021,-.00581,0.0*
1,1,.006,.04021,-.00581*
20,1,.006,.04021,-.00581,.03924,-.00242,0.0*
1,1,.006,.03924,-.00242*
20,1,.006,.03924,-.00242,.03585,0.0,0.0*
1,1,.006,.03585,0.0*
20,1,.006,.03585,0.0,.03246,.00097,0.0*
1,1,.006,.03246,.00097*
20,1,.006,.03246,.00097,.02811,.00097,0.0*
1,1,.006,.02811,.00097*
1,1,.006,.03246,.00097*
20,1,.006,.03246,.00097,.03537,.00243,0.0*
1,1,.006,.03537,.00243*
20,1,.006,.03537,.00243,.03779,.00485,0.0*
1,1,.006,.03779,.00485*
20,1,.006,.03779,.00485,.03876,.00775,0.0*
1,1,.006,.03876,.00775*
20,1,.006,.03876,.00775,.03779,.01066,0.0*
1,1,.006,.03779,.01066*
20,1,.006,.03779,.01066,.03537,.01308,0.0*
1,1,.006,.03537,.01308*
20,1,.006,.03537,.01308,.03101,.01453,0.0*
1,1,.006,.03101,.01453*
20,1,.006,.03101,.01453,.02665,.01405,0.0*
1,1,.006,.02665,.01405*
20,1,.006,.02665,.01405,.0223,.01211,0.0*
1,1,.006,.0223,.01211*
%
%ADD20MACRO20*%
%AMMACRO10*
1,1,.006,.035,0.0*
20,1,.006,.035,0.0,.034468,-.006078,0.0*
1,1,.006,.034468,-.006078*
20,1,.006,.034468,-.006078,.032889,-.011971,0.0*
1,1,.006,.032889,-.011971*
20,1,.006,.032889,-.011971,.030311,-.0175,0.0*
1,1,.006,.030311,-.0175*
20,1,.006,.030311,-.0175,.026812,-.022498,0.0*
1,1,.006,.026812,-.022498*
20,1,.006,.026812,-.022498,.022498,-.026812,0.0*
1,1,.006,.022498,-.026812*
20,1,.006,.022498,-.026812,.0175,-.030311,0.0*
1,1,.006,.0175,-.030311*
20,1,.006,.0175,-.030311,.011971,-.032889,0.0*
1,1,.006,.011971,-.032889*
20,1,.006,.011971,-.032889,.006078,-.034468,0.0*
1,1,.006,.006078,-.034468*
20,1,.006,.006078,-.034468,0.0,-.035,0.0*
1,1,.006,0.0,-.035*
20,1,.006,0.0,-.035,-.006078,-.034468,0.0*
1,1,.006,-.006078,-.034468*
20,1,.006,-.006078,-.034468,-.011971,-.032889,0.0*
1,1,.006,-.011971,-.032889*
20,1,.006,-.011971,-.032889,-.0175,-.030311,0.0*
1,1,.006,-.0175,-.030311*
20,1,.006,-.0175,-.030311,-.022498,-.026812,0.0*
1,1,.006,-.022498,-.026812*
20,1,.006,-.022498,-.026812,-.026812,-.022498,0.0*
1,1,.006,-.026812,-.022498*
20,1,.006,-.026812,-.022498,-.030311,-.0175,0.0*
1,1,.006,-.030311,-.0175*
20,1,.006,-.030311,-.0175,-.032889,-.011971,0.0*
1,1,.006,-.032889,-.011971*
20,1,.006,-.032889,-.011971,-.034468,-.006078,0.0*
1,1,.006,-.034468,-.006078*
20,1,.006,-.034468,-.006078,-.035,0.0,0.0*
1,1,.006,-.035,0.0*
20,1,.006,-.035,0.0,-.034468,.006078,0.0*
1,1,.006,-.034468,.006078*
20,1,.006,-.034468,.006078,-.032889,.011971,0.0*
1,1,.006,-.032889,.011971*
20,1,.006,-.032889,.011971,-.030311,.0175,0.0*
1,1,.006,-.030311,.0175*
20,1,.006,-.030311,.0175,-.026812,.022498,0.0*
1,1,.006,-.026812,.022498*
20,1,.006,-.026812,.022498,-.022498,.026812,0.0*
1,1,.006,-.022498,.026812*
20,1,.006,-.022498,.026812,-.0175,.030311,0.0*
1,1,.006,-.0175,.030311*
20,1,.006,-.0175,.030311,-.011971,.032889,0.0*
1,1,.006,-.011971,.032889*
20,1,.006,-.011971,.032889,-.006078,.034468,0.0*
1,1,.006,-.006078,.034468*
20,1,.006,-.006078,.034468,0.0,.035,0.0*
1,1,.006,0.0,.035*
20,1,.006,0.0,.035,.006078,.034468,0.0*
1,1,.006,.006078,.034468*
20,1,.006,.006078,.034468,.011971,.032889,0.0*
1,1,.006,.011971,.032889*
20,1,.006,.011971,.032889,.0175,.030311,0.0*
1,1,.006,.0175,.030311*
20,1,.006,.0175,.030311,.022498,.026812,0.0*
1,1,.006,.022498,.026812*
20,1,.006,.022498,.026812,.026812,.022498,0.0*
1,1,.006,.026812,.022498*
20,1,.006,.026812,.022498,.030311,.0175,0.0*
1,1,.006,.030311,.0175*
20,1,.006,.030311,.0175,.032889,.011971,0.0*
1,1,.006,.032889,.011971*
20,1,.006,.032889,.011971,.034468,.006078,0.0*
1,1,.006,.034468,.006078*
20,1,.006,.034468,.006078,.035,0.0,0.0*
1,1,.006,.035,0.0*
1,1,.006,-.0295,.01041*
20,1,.006,-.0295,.01041,-.02082,-.01041,0.0*
1,1,.006,-.02082,-.01041*
20,1,.006,-.02082,-.01041,-.01214,.01041,0.0*
1,1,.006,-.01214,.01041*
1,1,.006,.00001,-.01041*
20,1,.006,.00001,-.01041,.00001,.01041,0.0*
1,1,.006,.00001,.01041*
20,1,.006,.00001,.01041,-.00415,.00625,0.0*
1,1,.006,-.00415,.00625*
1,1,.006,-.00415,-.01041*
20,1,.006,-.00415,-.01041,.00417,-.01041,0.0*
1,1,.006,.00417,-.01041*
1,1,.006,.02084,.01041*
20,1,.006,.02084,.01041,.01806,.00972,0.0*
1,1,.006,.01806,.00972*
20,1,.006,.01806,.00972,.01598,.00798,0.0*
1,1,.006,.01598,.00798*
20,1,.006,.01598,.00798,.01459,.0059,0.0*
1,1,.006,.01459,.0059*
20,1,.006,.01459,.0059,.01355,.00312,0.0*
1,1,.006,.01355,.00312*
20,1,.006,.01355,.00312,.01321,0.0,0.0*
1,1,.006,.01321,0.0*
20,1,.006,.01321,0.0,.01355,-.00312,0.0*
1,1,.006,.01355,-.00312*
20,1,.006,.01355,-.00312,.01459,-.0059,0.0*
1,1,.006,.01459,-.0059*
20,1,.006,.01459,-.0059,.01598,-.00798,0.0*
1,1,.006,.01598,-.00798*
20,1,.006,.01598,-.00798,.01806,-.00972,0.0*
1,1,.006,.01806,-.00972*
20,1,.006,.01806,-.00972,.02084,-.01041,0.0*
1,1,.006,.02084,-.01041*
20,1,.006,.02084,-.01041,.02362,-.00972,0.0*
1,1,.006,.02362,-.00972*
20,1,.006,.02362,-.00972,.0257,-.00798,0.0*
1,1,.006,.0257,-.00798*
20,1,.006,.0257,-.00798,.02709,-.0059,0.0*
1,1,.006,.02709,-.0059*
20,1,.006,.02709,-.0059,.02813,-.00312,0.0*
1,1,.006,.02813,-.00312*
20,1,.006,.02813,-.00312,.02847,0.0,0.0*
1,1,.006,.02847,0.0*
20,1,.006,.02847,0.0,.02813,.00312,0.0*
1,1,.006,.02813,.00312*
20,1,.006,.02813,.00312,.02709,.0059,0.0*
1,1,.006,.02709,.0059*
20,1,.006,.02709,.0059,.0257,.00798,0.0*
1,1,.006,.0257,.00798*
20,1,.006,.0257,.00798,.02362,.00972,0.0*
1,1,.006,.02362,.00972*
20,1,.006,.02362,.00972,.02084,.01041,0.0*
1,1,.006,.02084,.01041*
%
%ADD10MACRO10*%
%ADD11C,.125*%
%AMMACRO19*
1,1,.006,.0625,0.0*
20,1,.006,.0625,0.0,.03125,.054127,0.0*
1,1,.006,.03125,.054127*
20,1,.006,.03125,.054127,-.03125,.054127,0.0*
1,1,.006,-.03125,.054127*
20,1,.006,-.03125,.054127,-.0625,0.0,0.0*
1,1,.006,-.0625,0.0*
20,1,.006,-.0625,0.0,-.03125,-.054127,0.0*
1,1,.006,-.03125,-.054127*
20,1,.006,-.03125,-.054127,.03125,-.054127,0.0*
1,1,.006,.03125,-.054127*
20,1,.006,.03125,-.054127,.0625,0.0,0.0*
1,1,.006,.0625,0.0*
1,1,.006,-.02143,-.02552*
20,1,.006,-.02143,-.02552,-.02143,.0051,0.0*
1,1,.006,-.02143,.0051*
1,1,.006,-.02143,.00051*
20,1,.006,-.02143,.00051,-.02399,.00306,0.0*
1,1,.006,-.02399,.00306*
20,1,.006,-.02399,.00306,-.02705,.00459,0.0*
1,1,.006,-.02705,.00459*
20,1,.006,-.02705,.00459,-.03062,.0051,0.0*
1,1,.006,-.03062,.0051*
20,1,.006,-.03062,.0051,-.03368,.00459,0.0*
1,1,.006,-.03368,.00459*
20,1,.006,-.03368,.00459,-.03725,.00204,0.0*
1,1,.006,-.03725,.00204*
20,1,.006,-.03725,.00204,-.0393,-.00153,0.0*
1,1,.006,-.0393,-.00153*
20,1,.006,-.0393,-.00153,-.03981,-.0051,0.0*
1,1,.006,-.03981,-.0051*
20,1,.006,-.03981,-.0051,-.0393,-.00868,0.0*
1,1,.006,-.0393,-.00868*
20,1,.006,-.0393,-.00868,-.03725,-.01225,0.0*
1,1,.006,-.03725,-.01225*
20,1,.006,-.03725,-.01225,-.03368,-.0148,0.0*
1,1,.006,-.03368,-.0148*
20,1,.006,-.03368,-.0148,-.03062,-.01531,0.0*
1,1,.006,-.03062,-.01531*
20,1,.006,-.03062,-.01531,-.02705,-.0148,0.0*
1,1,.006,-.02705,-.0148*
20,1,.006,-.02705,-.0148,-.02399,-.01327,0.0*
1,1,.006,-.02399,-.01327*
20,1,.006,-.02399,-.01327,-.02143,-.01072,0.0*
1,1,.006,-.02143,-.01072*
1,1,.006,-.01275,.0051*
20,1,.006,-.01275,.0051,-.00662,-.01531,0.0*
1,1,.006,-.00662,-.01531*
20,1,.006,-.00662,-.01531,.00001,.0051,0.0*
1,1,.006,.00001,.0051*
20,1,.006,.00001,.0051,.00664,-.01531,0.0*
1,1,.006,.00664,-.01531*
20,1,.006,.00664,-.01531,.01277,.0051,0.0*
1,1,.006,.01277,.0051*
1,1,.006,.03064,.01531*
20,1,.006,.03064,.01531,.03064,-.01531,0.0*
1,1,.006,.03064,-.01531*
1,1,.006,.0235,.0051*
20,1,.006,.0235,.0051,.03778,.0051,0.0*
1,1,.006,.03778,.0051*
%
%ADD19MACRO19*%
%AMMACRO24*
1,1,.006,.063,0.0*
20,1,.006,.063,0.0,.0315,.05456,0.0*
1,1,.006,.0315,.05456*
20,1,.006,.0315,.05456,-.0315,.05456,0.0*
1,1,.006,-.0315,.05456*
20,1,.006,-.0315,.05456,-.063,0.0,0.0*
1,1,.006,-.063,0.0*
20,1,.006,-.063,0.0,-.0315,-.05456,0.0*
1,1,.006,-.0315,-.05456*
20,1,.006,-.0315,-.05456,.0315,-.05456,0.0*
1,1,.006,.0315,-.05456*
20,1,.006,.0315,-.05456,.063,0.0,0.0*
1,1,.006,.063,0.0*
1,1,.006,-.0216,-.02572*
20,1,.006,-.0216,-.02572,-.0216,.00515,0.0*
1,1,.006,-.0216,.00515*
1,1,.006,-.0216,.00052*
20,1,.006,-.0216,.00052,-.02418,.00309,0.0*
1,1,.006,-.02418,.00309*
20,1,.006,-.02418,.00309,-.02726,.00463,0.0*
1,1,.006,-.02726,.00463*
20,1,.006,-.02726,.00463,-.03087,.00515,0.0*
1,1,.006,-.03087,.00515*
20,1,.006,-.03087,.00515,-.03395,.00463,0.0*
1,1,.006,-.03395,.00463*
20,1,.006,-.03395,.00463,-.03755,.00206,0.0*
1,1,.006,-.03755,.00206*
20,1,.006,-.03755,.00206,-.03961,-.00154,0.0*
1,1,.006,-.03961,-.00154*
20,1,.006,-.03961,-.00154,-.04013,-.00514,0.0*
1,1,.006,-.04013,-.00514*
20,1,.006,-.04013,-.00514,-.03961,-.00874,0.0*
1,1,.006,-.03961,-.00874*
20,1,.006,-.03961,-.00874,-.03755,-.01234,0.0*
1,1,.006,-.03755,-.01234*
20,1,.006,-.03755,-.01234,-.03395,-.01492,0.0*
1,1,.006,-.03395,-.01492*
20,1,.006,-.03395,-.01492,-.03087,-.01543,0.0*
1,1,.006,-.03087,-.01543*
20,1,.006,-.03087,-.01543,-.02726,-.01492,0.0*
1,1,.006,-.02726,-.01492*
20,1,.006,-.02726,-.01492,-.02418,-.01337,0.0*
1,1,.006,-.02418,-.01337*
20,1,.006,-.02418,-.01337,-.0216,-.0108,0.0*
1,1,.006,-.0216,-.0108*
1,1,.006,-.01285,.00515*
20,1,.006,-.01285,.00515,-.00667,-.01543,0.0*
1,1,.006,-.00667,-.01543*
20,1,.006,-.00667,-.01543,.00001,.00515,0.0*
1,1,.006,.00001,.00515*
20,1,.006,.00001,.00515,.0067,-.01543,0.0*
1,1,.006,.0067,-.01543*
20,1,.006,.0067,-.01543,.01288,.00515,0.0*
1,1,.006,.01288,.00515*
1,1,.006,.02009,-.02469*
20,1,.006,.02009,-.02469,.02318,-.02572,0.0*
1,1,.006,.02318,-.02572*
20,1,.006,.02318,-.02572,.02729,-.02469,0.0*
1,1,.006,.02729,-.02469*
20,1,.006,.02729,-.02469,.02987,-.02263,0.0*
1,1,.006,.02987,-.02263*
20,1,.006,.02987,-.02263,.03192,-.02006,0.0*
1,1,.006,.03192,-.02006*
20,1,.006,.03192,-.02006,.03501,-.01183,0.0*
1,1,.006,.03501,-.01183*
20,1,.006,.03501,-.01183,.0417,.00515,0.0*
1,1,.006,.0417,.00515*
1,1,.006,.02524,.00515*
20,1,.006,.02524,.00515,.03501,-.01183,0.0*
1,1,.006,.03501,-.01183*
%
%ADD24MACRO24*%
%AMMACRO15*
1,1,.006,0.0,.035*
20,1,.006,0.0,.035,.030311,-.0175,0.0*
1,1,.006,.030311,-.0175*
20,1,.006,.030311,-.0175,-.030311,-.0175,0.0*
1,1,.006,-.030311,-.0175*
20,1,.006,-.030311,-.0175,0.0,.035,0.0*
1,1,.006,0.0,.035*
1,1,.006,-.01102,.00551*
20,1,.006,-.01102,.00551,-.01249,.00514,0.0*
1,1,.006,-.01249,.00514*
20,1,.006,-.01249,.00514,-.01359,.00422,0.0*
1,1,.006,-.01359,.00422*
20,1,.006,-.01359,.00422,-.01433,.00312,0.0*
1,1,.006,-.01433,.00312*
20,1,.006,-.01433,.00312,-.01488,.00165,0.0*
1,1,.006,-.01488,.00165*
20,1,.006,-.01488,.00165,-.01506,0.0,0.0*
1,1,.006,-.01506,0.0*
20,1,.006,-.01506,0.0,-.01488,-.00165,0.0*
1,1,.006,-.01488,-.00165*
20,1,.006,-.01488,-.00165,-.01433,-.00312,0.0*
1,1,.006,-.01433,-.00312*
20,1,.006,-.01433,-.00312,-.01359,-.00422,0.0*
1,1,.006,-.01359,-.00422*
20,1,.006,-.01359,-.00422,-.01249,-.00514,0.0*
1,1,.006,-.01249,-.00514*
20,1,.006,-.01249,-.00514,-.01102,-.00551,0.0*
1,1,.006,-.01102,-.00551*
20,1,.006,-.01102,-.00551,-.00955,-.00514,0.0*
1,1,.006,-.00955,-.00514*
20,1,.006,-.00955,-.00514,-.00845,-.00422,0.0*
1,1,.006,-.00845,-.00422*
20,1,.006,-.00845,-.00422,-.00771,-.00312,0.0*
1,1,.006,-.00771,-.00312*
20,1,.006,-.00771,-.00312,-.00716,-.00165,0.0*
1,1,.006,-.00716,-.00165*
20,1,.006,-.00716,-.00165,-.00698,0.0,0.0*
1,1,.006,-.00698,0.0*
20,1,.006,-.00698,0.0,-.00716,.00165,0.0*
1,1,.006,-.00716,.00165*
20,1,.006,-.00716,.00165,-.00771,.00312,0.0*
1,1,.006,-.00771,.00312*
20,1,.006,-.00771,.00312,-.00845,.00422,0.0*
1,1,.006,-.00845,.00422*
20,1,.006,-.00845,.00422,-.00955,.00514,0.0*
1,1,.006,-.00955,.00514*
20,1,.006,-.00955,.00514,-.01102,.00551,0.0*
1,1,.006,-.01102,.00551*
1,1,.006,.00221,-.00551*
20,1,.006,.00221,-.00551,.00221,.00551,0.0*
1,1,.006,.00221,.00551*
20,1,.006,.00221,.00551,-.00458,-.00239,0.0*
1,1,.006,-.00458,-.00239*
20,1,.006,-.00458,-.00239,.0046,-.00239,0.0*
1,1,.006,.0046,-.00239*
1,1,.006,.01104,-.00551*
20,1,.006,.01104,-.00551,.01104,.00551,0.0*
1,1,.006,.01104,.00551*
20,1,.006,.01104,.00551,.00884,.00331,0.0*
1,1,.006,.00884,.00331*
1,1,.006,.00884,-.00551*
20,1,.006,.00884,-.00551,.01324,-.00551,0.0*
1,1,.006,.01324,-.00551*
%
%ADD15MACRO15*%
%AMMACRO21*
1,1,.006,0.0,.035*
20,1,.006,0.0,.035,.030311,-.0175,0.0*
1,1,.006,.030311,-.0175*
20,1,.006,.030311,-.0175,-.030311,-.0175,0.0*
1,1,.006,-.030311,-.0175*
20,1,.006,-.030311,-.0175,0.0,.035,0.0*
1,1,.006,0.0,.035*
1,1,.006,-.01102,.00551*
20,1,.006,-.01102,.00551,-.01249,.00514,0.0*
1,1,.006,-.01249,.00514*
20,1,.006,-.01249,.00514,-.01359,.00422,0.0*
1,1,.006,-.01359,.00422*
20,1,.006,-.01359,.00422,-.01433,.00312,0.0*
1,1,.006,-.01433,.00312*
20,1,.006,-.01433,.00312,-.01488,.00165,0.0*
1,1,.006,-.01488,.00165*
20,1,.006,-.01488,.00165,-.01506,0.0,0.0*
1,1,.006,-.01506,0.0*
20,1,.006,-.01506,0.0,-.01488,-.00165,0.0*
1,1,.006,-.01488,-.00165*
20,1,.006,-.01488,-.00165,-.01433,-.00312,0.0*
1,1,.006,-.01433,-.00312*
20,1,.006,-.01433,-.00312,-.01359,-.00422,0.0*
1,1,.006,-.01359,-.00422*
20,1,.006,-.01359,-.00422,-.01249,-.00514,0.0*
1,1,.006,-.01249,-.00514*
20,1,.006,-.01249,-.00514,-.01102,-.00551,0.0*
1,1,.006,-.01102,-.00551*
20,1,.006,-.01102,-.00551,-.00955,-.00514,0.0*
1,1,.006,-.00955,-.00514*
20,1,.006,-.00955,-.00514,-.00845,-.00422,0.0*
1,1,.006,-.00845,-.00422*
20,1,.006,-.00845,-.00422,-.00771,-.00312,0.0*
1,1,.006,-.00771,-.00312*
20,1,.006,-.00771,-.00312,-.00716,-.00165,0.0*
1,1,.006,-.00716,-.00165*
20,1,.006,-.00716,-.00165,-.00698,0.0,0.0*
1,1,.006,-.00698,0.0*
20,1,.006,-.00698,0.0,-.00716,.00165,0.0*
1,1,.006,-.00716,.00165*
20,1,.006,-.00716,.00165,-.00771,.00312,0.0*
1,1,.006,-.00771,.00312*
20,1,.006,-.00771,.00312,-.00845,.00422,0.0*
1,1,.006,-.00845,.00422*
20,1,.006,-.00845,.00422,-.00955,.00514,0.0*
1,1,.006,-.00955,.00514*
20,1,.006,-.00955,.00514,-.01102,.00551,0.0*
1,1,.006,-.01102,.00551*
1,1,.006,.00221,-.00551*
20,1,.006,.00221,-.00551,.00221,.00551,0.0*
1,1,.006,.00221,.00551*
20,1,.006,.00221,.00551,-.00458,-.00239,0.0*
1,1,.006,-.00458,-.00239*
20,1,.006,-.00458,-.00239,.0046,-.00239,0.0*
1,1,.006,.0046,-.00239*
1,1,.006,.00755,.00367*
20,1,.006,.00755,.00367,.00865,.00478,0.0*
1,1,.006,.00865,.00478*
20,1,.006,.00865,.00478,.00994,.00533,0.0*
1,1,.006,.00994,.00533*
20,1,.006,.00994,.00533,.01141,.00551,0.0*
1,1,.006,.01141,.00551*
20,1,.006,.01141,.00551,.01324,.00514,0.0*
1,1,.006,.01324,.00514*
20,1,.006,.01324,.00514,.01453,.00422,0.0*
1,1,.006,.01453,.00422*
20,1,.006,.01453,.00422,.0149,.00312,0.0*
1,1,.006,.0149,.00312*
20,1,.006,.0149,.00312,.01471,.00202,0.0*
1,1,.006,.01471,.00202*
20,1,.006,.01471,.00202,.01398,.0011,0.0*
1,1,.006,.01398,.0011*
20,1,.006,.01398,.0011,.01031,-.00073,0.0*
1,1,.006,.01031,-.00073*
20,1,.006,.01031,-.00073,.00865,-.00202,0.0*
1,1,.006,.00865,-.00202*
20,1,.006,.00865,-.00202,.00755,-.00386,0.0*
1,1,.006,.00755,-.00386*
20,1,.006,.00755,-.00386,.00718,-.00551,0.0*
1,1,.006,.00718,-.00551*
20,1,.006,.00718,-.00551,.0149,-.00551,0.0*
1,1,.006,.0149,-.00551*
%
%ADD21MACRO21*%
%AMMACRO17*
1,1,.006,.078,0.0*
20,1,.006,.078,0.0,.039,.06755,0.0*
1,1,.006,.039,.06755*
20,1,.006,.039,.06755,-.039,.06755,0.0*
1,1,.006,-.039,.06755*
20,1,.006,-.039,.06755,-.078,0.0,0.0*
1,1,.006,-.078,0.0*
20,1,.006,-.078,0.0,-.039,-.06755,0.0*
1,1,.006,-.039,-.06755*
20,1,.006,-.039,-.06755,.039,-.06755,0.0*
1,1,.006,.039,-.06755*
20,1,.006,.039,-.06755,.078,0.0,0.0*
1,1,.006,.078,0.0*
1,1,.006,-.02675,-.03185*
20,1,.006,-.02675,-.03185,-.02675,.00637,0.0*
1,1,.006,-.02675,.00637*
1,1,.006,-.02675,.00064*
20,1,.006,-.02675,.00064,-.02994,.00382,0.0*
1,1,.006,-.02994,.00382*
20,1,.006,-.02994,.00382,-.03376,.00573,0.0*
1,1,.006,-.03376,.00573*
20,1,.006,-.03376,.00573,-.03822,.00637,0.0*
1,1,.006,-.03822,.00637*
20,1,.006,-.03822,.00637,-.04204,.00573,0.0*
1,1,.006,-.04204,.00573*
20,1,.006,-.04204,.00573,-.0465,.00255,0.0*
1,1,.006,-.0465,.00255*
20,1,.006,-.0465,.00255,-.04905,-.00191,0.0*
1,1,.006,-.04905,-.00191*
20,1,.006,-.04905,-.00191,-.04969,-.00637,0.0*
1,1,.006,-.04969,-.00637*
20,1,.006,-.04969,-.00637,-.04905,-.01083,0.0*
1,1,.006,-.04905,-.01083*
20,1,.006,-.04905,-.01083,-.0465,-.01529,0.0*
1,1,.006,-.0465,-.01529*
20,1,.006,-.0465,-.01529,-.04204,-.01847,0.0*
1,1,.006,-.04204,-.01847*
20,1,.006,-.04204,-.01847,-.03822,-.01911,0.0*
1,1,.006,-.03822,-.01911*
20,1,.006,-.03822,-.01911,-.03376,-.01847,0.0*
1,1,.006,-.03376,-.01847*
20,1,.006,-.03376,-.01847,-.02994,-.01656,0.0*
1,1,.006,-.02994,-.01656*
20,1,.006,-.02994,-.01656,-.02675,-.01338,0.0*
1,1,.006,-.02675,-.01338*
1,1,.006,.00001,.01911*
20,1,.006,.00001,.01911,.00001,-.01911,0.0*
1,1,.006,.00001,-.01911*
1,1,.006,-.00891,.00637*
20,1,.006,-.00891,.00637,.00893,.00637,0.0*
1,1,.006,.00893,.00637*
1,1,.006,.02486,-.03058*
20,1,.006,.02486,-.03058,.02869,-.03185,0.0*
1,1,.006,.02869,-.03185*
20,1,.006,.02869,-.03185,.03378,-.03058,0.0*
1,1,.006,.03378,-.03058*
20,1,.006,.03378,-.03058,.03697,-.02803,0.0*
1,1,.006,.03697,-.02803*
20,1,.006,.03697,-.02803,.03951,-.02484,0.0*
1,1,.006,.03951,-.02484*
20,1,.006,.03951,-.02484,.04334,-.01465,0.0*
1,1,.006,.04334,-.01465*
20,1,.006,.04334,-.01465,.05162,.00637,0.0*
1,1,.006,.05162,.00637*
1,1,.006,.03123,.00637*
20,1,.006,.03123,.00637,.04334,-.01465,0.0*
1,1,.006,.04334,-.01465*
%
%ADD17MACRO17*%
%AMMACRO23*
1,1,.006,0.0,.035*
20,1,.006,0.0,.035,.030311,-.0175,0.0*
1,1,.006,.030311,-.0175*
20,1,.006,.030311,-.0175,-.030311,-.0175,0.0*
1,1,.006,-.030311,-.0175*
20,1,.006,-.030311,-.0175,0.0,.035,0.0*
1,1,.006,0.0,.035*
1,1,.006,-.01102,.00551*
20,1,.006,-.01102,.00551,-.01249,.00514,0.0*
1,1,.006,-.01249,.00514*
20,1,.006,-.01249,.00514,-.01359,.00422,0.0*
1,1,.006,-.01359,.00422*
20,1,.006,-.01359,.00422,-.01433,.00312,0.0*
1,1,.006,-.01433,.00312*
20,1,.006,-.01433,.00312,-.01488,.00165,0.0*
1,1,.006,-.01488,.00165*
20,1,.006,-.01488,.00165,-.01506,0.0,0.0*
1,1,.006,-.01506,0.0*
20,1,.006,-.01506,0.0,-.01488,-.00165,0.0*
1,1,.006,-.01488,-.00165*
20,1,.006,-.01488,-.00165,-.01433,-.00312,0.0*
1,1,.006,-.01433,-.00312*
20,1,.006,-.01433,-.00312,-.01359,-.00422,0.0*
1,1,.006,-.01359,-.00422*
20,1,.006,-.01359,-.00422,-.01249,-.00514,0.0*
1,1,.006,-.01249,-.00514*
20,1,.006,-.01249,-.00514,-.01102,-.00551,0.0*
1,1,.006,-.01102,-.00551*
20,1,.006,-.01102,-.00551,-.00955,-.00514,0.0*
1,1,.006,-.00955,-.00514*
20,1,.006,-.00955,-.00514,-.00845,-.00422,0.0*
1,1,.006,-.00845,-.00422*
20,1,.006,-.00845,-.00422,-.00771,-.00312,0.0*
1,1,.006,-.00771,-.00312*
20,1,.006,-.00771,-.00312,-.00716,-.00165,0.0*
1,1,.006,-.00716,-.00165*
20,1,.006,-.00716,-.00165,-.00698,0.0,0.0*
1,1,.006,-.00698,0.0*
20,1,.006,-.00698,0.0,-.00716,.00165,0.0*
1,1,.006,-.00716,.00165*
20,1,.006,-.00716,.00165,-.00771,.00312,0.0*
1,1,.006,-.00771,.00312*
20,1,.006,-.00771,.00312,-.00845,.00422,0.0*
1,1,.006,-.00845,.00422*
20,1,.006,-.00845,.00422,-.00955,.00514,0.0*
1,1,.006,-.00955,.00514*
20,1,.006,-.00955,.00514,-.01102,.00551,0.0*
1,1,.006,-.01102,.00551*
1,1,.006,-.00348,-.00092*
20,1,.006,-.00348,-.00092,-.00219,.00037,0.0*
1,1,.006,-.00219,.00037*
20,1,.006,-.00219,.00037,-.00109,.0011,0.0*
1,1,.006,-.00109,.0011*
20,1,.006,-.00109,.0011,.00038,.00147,0.0*
1,1,.006,.00038,.00147*
20,1,.006,.00038,.00147,.00166,.0011,0.0*
1,1,.006,.00166,.0011*
20,1,.006,.00166,.0011,.00258,.00037,0.0*
1,1,.006,.00258,.00037*
20,1,.006,.00258,.00037,.00332,-.00073,0.0*
1,1,.006,.00332,-.00073*
20,1,.006,.00332,-.00073,.0035,-.00202,0.0*
1,1,.006,.0035,-.00202*
20,1,.006,.0035,-.00202,.00332,-.00312,0.0*
1,1,.006,.00332,-.00312*
20,1,.006,.00332,-.00312,.00258,-.00422,0.0*
1,1,.006,.00258,-.00422*
20,1,.006,.00258,-.00422,.00148,-.00514,0.0*
1,1,.006,.00148,-.00514*
20,1,.006,.00148,-.00514,.00019,-.00551,0.0*
1,1,.006,.00019,-.00551*
20,1,.006,.00019,-.00551,-.00128,-.00514,0.0*
1,1,.006,-.00128,-.00514*
20,1,.006,-.00128,-.00514,-.00256,-.00404,0.0*
1,1,.006,-.00256,-.00404*
20,1,.006,-.00256,-.00404,-.0033,-.00239,0.0*
1,1,.006,-.0033,-.00239*
20,1,.006,-.0033,-.00239,-.00348,-.00055,0.0*
1,1,.006,-.00348,-.00055*
20,1,.006,-.00348,-.00055,-.00311,.00184,0.0*
1,1,.006,-.00311,.00184*
20,1,.006,-.00311,.00184,-.00256,.00312,0.0*
1,1,.006,-.00256,.00312*
20,1,.006,-.00256,.00312,-.00164,.00441,0.0*
1,1,.006,-.00164,.00441*
20,1,.006,-.00164,.00441,-.00036,.00533,0.0*
1,1,.006,-.00036,.00533*
20,1,.006,-.00036,.00533,.00093,.00551,0.0*
1,1,.006,.00093,.00551*
20,1,.006,.00093,.00551,.00221,.00514,0.0*
1,1,.006,.00221,.00514*
20,1,.006,.00221,.00514,.00313,.00422,0.0*
1,1,.006,.00313,.00422*
1,1,.006,.007,-.00331*
20,1,.006,.007,-.00331,.0081,-.00459,0.0*
1,1,.006,.0081,-.00459*
20,1,.006,.0081,-.00459,.00957,-.00533,0.0*
1,1,.006,.00957,-.00533*
20,1,.006,.00957,-.00533,.01122,-.00551,0.0*
1,1,.006,.01122,-.00551*
20,1,.006,.01122,-.00551,.01269,-.00533,0.0*
1,1,.006,.01269,-.00533*
20,1,.006,.01269,-.00533,.01416,-.00441,0.0*
1,1,.006,.01416,-.00441*
20,1,.006,.01416,-.00441,.01508,-.00331,0.0*
1,1,.006,.01508,-.00331*
20,1,.006,.01508,-.00331,.01526,-.0022,0.0*
1,1,.006,.01526,-.0022*
20,1,.006,.01526,-.0022,.0149,-.00092,0.0*
1,1,.006,.0149,-.00092*
20,1,.006,.0149,-.00092,.01361,0.0,0.0*
1,1,.006,.01361,0.0*
20,1,.006,.01361,0.0,.01233,.00037,0.0*
1,1,.006,.01233,.00037*
20,1,.006,.01233,.00037,.01067,.00037,0.0*
1,1,.006,.01067,.00037*
1,1,.006,.01233,.00037*
20,1,.006,.01233,.00037,.01343,.00092,0.0*
1,1,.006,.01343,.00092*
20,1,.006,.01343,.00092,.01435,.00184,0.0*
1,1,.006,.01435,.00184*
20,1,.006,.01435,.00184,.01471,.00294,0.0*
1,1,.006,.01471,.00294*
20,1,.006,.01471,.00294,.01435,.00404,0.0*
1,1,.006,.01435,.00404*
20,1,.006,.01435,.00404,.01343,.00496,0.0*
1,1,.006,.01343,.00496*
20,1,.006,.01343,.00496,.01177,.00551,0.0*
1,1,.006,.01177,.00551*
20,1,.006,.01177,.00551,.01012,.00533,0.0*
1,1,.006,.01012,.00533*
20,1,.006,.01012,.00533,.00847,.00459,0.0*
1,1,.006,.00847,.00459*
%
%ADD23MACRO23*%
%AMMACRO28*
1,1,.006,0.0,.035*
20,1,.006,0.0,.035,.030311,-.0175,0.0*
1,1,.006,.030311,-.0175*
20,1,.006,.030311,-.0175,-.030311,-.0175,0.0*
1,1,.006,-.030311,-.0175*
20,1,.006,-.030311,-.0175,0.0,.035,0.0*
1,1,.006,0.0,.035*
1,1,.006,-.01102,.00551*
20,1,.006,-.01102,.00551,-.01249,.00514,0.0*
1,1,.006,-.01249,.00514*
20,1,.006,-.01249,.00514,-.01359,.00422,0.0*
1,1,.006,-.01359,.00422*
20,1,.006,-.01359,.00422,-.01433,.00312,0.0*
1,1,.006,-.01433,.00312*
20,1,.006,-.01433,.00312,-.01488,.00165,0.0*
1,1,.006,-.01488,.00165*
20,1,.006,-.01488,.00165,-.01506,0.0,0.0*
1,1,.006,-.01506,0.0*
20,1,.006,-.01506,0.0,-.01488,-.00165,0.0*
1,1,.006,-.01488,-.00165*
20,1,.006,-.01488,-.00165,-.01433,-.00312,0.0*
1,1,.006,-.01433,-.00312*
20,1,.006,-.01433,-.00312,-.01359,-.00422,0.0*
1,1,.006,-.01359,-.00422*
20,1,.006,-.01359,-.00422,-.01249,-.00514,0.0*
1,1,.006,-.01249,-.00514*
20,1,.006,-.01249,-.00514,-.01102,-.00551,0.0*
1,1,.006,-.01102,-.00551*
20,1,.006,-.01102,-.00551,-.00955,-.00514,0.0*
1,1,.006,-.00955,-.00514*
20,1,.006,-.00955,-.00514,-.00845,-.00422,0.0*
1,1,.006,-.00845,-.00422*
20,1,.006,-.00845,-.00422,-.00771,-.00312,0.0*
1,1,.006,-.00771,-.00312*
20,1,.006,-.00771,-.00312,-.00716,-.00165,0.0*
1,1,.006,-.00716,-.00165*
20,1,.006,-.00716,-.00165,-.00698,0.0,0.0*
1,1,.006,-.00698,0.0*
20,1,.006,-.00698,0.0,-.00716,.00165,0.0*
1,1,.006,-.00716,.00165*
20,1,.006,-.00716,.00165,-.00771,.00312,0.0*
1,1,.006,-.00771,.00312*
20,1,.006,-.00771,.00312,-.00845,.00422,0.0*
1,1,.006,-.00845,.00422*
20,1,.006,-.00845,.00422,-.00955,.00514,0.0*
1,1,.006,-.00955,.00514*
20,1,.006,-.00955,.00514,-.01102,.00551,0.0*
1,1,.006,-.01102,.00551*
1,1,.006,.00221,-.00551*
20,1,.006,.00221,-.00551,.00221,.00551,0.0*
1,1,.006,.00221,.00551*
20,1,.006,.00221,.00551,-.00458,-.00239,0.0*
1,1,.006,-.00458,-.00239*
20,1,.006,-.00458,-.00239,.0046,-.00239,0.0*
1,1,.006,.0046,-.00239*
1,1,.006,.00755,-.00092*
20,1,.006,.00755,-.00092,.00884,.00037,0.0*
1,1,.006,.00884,.00037*
20,1,.006,.00884,.00037,.00994,.0011,0.0*
1,1,.006,.00994,.0011*
20,1,.006,.00994,.0011,.01141,.00147,0.0*
1,1,.006,.01141,.00147*
20,1,.006,.01141,.00147,.01269,.0011,0.0*
1,1,.006,.01269,.0011*
20,1,.006,.01269,.0011,.01361,.00037,0.0*
1,1,.006,.01361,.00037*
20,1,.006,.01361,.00037,.01435,-.00073,0.0*
1,1,.006,.01435,-.00073*
20,1,.006,.01435,-.00073,.01453,-.00202,0.0*
1,1,.006,.01453,-.00202*
20,1,.006,.01453,-.00202,.01435,-.00312,0.0*
1,1,.006,.01435,-.00312*
20,1,.006,.01435,-.00312,.01361,-.00422,0.0*
1,1,.006,.01361,-.00422*
20,1,.006,.01361,-.00422,.01251,-.00514,0.0*
1,1,.006,.01251,-.00514*
20,1,.006,.01251,-.00514,.01122,-.00551,0.0*
1,1,.006,.01122,-.00551*
20,1,.006,.01122,-.00551,.00975,-.00514,0.0*
1,1,.006,.00975,-.00514*
20,1,.006,.00975,-.00514,.00847,-.00404,0.0*
1,1,.006,.00847,-.00404*
20,1,.006,.00847,-.00404,.00773,-.00239,0.0*
1,1,.006,.00773,-.00239*
20,1,.006,.00773,-.00239,.00755,-.00055,0.0*
1,1,.006,.00755,-.00055*
20,1,.006,.00755,-.00055,.00792,.00184,0.0*
1,1,.006,.00792,.00184*
20,1,.006,.00792,.00184,.00847,.00312,0.0*
1,1,.006,.00847,.00312*
20,1,.006,.00847,.00312,.00939,.00441,0.0*
1,1,.006,.00939,.00441*
20,1,.006,.00939,.00441,.01067,.00533,0.0*
1,1,.006,.01067,.00533*
20,1,.006,.01067,.00533,.01196,.00551,0.0*
1,1,.006,.01196,.00551*
20,1,.006,.01196,.00551,.01324,.00514,0.0*
1,1,.006,.01324,.00514*
20,1,.006,.01324,.00514,.01416,.00422,0.0*
1,1,.006,.01416,.00422*
%
%ADD28MACRO28*%
%AMMACRO27*
1,1,.006,0.0,.035*
20,1,.006,0.0,.035,.030311,-.0175,0.0*
1,1,.006,.030311,-.0175*
20,1,.006,.030311,-.0175,-.030311,-.0175,0.0*
1,1,.006,-.030311,-.0175*
20,1,.006,-.030311,-.0175,0.0,.035,0.0*
1,1,.006,0.0,.035*
1,1,.006,-.01102,.00551*
20,1,.006,-.01102,.00551,-.01249,.00514,0.0*
1,1,.006,-.01249,.00514*
20,1,.006,-.01249,.00514,-.01359,.00422,0.0*
1,1,.006,-.01359,.00422*
20,1,.006,-.01359,.00422,-.01433,.00312,0.0*
1,1,.006,-.01433,.00312*
20,1,.006,-.01433,.00312,-.01488,.00165,0.0*
1,1,.006,-.01488,.00165*
20,1,.006,-.01488,.00165,-.01506,0.0,0.0*
1,1,.006,-.01506,0.0*
20,1,.006,-.01506,0.0,-.01488,-.00165,0.0*
1,1,.006,-.01488,-.00165*
20,1,.006,-.01488,-.00165,-.01433,-.00312,0.0*
1,1,.006,-.01433,-.00312*
20,1,.006,-.01433,-.00312,-.01359,-.00422,0.0*
1,1,.006,-.01359,-.00422*
20,1,.006,-.01359,-.00422,-.01249,-.00514,0.0*
1,1,.006,-.01249,-.00514*
20,1,.006,-.01249,-.00514,-.01102,-.00551,0.0*
1,1,.006,-.01102,-.00551*
20,1,.006,-.01102,-.00551,-.00955,-.00514,0.0*
1,1,.006,-.00955,-.00514*
20,1,.006,-.00955,-.00514,-.00845,-.00422,0.0*
1,1,.006,-.00845,-.00422*
20,1,.006,-.00845,-.00422,-.00771,-.00312,0.0*
1,1,.006,-.00771,-.00312*
20,1,.006,-.00771,-.00312,-.00716,-.00165,0.0*
1,1,.006,-.00716,-.00165*
20,1,.006,-.00716,-.00165,-.00698,0.0,0.0*
1,1,.006,-.00698,0.0*
20,1,.006,-.00698,0.0,-.00716,.00165,0.0*
1,1,.006,-.00716,.00165*
20,1,.006,-.00716,.00165,-.00771,.00312,0.0*
1,1,.006,-.00771,.00312*
20,1,.006,-.00771,.00312,-.00845,.00422,0.0*
1,1,.006,-.00845,.00422*
20,1,.006,-.00845,.00422,-.00955,.00514,0.0*
1,1,.006,-.00955,.00514*
20,1,.006,-.00955,.00514,-.01102,.00551,0.0*
1,1,.006,-.01102,.00551*
1,1,.006,-.00348,-.00092*
20,1,.006,-.00348,-.00092,-.00219,.00037,0.0*
1,1,.006,-.00219,.00037*
20,1,.006,-.00219,.00037,-.00109,.0011,0.0*
1,1,.006,-.00109,.0011*
20,1,.006,-.00109,.0011,.00038,.00147,0.0*
1,1,.006,.00038,.00147*
20,1,.006,.00038,.00147,.00166,.0011,0.0*
1,1,.006,.00166,.0011*
20,1,.006,.00166,.0011,.00258,.00037,0.0*
1,1,.006,.00258,.00037*
20,1,.006,.00258,.00037,.00332,-.00073,0.0*
1,1,.006,.00332,-.00073*
20,1,.006,.00332,-.00073,.0035,-.00202,0.0*
1,1,.006,.0035,-.00202*
20,1,.006,.0035,-.00202,.00332,-.00312,0.0*
1,1,.006,.00332,-.00312*
20,1,.006,.00332,-.00312,.00258,-.00422,0.0*
1,1,.006,.00258,-.00422*
20,1,.006,.00258,-.00422,.00148,-.00514,0.0*
1,1,.006,.00148,-.00514*
20,1,.006,.00148,-.00514,.00019,-.00551,0.0*
1,1,.006,.00019,-.00551*
20,1,.006,.00019,-.00551,-.00128,-.00514,0.0*
1,1,.006,-.00128,-.00514*
20,1,.006,-.00128,-.00514,-.00256,-.00404,0.0*
1,1,.006,-.00256,-.00404*
20,1,.006,-.00256,-.00404,-.0033,-.00239,0.0*
1,1,.006,-.0033,-.00239*
20,1,.006,-.0033,-.00239,-.00348,-.00055,0.0*
1,1,.006,-.00348,-.00055*
20,1,.006,-.00348,-.00055,-.00311,.00184,0.0*
1,1,.006,-.00311,.00184*
20,1,.006,-.00311,.00184,-.00256,.00312,0.0*
1,1,.006,-.00256,.00312*
20,1,.006,-.00256,.00312,-.00164,.00441,0.0*
1,1,.006,-.00164,.00441*
20,1,.006,-.00164,.00441,-.00036,.00533,0.0*
1,1,.006,-.00036,.00533*
20,1,.006,-.00036,.00533,.00093,.00551,0.0*
1,1,.006,.00093,.00551*
20,1,.006,.00093,.00551,.00221,.00514,0.0*
1,1,.006,.00221,.00514*
20,1,.006,.00221,.00514,.00313,.00422,0.0*
1,1,.006,.00313,.00422*
1,1,.006,.01067,-.00551*
20,1,.006,.01067,-.00551,.01104,-.00312,0.0*
1,1,.006,.01104,-.00312*
20,1,.006,.01104,-.00312,.01159,-.0011,0.0*
1,1,.006,.01159,-.0011*
20,1,.006,.01159,-.0011,.01233,.00073,0.0*
1,1,.006,.01233,.00073*
20,1,.006,.01233,.00073,.01324,.00275,0.0*
1,1,.006,.01324,.00275*
20,1,.006,.01324,.00275,.01471,.00551,0.0*
1,1,.006,.01471,.00551*
20,1,.006,.01471,.00551,.00737,.00551,0.0*
1,1,.006,.00737,.00551*
%
%ADD27MACRO27*%
%ADD31C,.006*%
G75*
%LPD*%
G75*
G54D10*
X3005Y19808D03*
Y34808D03*
Y59808D03*
X7595Y128373D03*
X3005Y145238D03*
Y165238D03*
Y185238D03*
Y205238D03*
Y225238D03*
Y245238D03*
Y265238D03*
Y285238D03*
Y305238D03*
Y325238D03*
Y345238D03*
Y365238D03*
Y385238D03*
Y405238D03*
Y425238D03*
Y445238D03*
X3023Y524312D03*
Y549312D03*
X4540Y566003D03*
X34582Y3004D03*
X14811Y3732D03*
X12767Y72072D03*
X27271Y127298D03*
X19558Y454589D03*
X9913Y510026D03*
X20498Y575739D03*
X54582Y3004D03*
X63436Y353962D03*
X39549Y454916D03*
X40498Y575739D03*
X60498D03*
X94582Y3004D03*
X74582D03*
X80498Y575739D03*
X114582Y3004D03*
X108600Y258560D03*
X111600D03*
X108600Y261560D03*
X111600D03*
X108600Y255560D03*
X111600D03*
X123000Y414500D03*
X119500D03*
Y411500D03*
X123000D03*
X119500Y408500D03*
X123000D03*
X119500Y417500D03*
X123000D03*
X119500Y420500D03*
X123000D03*
X115700Y420600D03*
Y417600D03*
Y408600D03*
Y411600D03*
Y414600D03*
X123000Y426600D03*
X119500D03*
X123000Y423600D03*
X119500D03*
X115700Y423700D03*
Y426700D03*
X100498Y575739D03*
X120498D03*
X154582Y3004D03*
X134582D03*
X153480Y213350D03*
X150634Y219063D03*
X155140Y240230D03*
X155034Y228063D03*
Y224563D03*
X152334Y223063D03*
Y226563D03*
Y230063D03*
X155034Y231563D03*
X140400Y258360D03*
X143400D03*
X140400Y261360D03*
X143400D03*
X140400Y255360D03*
X143400D03*
X140498Y575739D03*
X174582Y3004D03*
X172934Y219110D03*
X184349Y212651D03*
X165350Y220098D03*
X162850D03*
X182260Y197050D03*
X179460D03*
X176560D03*
X174660Y205850D03*
Y202650D03*
X167660Y213050D03*
X164760D03*
X167660Y209850D03*
X164760D03*
X183900Y216830D03*
X172712Y222263D03*
X183815Y220903D03*
X162850Y227185D03*
Y230728D03*
X165350Y223642D03*
Y227185D03*
Y230728D03*
X162850Y223642D03*
X165840Y247805D03*
X169840D03*
X175481Y225183D03*
X161400Y323200D03*
X173265Y340552D03*
X157000Y414500D03*
X160500D03*
Y417500D03*
X157000D03*
X160500Y420500D03*
X157000D03*
X160500Y411500D03*
X157000D03*
X160500Y408500D03*
X157000D03*
X164000Y414600D03*
Y417600D03*
Y420600D03*
Y411600D03*
Y408600D03*
X160300Y423600D03*
X156800D03*
X160300Y426600D03*
X156800D03*
X163800Y426700D03*
Y423700D03*
X180539Y498000D03*
X168939D03*
X180539Y518000D03*
X168939D03*
X214582Y3004D03*
X194582D03*
X194160Y205200D03*
Y208200D03*
X200160Y205200D03*
Y208200D03*
X197160Y205200D03*
Y208200D03*
X185260Y205350D03*
Y208350D03*
X189760Y242100D03*
Y245100D03*
X192760Y242100D03*
Y245100D03*
X195760Y242100D03*
Y245100D03*
X198760Y242100D03*
Y245100D03*
X201760Y242100D03*
Y245100D03*
X208071Y305975D03*
X203575Y297500D03*
X212925Y315500D03*
X234582Y3004D03*
X242500Y243000D03*
Y247500D03*
X218500Y305000D03*
X226975D03*
X235975D03*
X239567Y305975D03*
X218500Y309500D03*
X226975D03*
X235975D03*
X230425Y313605D03*
X221425Y313000D03*
X223819Y445025D03*
X228539Y498000D03*
X216939D03*
X228539Y518000D03*
X216939D03*
X254582Y3004D03*
X246000Y235500D03*
X247441Y305975D03*
X264939Y498000D03*
Y518000D03*
X294582Y3004D03*
X274582D03*
X297000Y206000D03*
Y203500D03*
Y198500D03*
Y196000D03*
X283000Y203500D03*
Y198500D03*
Y196000D03*
Y206000D03*
X285219Y279078D03*
X281219D03*
X277219D03*
X285219Y275078D03*
X281219D03*
X277219D03*
X285219Y271078D03*
X281219D03*
X277219D03*
Y283078D03*
X281219D03*
X285219D03*
X290720Y340338D03*
X276539Y498000D03*
Y518000D03*
X314582Y3004D03*
X318500Y206000D03*
Y203500D03*
Y198500D03*
Y196000D03*
X326000Y203500D03*
Y198500D03*
Y196000D03*
Y206000D03*
X304500Y203500D03*
Y198500D03*
Y196000D03*
Y206000D03*
X313571Y340552D03*
X326419Y498000D03*
Y518000D03*
X354582Y3004D03*
X334582D03*
X340000Y206000D03*
Y203500D03*
Y198500D03*
Y196000D03*
X361500Y206000D03*
Y203500D03*
Y198500D03*
Y196000D03*
X347500Y203500D03*
Y198500D03*
Y196000D03*
Y206000D03*
X361000Y305975D03*
X338019Y498000D03*
Y518000D03*
X374582Y3004D03*
X383000Y206000D03*
Y203500D03*
Y198500D03*
Y196000D03*
X390500Y203500D03*
Y198500D03*
Y196000D03*
Y206000D03*
X369000Y203500D03*
Y198500D03*
Y196000D03*
Y206000D03*
X375475Y305000D03*
X383975D03*
X365551Y305975D03*
X375500Y309500D03*
X383975D03*
X382963Y316400D03*
Y313750D03*
X381299Y445025D03*
X386019Y498000D03*
X374419D03*
X386019Y518000D03*
X374419D03*
X414582Y3004D03*
X394582D03*
X404500Y206000D03*
Y203500D03*
Y198500D03*
Y196000D03*
X412000Y203500D03*
Y198500D03*
Y196000D03*
Y206000D03*
X402000Y235000D03*
X398500Y242500D03*
X393000Y305000D03*
X397047Y305975D03*
X404921D03*
X392975Y309500D03*
X434582Y3004D03*
X426000Y206000D03*
Y203500D03*
Y198500D03*
Y196000D03*
X442499Y279186D03*
X438499D03*
X434499D03*
X442499Y275186D03*
X438499D03*
X434499D03*
X442499Y271186D03*
X438499D03*
X434499D03*
Y283186D03*
X438499D03*
X442499D03*
X447255Y340339D03*
X430019Y444260D03*
X432019Y452025D03*
X434019Y498000D03*
X422419D03*
X434019Y518000D03*
X422419D03*
X474582Y3004D03*
X454582D03*
X473095Y340339D03*
X494582Y3004D03*
X495500Y498000D03*
X483900D03*
X495500Y518000D03*
X483900D03*
X534582Y3004D03*
X514582D03*
X533475Y305500D03*
X523032Y305975D03*
X518575Y295500D03*
X533475Y310500D03*
X539619Y316400D03*
Y313400D03*
X538780Y445025D03*
X531900Y498000D03*
Y518000D03*
X554582Y3004D03*
X555500Y239000D03*
Y236000D03*
X552000Y243500D03*
Y247000D03*
X542475Y305500D03*
X551475D03*
X554528Y305975D03*
X562402D03*
X542475Y310500D03*
X551475D03*
X545063Y340339D03*
X549500Y445024D03*
X562000Y442000D03*
X564500D03*
X543500Y498000D03*
Y518000D03*
X594582Y3004D03*
X574582D03*
X590500Y203000D03*
Y198000D03*
Y195500D03*
Y205500D03*
X587500Y444260D03*
X589500Y446500D03*
X591500Y498000D03*
X579900D03*
X591500Y518000D03*
X579900D03*
X614582Y3004D03*
X604500Y205500D03*
Y203000D03*
Y198000D03*
Y195500D03*
X626000Y205500D03*
Y203000D03*
Y198000D03*
Y195500D03*
X612000Y203000D03*
Y198000D03*
Y195500D03*
Y205500D03*
X654582Y3004D03*
X634582D03*
X640900Y42300D03*
X647999Y33000D03*
X655300Y56800D03*
X638200Y44000D03*
Y46500D03*
X641100Y48100D03*
X647500Y205500D03*
Y203000D03*
Y198000D03*
Y195500D03*
X655000Y203000D03*
Y198000D03*
Y195500D03*
Y205500D03*
X633500Y203000D03*
Y198000D03*
Y195500D03*
Y205500D03*
X652981Y498000D03*
X641381D03*
X652981Y518000D03*
X641381D03*
X674582Y3004D03*
X684525Y36500D03*
X679000Y56800D03*
X686500D03*
X671100D03*
X663200D03*
X669000Y205500D03*
Y203000D03*
Y198000D03*
Y195500D03*
X676500D03*
Y198000D03*
Y203000D03*
Y205500D03*
X680513Y305975D03*
X676075Y299600D03*
X714582Y3004D03*
X694582D03*
X699500Y34500D03*
X696900Y53300D03*
X694200D03*
X691400D03*
X689900Y56600D03*
X696100Y56700D03*
X690500Y205500D03*
Y203000D03*
Y198000D03*
Y195500D03*
X711990D03*
Y198000D03*
Y203000D03*
Y205500D03*
X697990Y195500D03*
Y198000D03*
Y203000D03*
Y205500D03*
X709500Y247000D03*
X709481Y243500D03*
X712981Y236000D03*
Y239000D03*
X716100Y255987D03*
X700040Y258960D03*
X712009Y305975D03*
X708956Y305500D03*
X690956D03*
X700000D03*
X694406Y295500D03*
X690956Y310500D03*
X699956D03*
X708956D03*
X697100Y313400D03*
X704400Y358600D03*
X702200Y356000D03*
X697900Y352500D03*
X707750Y358750D03*
X696261Y445024D03*
X700981Y498000D03*
X689381D03*
X700981Y518000D03*
X689381D03*
X734582Y3004D03*
X747160Y30000D03*
Y38500D03*
Y64000D03*
Y47000D03*
Y55500D03*
X733490Y195500D03*
Y198000D03*
Y203000D03*
Y205500D03*
X719490Y195500D03*
Y198000D03*
Y203000D03*
Y205500D03*
X719883Y305975D03*
X724000Y294500D03*
X732100Y332400D03*
X742500Y328500D03*
Y324500D03*
Y334500D03*
X735075Y326000D03*
Y336000D03*
X731925D03*
X732000Y326000D03*
X742500Y361500D03*
X742000Y341500D03*
X742500Y347700D03*
Y353200D03*
X737381Y498000D03*
Y518000D03*
X774582Y3004D03*
X754582D03*
X758760Y38500D03*
X756160D03*
X758760Y30000D03*
X756160D03*
X758900Y27400D03*
X750300Y27200D03*
X752560Y30100D03*
X749760D03*
X752560Y38600D03*
X749760D03*
X758760Y55500D03*
X756160D03*
X758760Y47000D03*
X756160D03*
X758760Y64000D03*
X756160D03*
X752560Y64100D03*
X749760D03*
X752560Y47100D03*
X749760D03*
X752560Y55600D03*
X749760D03*
X754000Y353500D03*
X748075Y366500D03*
X748981Y498000D03*
Y518000D03*
X794582Y3004D03*
X797854Y259539D03*
X803900Y279425D03*
X803500Y259525D03*
X806500Y285500D03*
X786500Y336484D03*
X800575Y338000D03*
X779100Y326820D03*
X798400Y323900D03*
X786500Y316700D03*
X793800Y323880D03*
X781500Y362700D03*
X803000Y357000D03*
Y346500D03*
X802975Y362000D03*
X805323Y408150D03*
Y405150D03*
X799323D03*
Y408150D03*
X802323Y405150D03*
Y408150D03*
X796600Y408097D03*
Y405097D03*
X802323Y416916D03*
X799323D03*
X805323D03*
X802323Y413916D03*
X799323D03*
X805323D03*
Y411150D03*
X799323D03*
X802323D03*
X796600Y411097D03*
Y413863D03*
Y416863D03*
X799655Y474684D03*
Y480503D03*
Y477684D03*
X802655Y474684D03*
Y480503D03*
Y477684D03*
X805655Y474684D03*
Y480503D03*
Y477684D03*
X802655Y483503D03*
X805709Y486332D03*
X805655Y483503D03*
X796655Y474684D03*
Y480503D03*
Y477684D03*
X796709Y486332D03*
X796655Y483503D03*
X799709Y486332D03*
X799655Y483503D03*
X802709Y486332D03*
X834582Y3004D03*
X814582D03*
X809500Y259430D03*
X808500Y272925D03*
X831000Y260500D03*
X836000D03*
X826000Y260525D03*
X831000Y270500D03*
X808500Y276075D03*
X836000Y270500D03*
X826000Y270525D03*
X821000D03*
X814500Y293000D03*
X819500Y329000D03*
X827500D03*
X811500D03*
X815500D03*
X823500D03*
X808425Y334000D03*
X825941Y339560D03*
X813975Y362000D03*
Y357000D03*
X835610Y355590D03*
X829500Y354925D03*
X827000Y360475D03*
X811575Y344000D03*
X808425D03*
X811323Y405150D03*
Y408150D03*
X808323D03*
Y405150D03*
Y416916D03*
X811323D03*
X808323Y413916D03*
X811323D03*
Y411150D03*
X808323D03*
X817153Y408096D03*
Y405096D03*
X814323Y405150D03*
Y408150D03*
Y416916D03*
X817153Y416862D03*
X814323Y413916D03*
X817153Y413862D03*
Y411096D03*
X814323Y411150D03*
X817709Y486332D03*
X817655Y483503D03*
X808655Y474684D03*
Y480503D03*
Y477684D03*
X811655Y474684D03*
Y480503D03*
Y477684D03*
X814655D03*
Y480503D03*
Y474684D03*
X808709Y486332D03*
X808655Y483503D03*
X811709Y486332D03*
X811655Y483503D03*
X814655D03*
X814709Y486332D03*
X817655Y474684D03*
Y480503D03*
Y477684D03*
X854582Y3004D03*
X849490Y196000D03*
Y198500D03*
Y203500D03*
Y206000D03*
X863600Y208900D03*
X841000Y260525D03*
X846000D03*
X851000D03*
X856000D03*
X841000Y270500D03*
X846000Y270525D03*
X851000D03*
X856000D03*
X850750Y250750D03*
X848075Y306500D03*
X861600Y304600D03*
X837575Y321000D03*
X865000Y313200D03*
X844760Y336077D03*
X839692Y329592D03*
X854825Y330925D03*
X850500Y360075D03*
Y366000D03*
X847500D03*
X856500D03*
X859500D03*
X865500D03*
X850500Y356925D03*
X864500Y358500D03*
X850390Y385878D03*
X847390D03*
X859253D03*
X856253D03*
X865542Y385771D03*
X859342Y413916D03*
X856342D03*
X865342D03*
X862342D03*
Y411150D03*
X865342D03*
X856342D03*
X859342D03*
X853619Y411097D03*
Y413863D03*
Y416863D03*
X862342Y408150D03*
Y405150D03*
X865342Y408150D03*
Y405150D03*
X856342D03*
Y408150D03*
X859342Y405150D03*
Y408150D03*
X853619Y408097D03*
Y405097D03*
X859342Y416916D03*
X856342D03*
X865342D03*
X862342D03*
X856257Y474684D03*
Y480503D03*
Y477684D03*
X859257Y474684D03*
Y480503D03*
Y477684D03*
X862257Y474684D03*
Y480503D03*
Y477684D03*
X859257Y483503D03*
X862311Y486332D03*
X862257Y483503D03*
X853257Y474684D03*
Y480503D03*
Y477684D03*
X853311Y486332D03*
X853257Y483503D03*
X856311Y486332D03*
X856257Y483503D03*
X859311Y486332D03*
X865311D03*
X865257Y483503D03*
Y474684D03*
Y480503D03*
Y477684D03*
X854082Y505410D03*
X848263D03*
X851082D03*
X854082Y508410D03*
X848263D03*
X851082D03*
X854082Y511410D03*
X848263D03*
X851082D03*
X854082Y514410D03*
X848263D03*
X851082D03*
X845263Y508410D03*
X842434Y511464D03*
X845263Y511410D03*
X842434Y514464D03*
X845263Y514410D03*
X854082Y502410D03*
X848263D03*
X851082D03*
X842434Y502464D03*
X845263Y502410D03*
X842434Y505464D03*
X845263Y505410D03*
X842434Y508464D03*
Y523464D03*
X845263Y523410D03*
X854082Y517410D03*
X848263D03*
X851082D03*
Y520410D03*
X848263D03*
X854082D03*
X842434Y517464D03*
X845263Y517410D03*
Y520410D03*
X842434Y520464D03*
X854082Y523410D03*
X848263D03*
X851082D03*
X894582Y3004D03*
X874582D03*
X868000Y271500D03*
X894500Y283475D03*
X884000D03*
X877500D03*
X893363Y298740D03*
X883000Y293925D03*
X867000Y291260D03*
X875000Y304525D03*
X888000Y283475D03*
X877500Y366000D03*
X874500D03*
X884000D03*
X887000D03*
X893500D03*
X868500D03*
X878000Y358475D03*
X883000Y358500D03*
X874000Y358475D03*
X885500Y352925D03*
X893091Y385771D03*
X874405D03*
X877405D03*
X868542D03*
X884228D03*
X887228D03*
X868342Y416916D03*
X871342D03*
X868342Y413916D03*
X871342D03*
Y411150D03*
X868342D03*
X874172Y408096D03*
Y405096D03*
Y416862D03*
Y413862D03*
Y411096D03*
X871342Y405150D03*
Y408150D03*
X868342Y405150D03*
Y408150D03*
X868311Y486332D03*
X868257Y483503D03*
Y477684D03*
Y480503D03*
Y474684D03*
X871311Y486332D03*
X874311D03*
X874257Y477684D03*
Y480503D03*
Y474684D03*
X871257Y483503D03*
Y474684D03*
Y480503D03*
Y477684D03*
X874257Y483503D03*
X914582Y3004D03*
X915500Y283475D03*
X914500Y292000D03*
X905000Y283475D03*
X905941Y306500D03*
X909000Y283475D03*
X904500Y292000D03*
X912500Y327975D03*
X916260Y337077D03*
X908000Y327975D03*
X915000Y322425D03*
X912000Y332425D03*
X903500Y327975D03*
X896500Y366000D03*
X906000D03*
X903000D03*
X912500D03*
X915500D03*
X922000D03*
X901063Y352340D03*
X920000Y355525D03*
X896091Y385771D03*
X912525Y385877D03*
X906662D03*
X903662D03*
X922454Y385771D03*
X915525Y385877D03*
X911776Y507184D03*
Y510184D03*
Y501184D03*
Y504184D03*
X923595Y498461D03*
X920595D03*
X920542Y504184D03*
X923542D03*
X920542Y501184D03*
X923542D03*
Y510184D03*
X920542D03*
X923542Y507184D03*
X920542D03*
Y513184D03*
X923542D03*
X911829Y498461D03*
X914829D03*
X917595D03*
X917542Y504184D03*
Y501184D03*
Y510184D03*
Y507184D03*
Y513184D03*
X914776D03*
Y507184D03*
Y510184D03*
Y501184D03*
Y504184D03*
X911776Y513184D03*
X920542Y516184D03*
X923542D03*
X917542D03*
X914776D03*
X911776D03*
X917596Y519014D03*
X914830D03*
X911830D03*
X923596D03*
X920596D03*
X934582Y3004D03*
X940575Y304000D03*
X933000Y293476D03*
X940000D03*
X947000D03*
X926000Y283475D03*
X937516Y300075D03*
X947000Y302475D03*
X933196Y309910D03*
X930500Y315460D03*
X943172Y310885D03*
X943171Y315385D03*
X925000Y366000D03*
X944000D03*
X941000D03*
X934500D03*
X950500D03*
X953500D03*
X931500D03*
X927000Y361075D03*
X941035Y344474D03*
X927000Y357925D03*
X943885Y352385D03*
X925454Y385771D03*
X944247Y385877D03*
X941247D03*
X931317Y385771D03*
X934317D03*
X950110Y385877D03*
X953110D03*
X940498Y575739D03*
X974582Y3004D03*
X954582D03*
X960498Y575739D03*
X980498D03*
X994582Y3004D03*
X1000498Y575739D03*
X1034582Y3004D03*
X1014582D03*
X1022575Y100925D03*
Y115500D03*
X1034500Y142000D03*
X1037000Y146300D03*
X1037500Y142000D03*
X1036500Y153500D03*
X1019030Y160330D03*
X1022168Y155877D03*
X1017837Y154280D03*
X1024340Y146600D03*
X1016614Y187267D03*
X1036500Y172000D03*
Y163000D03*
X1039538Y179208D03*
X1039016Y185925D03*
X1016614Y197767D03*
X1020498Y575739D03*
X1040498D03*
X1054582Y3004D03*
X1070400Y123200D03*
X1067600D03*
X1068900Y110000D03*
X1057525Y130500D03*
X1065000Y156425D03*
X1047159Y141487D03*
X1048000Y153500D03*
X1057525Y134000D03*
Y138600D03*
X1070715Y146500D03*
X1063500Y159814D03*
X1070715Y178585D03*
X1048000Y172000D03*
Y163000D03*
X1060500Y164500D03*
X1067000Y191500D03*
X1070000D03*
X1058000D03*
X1053830Y191670D03*
X1060000Y249000D03*
X1063000D03*
X1066000D03*
Y246000D03*
X1063000D03*
X1060000D03*
X1066000Y243000D03*
X1063000D03*
X1060000D03*
X1069000Y246000D03*
Y243000D03*
X1072000Y246000D03*
Y243000D03*
X1060000Y252000D03*
X1063000D03*
X1066000D03*
Y258000D03*
X1063000D03*
X1060000D03*
X1066000Y255000D03*
X1063000D03*
X1060000D03*
X1069000Y258000D03*
Y255000D03*
X1072000Y258000D03*
Y255000D03*
X1060000Y296500D03*
X1063000D03*
X1066000D03*
Y293500D03*
X1063000D03*
X1060000D03*
X1069000D03*
X1060000Y299500D03*
X1063000D03*
X1066000D03*
Y305500D03*
X1063000D03*
X1060000D03*
X1066000Y302500D03*
X1063000D03*
X1060000D03*
X1069000Y305500D03*
Y302500D03*
X1066000Y290500D03*
X1063000D03*
X1060000D03*
X1069000D03*
X1072000Y293500D03*
Y305500D03*
Y302500D03*
Y290500D03*
X1066000Y338000D03*
X1063000D03*
X1060000D03*
X1069000D03*
X1072000D03*
X1060000Y344000D03*
X1063000D03*
X1066000D03*
X1060000Y347000D03*
X1063000D03*
X1066000D03*
Y341000D03*
X1063000D03*
X1060000D03*
X1066000Y353000D03*
X1063000D03*
X1060000D03*
X1066000Y350000D03*
X1063000D03*
X1060000D03*
X1069000Y353000D03*
Y350000D03*
Y341000D03*
X1072000Y353000D03*
Y350000D03*
Y341000D03*
X1061600Y359642D03*
X1066000Y397500D03*
X1063000D03*
X1060000D03*
X1069000D03*
X1060000Y391500D03*
X1063000D03*
X1066000D03*
X1060000Y394500D03*
X1063000D03*
X1066000D03*
Y388500D03*
X1063000D03*
X1060000D03*
X1066000Y385500D03*
X1063000D03*
X1060000D03*
X1069000Y388500D03*
Y385500D03*
X1072000Y397500D03*
Y388500D03*
Y385500D03*
X1066000Y400500D03*
X1063000D03*
X1060000D03*
X1069000D03*
X1072000D03*
X1060984Y418742D03*
X1066000Y433000D03*
X1063000D03*
X1060000D03*
X1069000D03*
X1060000Y439000D03*
X1063000D03*
X1066000D03*
X1060000Y442000D03*
X1063000D03*
X1066000D03*
Y436000D03*
X1063000D03*
X1060000D03*
X1069000D03*
X1072000Y433000D03*
Y436000D03*
X1066000Y448000D03*
X1063000D03*
X1060000D03*
X1066000Y445000D03*
X1063000D03*
X1060000D03*
X1069000Y448000D03*
Y445000D03*
X1072000Y448000D03*
Y445000D03*
X1069000Y480500D03*
Y483500D03*
X1060000Y480500D03*
X1063000D03*
X1066000D03*
X1060000Y483500D03*
X1063000D03*
X1066000D03*
Y486500D03*
X1063000D03*
X1060000D03*
X1072000Y480500D03*
Y483500D03*
X1069000Y492500D03*
Y495500D03*
X1060000Y492500D03*
X1063000D03*
X1066000D03*
X1060000Y495500D03*
X1063000D03*
X1066000D03*
Y489500D03*
X1063000D03*
X1060000D03*
X1072000Y492500D03*
Y495500D03*
X1066500Y541000D03*
X1069500D03*
X1066500Y544000D03*
X1069500D03*
Y538000D03*
X1060498Y575739D03*
X1069500Y547000D03*
Y550000D03*
X1066500Y547000D03*
Y550000D03*
X1069500Y553000D03*
X1094582Y3004D03*
X1074582D03*
X1097100Y35582D03*
Y38582D03*
X1099600D03*
Y35582D03*
X1102100D03*
Y38582D03*
X1096961Y18126D03*
Y21126D03*
X1099461D03*
Y18126D03*
X1101961D03*
Y21126D03*
X1097101Y53737D03*
Y56737D03*
X1099601D03*
Y53737D03*
X1102101D03*
Y56737D03*
X1091000Y99500D03*
X1095100D03*
X1087000Y100000D03*
X1073200Y90900D03*
X1077200D03*
X1073200Y126000D03*
Y128800D03*
Y123200D03*
X1084740Y108000D03*
X1084325Y130197D03*
X1100075Y139925D03*
X1084260Y152600D03*
X1094493Y151856D03*
X1073154Y137800D03*
X1092000Y159500D03*
X1084401Y159260D03*
X1094024Y179500D03*
X1085000Y184575D03*
X1079500D03*
X1085525Y167500D03*
Y171000D03*
Y174500D03*
Y164000D03*
X1087500Y198000D03*
Y201000D03*
X1097500Y203700D03*
X1100000D03*
X1073500Y191500D03*
X1101903Y285019D03*
X1101796Y331894D03*
X1086500Y356000D03*
X1090500Y376500D03*
X1080418Y373600D03*
X1090443Y417343D03*
X1086500Y403500D03*
X1074316Y406925D03*
X1080498Y575739D03*
X1100498D03*
X1114582Y3004D03*
X1125170Y35582D03*
Y38582D03*
X1127670D03*
Y35582D03*
X1130170D03*
Y38582D03*
X1104600Y35582D03*
Y38582D03*
X1107100Y35582D03*
Y38582D03*
X1104461Y18126D03*
Y21126D03*
X1106961Y18126D03*
Y21126D03*
X1130031D03*
Y18126D03*
X1127531D03*
Y21126D03*
X1125031D03*
Y18126D03*
X1104601Y53737D03*
Y56737D03*
X1107101Y53737D03*
Y56737D03*
X1113000Y101240D03*
X1119500Y86000D03*
Y83000D03*
X1123000Y120816D03*
X1126000D03*
X1131500D03*
X1115800Y126600D03*
X1113500Y147500D03*
X1126075Y135973D03*
X1108500Y136500D03*
X1104500Y136524D03*
X1129000Y157000D03*
X1120200D03*
X1115425Y138925D03*
X1119000Y189500D03*
X1111100Y163749D03*
X1120200Y176500D03*
Y166500D03*
X1129000D03*
Y176500D03*
X1108821Y166800D03*
X1125918Y195418D03*
X1129068Y195500D03*
X1106189Y224241D03*
X1118774Y284699D03*
X1112902D03*
X1110019Y284806D03*
X1104786Y284912D03*
X1121657Y284592D03*
X1118667Y331574D03*
X1112795D03*
X1109912Y331681D03*
X1104679Y331787D03*
X1121550Y331467D03*
X1104009Y427245D03*
X1120880Y426925D03*
X1115008D03*
X1112125Y427032D03*
X1106892Y427138D03*
X1123763Y426818D03*
X1103800Y474339D03*
X1106683Y474232D03*
X1111916Y474126D03*
X1114799Y474019D03*
X1120671D03*
X1123554Y473912D03*
X1111452Y544000D03*
Y541000D03*
X1114452Y544000D03*
Y541000D03*
X1111452Y538000D03*
X1120669Y544000D03*
Y541000D03*
X1123669Y544000D03*
Y541000D03*
X1120669Y538000D03*
X1120498Y575739D03*
X1111452Y553000D03*
X1114452Y550000D03*
X1111452D03*
X1114452Y547000D03*
X1111452D03*
X1120669Y553000D03*
X1123669Y550000D03*
X1120669D03*
X1123669Y547000D03*
X1120669D03*
X1154582Y3004D03*
X1134582D03*
X1132670Y35582D03*
X1135170D03*
Y38582D03*
X1132670D03*
X1135031Y21126D03*
Y18126D03*
X1132531Y21126D03*
Y18126D03*
X1132950Y82867D03*
Y85867D03*
X1135450D03*
Y82867D03*
X1137950D03*
X1140450D03*
X1142950D03*
Y85867D03*
X1140450D03*
X1137950D03*
X1155000Y124913D03*
X1159300Y129700D03*
X1141500Y124425D03*
Y120500D03*
X1134500Y120816D03*
X1154000Y151500D03*
X1141500Y134575D03*
X1136300Y161100D03*
X1140000D03*
X1160200Y175982D03*
X1152781Y165719D03*
X1136300Y172300D03*
X1140000D03*
X1140336Y183560D03*
X1158000Y179000D03*
X1138203Y266860D03*
Y260860D03*
Y263860D03*
X1135203Y260860D03*
Y263860D03*
X1138203Y257860D03*
Y254860D03*
X1135203Y257860D03*
Y254860D03*
X1159710Y306037D03*
X1156710D03*
X1159710Y303037D03*
X1156710D03*
X1159710Y300037D03*
X1156710D03*
X1159710Y297037D03*
X1156710D03*
Y294037D03*
X1159710D03*
Y309037D03*
X1156710D03*
X1135403Y302360D03*
Y305360D03*
X1138403Y302360D03*
Y305360D03*
X1135403Y308360D03*
X1138403D03*
X1159710Y312037D03*
X1156710D03*
X1159710Y321037D03*
X1156710D03*
X1159710Y318037D03*
X1156710D03*
X1159710Y315037D03*
X1156710D03*
X1135403Y311360D03*
X1138403D03*
Y314360D03*
Y361979D03*
Y358979D03*
X1135403D03*
X1138403Y355979D03*
X1135403D03*
X1138403Y352979D03*
X1135403D03*
X1138403Y349979D03*
X1135403D03*
X1135190Y396965D03*
X1138190D03*
X1135190Y399965D03*
X1138190D03*
X1135190Y402965D03*
Y405965D03*
X1138190Y402965D03*
Y405965D03*
Y408965D03*
X1159799Y448537D03*
X1156799D03*
X1159799Y445537D03*
X1156799D03*
X1159799Y442537D03*
X1156799D03*
X1159799Y439537D03*
X1156799D03*
Y436537D03*
X1159799D03*
Y454537D03*
X1156799D03*
X1159799Y451537D03*
X1156799D03*
X1135404Y454228D03*
Y451228D03*
Y445228D03*
Y448228D03*
X1138404Y454228D03*
Y451228D03*
Y445228D03*
Y448228D03*
Y457228D03*
X1159799Y457537D03*
X1156799D03*
X1159799Y463537D03*
X1156799D03*
X1159799Y460537D03*
X1156799D03*
X1135622Y485732D03*
Y470732D03*
Y479732D03*
Y476732D03*
Y473732D03*
Y482732D03*
X1138622D03*
Y473732D03*
Y476732D03*
Y479732D03*
Y470732D03*
Y485732D03*
Y467732D03*
X1140498Y575739D03*
X1160498D03*
X1174582Y3004D03*
X1183321Y123652D03*
X1185821D03*
X1188321D03*
Y120652D03*
X1185821D03*
X1183321D03*
X1180821D03*
Y123652D03*
X1178321D03*
Y120652D03*
X1177475Y111500D03*
X1179500Y105500D03*
X1162700Y175959D03*
X1183021Y165952D03*
X1185521D03*
X1188618Y162782D03*
X1185521Y162952D03*
X1183021D03*
X1180521D03*
Y165952D03*
X1177521Y162952D03*
X1167600Y184500D03*
Y180500D03*
X1174500Y214000D03*
Y211000D03*
Y208000D03*
Y205000D03*
X1171500D03*
Y208000D03*
Y211000D03*
Y214000D03*
X1179651Y305942D03*
X1162710Y306037D03*
Y303037D03*
Y300037D03*
Y297037D03*
Y294037D03*
Y309037D03*
X1179651Y309942D03*
X1179411Y334250D03*
Y337750D03*
X1162710Y312037D03*
Y321037D03*
Y318037D03*
Y315037D03*
X1179411Y330750D03*
Y327250D03*
X1180986Y349234D03*
X1179877Y452442D03*
Y448442D03*
X1162799Y448537D03*
Y445537D03*
Y442537D03*
Y439537D03*
Y436537D03*
Y454537D03*
Y451537D03*
Y457537D03*
X1179500Y480250D03*
X1162799Y463537D03*
Y460537D03*
X1179500Y473250D03*
X1181075Y491734D03*
X1180498Y575739D03*
X1214582Y3004D03*
X1194582D03*
X1203887Y306894D03*
X1200887D03*
X1197887D03*
X1203887Y303894D03*
X1200887D03*
X1197887D03*
X1203887Y300894D03*
X1200887D03*
X1197887D03*
X1203887Y297894D03*
X1200887D03*
X1197887D03*
X1203887Y294894D03*
X1200887D03*
X1197887D03*
Y321894D03*
X1200887D03*
X1203887D03*
Y318894D03*
X1200887D03*
X1197887D03*
X1203887Y315894D03*
X1200887D03*
X1197887D03*
X1203887Y312894D03*
X1200887D03*
X1197887D03*
X1203887Y309894D03*
X1200887D03*
X1197887D03*
X1197976Y437394D03*
X1200976D03*
X1203976D03*
X1197976Y440394D03*
X1200976D03*
X1203976D03*
X1197976Y443394D03*
X1200976D03*
X1203976D03*
X1197976Y446394D03*
X1200976D03*
X1203976D03*
X1197976Y449394D03*
X1200976D03*
X1203976D03*
X1197976Y452394D03*
X1200976D03*
X1203976D03*
X1197976Y455394D03*
X1200976D03*
X1203976D03*
X1197976Y464394D03*
X1200976D03*
X1203976D03*
X1197976Y458394D03*
X1200976D03*
X1203976D03*
X1197976Y461394D03*
X1200976D03*
X1203976D03*
X1200498Y575739D03*
X1220498D03*
X1234582Y3004D03*
X1240498Y575739D03*
X1277657Y4128D03*
X1254582Y3004D03*
X1260498Y575739D03*
X1279438Y573806D03*
X1286766Y12634D03*
X1288331Y30962D03*
Y70962D03*
Y50962D03*
Y90962D03*
Y130962D03*
Y110962D03*
Y150962D03*
Y190962D03*
Y170962D03*
Y210962D03*
Y230962D03*
Y270962D03*
Y250962D03*
Y290962D03*
Y330962D03*
Y310962D03*
Y350962D03*
Y390962D03*
Y370962D03*
Y410962D03*
Y450962D03*
Y430962D03*
Y470962D03*
Y510962D03*
Y490962D03*
Y530962D03*
X1287616Y563889D03*
X1288331Y550962D03*
X1911126Y549509D03*
G54D11*
X19685Y-614173D03*
Y636929D03*
X619685D03*
X1271654Y-614173D03*
Y636929D03*
G54D20*
X178819Y277204D03*
X193819D03*
X253819D03*
X268819D03*
X336299D03*
X351299D03*
X411299D03*
X426299D03*
X493780D03*
X508780D03*
X568780D03*
X583780D03*
X651261D03*
X666261D03*
X726261D03*
X741261D03*
X1911126Y171509D03*
G54D21*
X165539Y539000D03*
X185224D03*
X213539D03*
X233224D03*
X261539D03*
X281224D03*
X323019D03*
X342704D03*
X371019D03*
X390704D03*
X419019D03*
X438704D03*
X480500D03*
X500185D03*
X528500D03*
X548185D03*
X576500D03*
X596185D03*
X637981D03*
X657666D03*
X685981D03*
X705666D03*
X733981D03*
X753666D03*
X1911126Y322709D03*
G54D30*
X1226024Y174429D03*
Y399429D03*
X1911126Y95909D03*
G54D12*
X72836Y47244D03*
Y535433D03*
X466536Y47244D03*
X860237D03*
X943225Y228000D03*
X985225Y542500D03*
G54D31*
G01X-297025Y-1013390D02*
Y1828909D01*
X3691357D01*
Y-1013390D01*
X-297025D01*
G01X-184400Y80974D02*
X-189050D01*
Y93474D01*
X-184400D01*
G01X-183850Y121750D02*
X-188500D01*
Y134250D01*
X-183850D01*
G01X-178050Y195423D02*
X-182700D01*
Y207923D01*
X-178050D01*
G01Y348966D02*
X-182700D01*
Y361466D01*
X-178050D01*
G01X-190600Y463455D02*
X-195250D01*
Y475955D01*
X-190600D01*
G01X-172850Y516683D02*
X-177500D01*
Y529183D01*
X-172850D01*
G01X-159600Y-18750D02*
X-164250D01*
Y-6250D01*
X-159600D01*
G01X-165650Y28494D02*
X-170300D01*
Y40994D01*
X-165650D01*
G01X-141000Y-18750D02*
X-136350D01*
Y-6250D01*
X-141000D01*
G01X-10000Y0D02*
X-126975D01*
G01X-134650Y28494D02*
X-130000D01*
Y40994D01*
X-134650D01*
G01X-116200Y80974D02*
X-111550D01*
Y93474D01*
X-116200D01*
G01X-115650Y121750D02*
X-111000D01*
Y134250D01*
X-115650D01*
G01X-122250Y195423D02*
X-117600D01*
Y207923D01*
X-122250D01*
G01Y348966D02*
X-117600D01*
Y361466D01*
X-122250D01*
G01X-129450Y516683D02*
X-124800D01*
Y529183D01*
X-129450D01*
G01X501811Y47244D02*
X-104975D01*
G01X98858Y99724D02*
X-102175D01*
G01X239252Y129685D02*
X-89900D01*
Y145500D01*
X-98375Y144794D01*
G01X9922Y214173D02*
X-98775D01*
G01X9922Y367716D02*
X-98775D01*
G01X72795Y482205D02*
X-95975D01*
G01X-110000Y463455D02*
X-105350D01*
Y475955D01*
X-110000D01*
G01X108111Y535433D02*
X-99775D01*
G01X4093Y-769672D02*
Y-844672D01*
X504093D01*
Y-769672D01*
X4093D01*
G01X0Y-10000D02*
Y-51675D01*
G01Y518622D02*
G03X11811Y506811I11811J0D01*
G01X37795D01*
G02X39764Y504843I0J-1968D01*
G01Y459567D01*
G02X37795Y457598I-1969J0D01*
G01X11811D01*
G03X0Y445787I0J-11811D01*
G01Y136102D01*
G03X11811Y124291I11811J0D01*
G01X37795D01*
G02X39764Y122323I0J-1969D01*
G01Y77047D01*
G02X37795Y75079I-1969J1D01*
G01X11811D01*
G03X0Y63268I0J-11811D01*
G01Y19685D01*
G03X19685Y0I19685J0D01*
G01X1271654D01*
G03X1291339Y19685I0J19685D01*
G01Y559055D01*
G03X1271654Y578740I-19685J0D01*
G01X19685D01*
G03X0Y559055I0J-19685D01*
G01Y518622D01*
G01Y426535D02*
Y785500D01*
G01X54252Y586614D02*
X0D01*
Y656614D01*
X54252D01*
Y586614D01*
G01X607375Y775500D02*
X0D01*
G01X7000Y777000D02*
X0Y775500D01*
X7000Y774000D01*
Y777000D01*
G01X-134Y1088504D02*
X-12634D01*
X-10134Y1086644D01*
G01X-134D02*
Y1090364D01*
G01X-12634Y1100904D02*
X-12217Y1099664D01*
X-11176Y1098734D01*
X-9926Y1098114D01*
X-8259Y1097649D01*
X-6384Y1097494D01*
X-4509Y1097649D01*
X-2842Y1098114D01*
X-1592Y1098734D01*
X-551Y1099664D01*
X-134Y1100904D01*
X-551Y1102144D01*
X-1592Y1103074D01*
X-2842Y1103694D01*
X-4509Y1104159D01*
X-6384Y1104314D01*
X-8259Y1104159D01*
X-9926Y1103694D01*
X-11176Y1103074D01*
X-12217Y1102144D01*
X-12634Y1100904D01*
G01X-134Y1109274D02*
X-12634D01*
X-2217Y1113304D01*
X-12634Y1117334D01*
X-134D01*
G01Y1121674D02*
X-12634D01*
X-2217Y1125704D01*
X-12634Y1129734D01*
X-134D01*
G01X74955Y1093324D02*
X851D01*
G01X74101Y1132694D02*
X851D01*
G01X-1905Y1343872D02*
Y1351872D01*
X-3105Y1350272D01*
G01Y1343872D02*
X-705D01*
G01X6095Y1351872D02*
X5295Y1351605D01*
X4695Y1350939D01*
X4295Y1350139D01*
X3995Y1349072D01*
X3895Y1347872D01*
X3995Y1346672D01*
X4295Y1345605D01*
X4695Y1344805D01*
X5295Y1344139D01*
X6095Y1343872D01*
X6895Y1344139D01*
X7495Y1344805D01*
X7895Y1345605D01*
X8195Y1346672D01*
X8295Y1347872D01*
X8195Y1349072D01*
X7895Y1350139D01*
X7495Y1350939D01*
X6895Y1351605D01*
X6095Y1351872D01*
G01X14095Y1343605D02*
X13895Y1343739D01*
Y1344005D01*
X14095Y1344139D01*
X14295Y1344005D01*
Y1343739D01*
X14095Y1343605D01*
G01X20195Y1343872D02*
Y1351872D01*
X23995D01*
G01X22595Y1348005D02*
X20195D01*
G01X30095Y1343872D02*
X29295Y1344005D01*
X28595Y1344539D01*
X27995Y1345339D01*
X27595Y1346272D01*
X27395Y1347339D01*
Y1348405D01*
X27595Y1349472D01*
X27995Y1350405D01*
X28595Y1351205D01*
X29295Y1351739D01*
X30095Y1351872D01*
X30895Y1351739D01*
X31595Y1351205D01*
X32195Y1350405D01*
X32595Y1349472D01*
X32795Y1348405D01*
Y1347339D01*
X32595Y1346272D01*
X32195Y1345339D01*
X31595Y1344539D01*
X30895Y1344005D01*
X30095Y1343872D01*
G01X36095D02*
Y1351872D01*
X38595D01*
X39395Y1351472D01*
X39895Y1350939D01*
X40095Y1349872D01*
X39895Y1348805D01*
X39295Y1348139D01*
X38595Y1347739D01*
X36095D01*
G01X38595D02*
X40095Y1343872D01*
G01X54095Y1351872D02*
Y1343872D01*
G01X51795Y1351872D02*
X56395D01*
G01X59995Y1343872D02*
Y1351872D01*
G01X64195D02*
Y1343872D01*
G01Y1347872D02*
X59995D01*
G01X72095Y1343872D02*
X68095D01*
Y1351872D01*
X72095D01*
G01X70495Y1348005D02*
X68095D01*
G01X84095Y1343872D02*
Y1351872D01*
X86495D01*
X87295Y1351472D01*
X87895Y1350539D01*
X88095Y1349472D01*
X87895Y1348405D01*
X87395Y1347605D01*
X86495Y1347205D01*
X84095D01*
G01X94095Y1351872D02*
Y1343872D01*
G01X91795Y1351872D02*
X96395D01*
G01X99995Y1343872D02*
Y1351872D01*
G01X104195D02*
Y1343872D01*
G01Y1347872D02*
X99995D01*
G01X118095Y1351872D02*
Y1343872D01*
G01X115795Y1351872D02*
X120395D01*
G01X126095Y1343872D02*
X125295Y1344005D01*
X124595Y1344539D01*
X123995Y1345339D01*
X123595Y1346272D01*
X123395Y1347339D01*
Y1348405D01*
X123595Y1349472D01*
X123995Y1350405D01*
X124595Y1351205D01*
X125295Y1351739D01*
X126095Y1351872D01*
X126895Y1351739D01*
X127595Y1351205D01*
X128195Y1350405D01*
X128595Y1349472D01*
X128795Y1348405D01*
Y1347339D01*
X128595Y1346272D01*
X128195Y1345339D01*
X127595Y1344539D01*
X126895Y1344005D01*
X126095Y1343872D01*
G01X134095D02*
X133295Y1344005D01*
X132595Y1344539D01*
X131995Y1345339D01*
X131595Y1346272D01*
X131395Y1347339D01*
Y1348405D01*
X131595Y1349472D01*
X131995Y1350405D01*
X132595Y1351205D01*
X133295Y1351739D01*
X134095Y1351872D01*
X134895Y1351739D01*
X135595Y1351205D01*
X136195Y1350405D01*
X136595Y1349472D01*
X136795Y1348405D01*
Y1347339D01*
X136595Y1346272D01*
X136195Y1345339D01*
X135595Y1344539D01*
X134895Y1344005D01*
X134095Y1343872D01*
G01X140095Y1351872D02*
Y1343872D01*
X144095D01*
G01X148895Y1351872D02*
X151295D01*
G01X150095D02*
Y1343872D01*
G01X148895D02*
X151295D01*
G01X155795D02*
Y1351872D01*
X160395Y1343872D01*
Y1351872D01*
G01X166695Y1347872D02*
X168695D01*
Y1345472D01*
X168095Y1344672D01*
X167395Y1344139D01*
X166395Y1343872D01*
X165395Y1344139D01*
X164695Y1344672D01*
X164095Y1345472D01*
X163695Y1346405D01*
X163495Y1347472D01*
Y1348405D01*
X163695Y1349205D01*
X164095Y1350139D01*
X164695Y1350939D01*
X165295Y1351472D01*
X166095Y1351872D01*
X166795D01*
X167595Y1351605D01*
X168195Y1351072D01*
G01X179995Y1343872D02*
Y1351872D01*
G01X184195D02*
Y1343872D01*
G01Y1347872D02*
X179995D01*
G01X190095Y1343872D02*
X189295Y1344005D01*
X188595Y1344539D01*
X187995Y1345339D01*
X187595Y1346272D01*
X187395Y1347339D01*
Y1348405D01*
X187595Y1349472D01*
X187995Y1350405D01*
X188595Y1351205D01*
X189295Y1351739D01*
X190095Y1351872D01*
X190895Y1351739D01*
X191595Y1351205D01*
X192195Y1350405D01*
X192595Y1349472D01*
X192795Y1348405D01*
Y1347339D01*
X192595Y1346272D01*
X192195Y1345339D01*
X191595Y1344539D01*
X190895Y1344005D01*
X190095Y1343872D01*
G01X196095Y1351872D02*
Y1343872D01*
X200095D01*
G01X208095D02*
X204095D01*
Y1351872D01*
X208095D01*
G01X206495Y1348005D02*
X204095D01*
G01X211995Y1344938D02*
X212795Y1344272D01*
X213695Y1343872D01*
X214495D01*
X215295Y1344272D01*
X215895Y1344938D01*
X216195Y1345872D01*
X215995Y1346805D01*
X215495Y1347605D01*
X214595Y1348139D01*
X213395Y1348405D01*
X212695Y1348939D01*
X212395Y1349872D01*
X212595Y1350805D01*
X213095Y1351472D01*
X213795Y1351872D01*
X214495D01*
X215195Y1351605D01*
X215795Y1350939D01*
G01X227095Y1351872D02*
X228495Y1343872D01*
X230095Y1351872D01*
X231695Y1343872D01*
X233095Y1351872D01*
G01X235995Y1343872D02*
Y1351872D01*
G01X240195D02*
Y1343872D01*
G01Y1347872D02*
X235995D01*
G01X244895Y1351872D02*
X247295D01*
G01X246095D02*
Y1343872D01*
G01X244895D02*
X247295D01*
G01X256295Y1351205D02*
X255695Y1351605D01*
X254995Y1351872D01*
X254195D01*
X253295Y1351472D01*
X252595Y1350805D01*
X252095Y1350005D01*
X251695Y1348672D01*
X251595Y1347472D01*
X251795Y1346272D01*
X252095Y1345472D01*
X252695Y1344672D01*
X253395Y1344139D01*
X254095Y1343872D01*
X254795D01*
X255495Y1344139D01*
X256095Y1344539D01*
X256595Y1345072D01*
G01X259995Y1343872D02*
Y1351872D01*
G01X264195D02*
Y1343872D01*
G01Y1347872D02*
X259995D01*
G01X275995Y1344938D02*
X276795Y1344272D01*
X277695Y1343872D01*
X278495D01*
X279295Y1344272D01*
X279895Y1344938D01*
X280195Y1345872D01*
X279995Y1346805D01*
X279495Y1347605D01*
X278595Y1348139D01*
X277395Y1348405D01*
X276695Y1348939D01*
X276395Y1349872D01*
X276595Y1350805D01*
X277095Y1351472D01*
X277795Y1351872D01*
X278495D01*
X279195Y1351605D01*
X279795Y1350939D01*
G01X284895Y1351872D02*
X287295D01*
G01X286095D02*
Y1343872D01*
G01X284895D02*
X287295D01*
G01X292195Y1351872D02*
X295995D01*
X292195Y1343872D01*
X295995D01*
G01X304095D02*
X300095D01*
Y1351872D01*
X304095D01*
G01X302495Y1348005D02*
X300095D01*
G01X316895Y1351872D02*
X319295D01*
G01X318095D02*
Y1343872D01*
G01X316895D02*
X319295D01*
G01X323995Y1344938D02*
X324795Y1344272D01*
X325695Y1343872D01*
X326495D01*
X327295Y1344272D01*
X327895Y1344938D01*
X328195Y1345872D01*
X327995Y1346805D01*
X327495Y1347605D01*
X326595Y1348139D01*
X325395Y1348405D01*
X324695Y1348939D01*
X324395Y1349872D01*
X324595Y1350805D01*
X325095Y1351472D01*
X325795Y1351872D01*
X326495D01*
X327195Y1351605D01*
X327795Y1350939D01*
G01X344095Y1343872D02*
X340095D01*
Y1351872D01*
X344095D01*
G01X342495Y1348005D02*
X340095D01*
G01X350095Y1343872D02*
X349295Y1344005D01*
X348595Y1344539D01*
X347995Y1345339D01*
X347595Y1346272D01*
X347395Y1347339D01*
Y1348405D01*
X347595Y1349472D01*
X347995Y1350405D01*
X348595Y1351205D01*
X349295Y1351739D01*
X350095Y1351872D01*
X350895Y1351739D01*
X351595Y1351205D01*
X352195Y1350405D01*
X352595Y1349472D01*
X352795Y1348405D01*
Y1347339D01*
X352595Y1346272D01*
X352195Y1345339D01*
X351595Y1344539D01*
X350895Y1344005D01*
X350095Y1343872D01*
G01X350895Y1346005D02*
X352095Y1343872D01*
G01X355895Y1351872D02*
Y1346139D01*
X356295Y1344938D01*
X357095Y1344139D01*
X358095Y1343872D01*
X359095Y1344139D01*
X359895Y1344938D01*
X360295Y1346139D01*
Y1351872D01*
G01X363595Y1343872D02*
X366095Y1351872D01*
X368595Y1343872D01*
G01X367695Y1346672D02*
X364495D01*
G01X372095Y1351872D02*
Y1343872D01*
X376095D01*
G01X390095Y1351872D02*
Y1343872D01*
G01X387795Y1351872D02*
X392395D01*
G01X398095Y1343872D02*
X397295Y1344005D01*
X396595Y1344539D01*
X395995Y1345339D01*
X395595Y1346272D01*
X395395Y1347339D01*
Y1348405D01*
X395595Y1349472D01*
X395995Y1350405D01*
X396595Y1351205D01*
X397295Y1351739D01*
X398095Y1351872D01*
X398895Y1351739D01*
X399595Y1351205D01*
X400195Y1350405D01*
X400595Y1349472D01*
X400795Y1348405D01*
Y1347339D01*
X400595Y1346272D01*
X400195Y1345339D01*
X399595Y1344539D01*
X398895Y1344005D01*
X398095Y1343872D01*
G01X414095D02*
X413295Y1344005D01*
X412595Y1344539D01*
X411995Y1345339D01*
X411595Y1346272D01*
X411395Y1347339D01*
Y1348405D01*
X411595Y1349472D01*
X411995Y1350405D01*
X412595Y1351205D01*
X413295Y1351739D01*
X414095Y1351872D01*
X414895Y1351739D01*
X415595Y1351205D01*
X416195Y1350405D01*
X416595Y1349472D01*
X416795Y1348405D01*
Y1347339D01*
X416595Y1346272D01*
X416195Y1345339D01*
X415595Y1344539D01*
X414895Y1344005D01*
X414095Y1343872D01*
G01X420095D02*
Y1351872D01*
X422595D01*
X423395Y1351472D01*
X423895Y1350939D01*
X424095Y1349872D01*
X423895Y1348805D01*
X423295Y1348139D01*
X422595Y1347739D01*
X420095D01*
G01X422595D02*
X424095Y1343872D01*
G01X435495D02*
Y1351872D01*
X438095Y1345205D01*
X440695Y1351872D01*
Y1343872D01*
G01X446095D02*
X445295Y1344005D01*
X444595Y1344539D01*
X443995Y1345339D01*
X443595Y1346272D01*
X443395Y1347339D01*
Y1348405D01*
X443595Y1349472D01*
X443995Y1350405D01*
X444595Y1351205D01*
X445295Y1351739D01*
X446095Y1351872D01*
X446895Y1351739D01*
X447595Y1351205D01*
X448195Y1350405D01*
X448595Y1349472D01*
X448795Y1348405D01*
Y1347339D01*
X448595Y1346272D01*
X448195Y1345339D01*
X447595Y1344539D01*
X446895Y1344005D01*
X446095Y1343872D01*
G01X452095D02*
Y1351872D01*
X454595D01*
X455395Y1351472D01*
X455895Y1350939D01*
X456095Y1349872D01*
X455895Y1348805D01*
X455295Y1348139D01*
X454595Y1347739D01*
X452095D01*
G01X454595D02*
X456095Y1343872D01*
G01X464095D02*
X460095D01*
Y1351872D01*
X464095D01*
G01X462495Y1348005D02*
X460095D01*
G01X478095Y1351872D02*
Y1343872D01*
G01X475795Y1351872D02*
X480395D01*
G01X483995Y1343872D02*
Y1351872D01*
G01X488195D02*
Y1343872D01*
G01Y1347872D02*
X483995D01*
G01X491595Y1343872D02*
X494095Y1351872D01*
X496595Y1343872D01*
G01X495695Y1346672D02*
X492495D01*
G01X499795Y1343872D02*
Y1351872D01*
X504395Y1343872D01*
Y1351872D01*
G01X517895Y1343872D02*
X518095Y1345605D01*
X518395Y1347072D01*
X518795Y1348405D01*
X519295Y1349872D01*
X520095Y1351872D01*
X516095D01*
G01X526095D02*
X525295Y1351605D01*
X524695Y1350939D01*
X524295Y1350139D01*
X523995Y1349072D01*
X523895Y1347872D01*
X523995Y1346672D01*
X524295Y1345605D01*
X524695Y1344805D01*
X525295Y1344139D01*
X526095Y1343872D01*
X526895Y1344139D01*
X527495Y1344805D01*
X527895Y1345605D01*
X528195Y1346672D01*
X528295Y1347872D01*
X528195Y1349072D01*
X527895Y1350139D01*
X527495Y1350939D01*
X526895Y1351605D01*
X526095Y1351872D01*
G01X539495Y1343872D02*
Y1351872D01*
X542095Y1345205D01*
X544695Y1351872D01*
Y1343872D01*
G01X548895Y1351872D02*
X551295D01*
G01X550095D02*
Y1343872D01*
G01X548895D02*
X551295D01*
G01X556095Y1351872D02*
Y1343872D01*
X560095D01*
G01X566095Y1343605D02*
X565895Y1343739D01*
Y1344005D01*
X566095Y1344139D01*
X566295Y1344005D01*
Y1343739D01*
X566095Y1343605D01*
G01X587795Y1343872D02*
Y1351872D01*
X592395Y1343872D01*
Y1351872D01*
G01X598095Y1343872D02*
X597295Y1344005D01*
X596595Y1344539D01*
X595995Y1345339D01*
X595595Y1346272D01*
X595395Y1347339D01*
Y1348405D01*
X595595Y1349472D01*
X595995Y1350405D01*
X596595Y1351205D01*
X597295Y1351739D01*
X598095Y1351872D01*
X598895Y1351739D01*
X599595Y1351205D01*
X600195Y1350405D01*
X600595Y1349472D01*
X600795Y1348405D01*
Y1347339D01*
X600595Y1346272D01*
X600195Y1345339D01*
X599595Y1344539D01*
X598895Y1344005D01*
X598095Y1343872D01*
G01X603795D02*
Y1351872D01*
X608395Y1343872D01*
Y1351872D01*
G01X612795Y1346539D02*
X615395D01*
G01X620195Y1343872D02*
Y1351872D01*
X623995D01*
G01X622595Y1348005D02*
X620195D01*
G01X627895Y1351872D02*
Y1346139D01*
X628295Y1344938D01*
X629095Y1344139D01*
X630095Y1343872D01*
X631095Y1344139D01*
X631895Y1344938D01*
X632295Y1346139D01*
Y1351872D01*
G01X635795Y1343872D02*
Y1351872D01*
X640395Y1343872D01*
Y1351872D01*
G01X648295Y1351205D02*
X647695Y1351605D01*
X646995Y1351872D01*
X646195D01*
X645295Y1351472D01*
X644595Y1350805D01*
X644095Y1350005D01*
X643695Y1348672D01*
X643595Y1347472D01*
X643795Y1346272D01*
X644095Y1345472D01*
X644695Y1344672D01*
X645395Y1344139D01*
X646095Y1343872D01*
X646795D01*
X647495Y1344139D01*
X648095Y1344539D01*
X648595Y1345072D01*
G01X654095Y1351872D02*
Y1343872D01*
G01X651795Y1351872D02*
X656395D01*
G01X660895D02*
X663295D01*
G01X662095D02*
Y1343872D01*
G01X660895D02*
X663295D01*
G01X670095D02*
X669295Y1344005D01*
X668595Y1344539D01*
X667995Y1345339D01*
X667595Y1346272D01*
X667395Y1347339D01*
Y1348405D01*
X667595Y1349472D01*
X667995Y1350405D01*
X668595Y1351205D01*
X669295Y1351739D01*
X670095Y1351872D01*
X670895Y1351739D01*
X671595Y1351205D01*
X672195Y1350405D01*
X672595Y1349472D01*
X672795Y1348405D01*
Y1347339D01*
X672595Y1346272D01*
X672195Y1345339D01*
X671595Y1344539D01*
X670895Y1344005D01*
X670095Y1343872D01*
G01X675795D02*
Y1351872D01*
X680395Y1343872D01*
Y1351872D01*
G01X683595Y1343872D02*
X686095Y1351872D01*
X688595Y1343872D01*
G01X687695Y1346672D02*
X684495D01*
G01X692095Y1351872D02*
Y1343872D01*
X696095D01*
G01X708095D02*
Y1351872D01*
X710495D01*
X711295Y1351472D01*
X711895Y1350539D01*
X712095Y1349472D01*
X711895Y1348405D01*
X711395Y1347605D01*
X710495Y1347205D01*
X708095D01*
G01X715595Y1343872D02*
X718095Y1351872D01*
X720595Y1343872D01*
G01X719695Y1346672D02*
X716495D01*
G01X723895Y1343872D02*
Y1351872D01*
X725895D01*
X726695Y1351472D01*
X727295Y1350939D01*
X727795Y1350139D01*
X728195Y1349205D01*
X728295Y1347872D01*
X728195Y1346539D01*
X727795Y1345605D01*
X727295Y1344805D01*
X726695Y1344272D01*
X725895Y1343872D01*
X723895D01*
G01X740895Y1351872D02*
X743295D01*
G01X742095D02*
Y1343872D01*
G01X740895D02*
X743295D01*
G01X747995Y1344938D02*
X748795Y1344272D01*
X749695Y1343872D01*
X750495D01*
X751295Y1344272D01*
X751895Y1344938D01*
X752195Y1345872D01*
X751995Y1346805D01*
X751495Y1347605D01*
X750595Y1348139D01*
X749395Y1348405D01*
X748695Y1348939D01*
X748395Y1349872D01*
X748595Y1350805D01*
X749095Y1351472D01*
X749795Y1351872D01*
X750495D01*
X751195Y1351605D01*
X751795Y1350939D01*
G01X764095Y1343872D02*
Y1351872D01*
X766595D01*
X767395Y1351472D01*
X767895Y1350939D01*
X768095Y1349872D01*
X767895Y1348805D01*
X767295Y1348139D01*
X766595Y1347739D01*
X764095D01*
G01X766595D02*
X768095Y1343872D01*
G01X776095D02*
X772095D01*
Y1351872D01*
X776095D01*
G01X774495Y1348005D02*
X772095D01*
G01X782095Y1343872D02*
X781295Y1344005D01*
X780595Y1344539D01*
X779995Y1345339D01*
X779595Y1346272D01*
X779395Y1347339D01*
Y1348405D01*
X779595Y1349472D01*
X779995Y1350405D01*
X780595Y1351205D01*
X781295Y1351739D01*
X782095Y1351872D01*
X782895Y1351739D01*
X783595Y1351205D01*
X784195Y1350405D01*
X784595Y1349472D01*
X784795Y1348405D01*
Y1347339D01*
X784595Y1346272D01*
X784195Y1345339D01*
X783595Y1344539D01*
X782895Y1344005D01*
X782095Y1343872D01*
G01X782895Y1346005D02*
X784095Y1343872D01*
G01X787895Y1351872D02*
Y1346139D01*
X788295Y1344938D01*
X789095Y1344139D01*
X790095Y1343872D01*
X791095Y1344139D01*
X791895Y1344938D01*
X792295Y1346139D01*
Y1351872D01*
G01X796895D02*
X799295D01*
G01X798095D02*
Y1343872D01*
G01X796895D02*
X799295D01*
G01X804095D02*
Y1351872D01*
X806595D01*
X807395Y1351472D01*
X807895Y1350939D01*
X808095Y1349872D01*
X807895Y1348805D01*
X807295Y1348139D01*
X806595Y1347739D01*
X804095D01*
G01X806595D02*
X808095Y1343872D01*
G01X816095D02*
X812095D01*
Y1351872D01*
X816095D01*
G01X814495Y1348005D02*
X812095D01*
G01X819895Y1343872D02*
Y1351872D01*
X821895D01*
X822695Y1351472D01*
X823295Y1350939D01*
X823795Y1350139D01*
X824195Y1349205D01*
X824295Y1347872D01*
X824195Y1346539D01*
X823795Y1345605D01*
X823295Y1344805D01*
X822695Y1344272D01*
X821895Y1343872D01*
X819895D01*
G01X838095Y1351872D02*
Y1343872D01*
G01X835795Y1351872D02*
X840395D01*
G01X846095Y1343872D02*
X845295Y1344005D01*
X844595Y1344539D01*
X843995Y1345339D01*
X843595Y1346272D01*
X843395Y1347339D01*
Y1348405D01*
X843595Y1349472D01*
X843995Y1350405D01*
X844595Y1351205D01*
X845295Y1351739D01*
X846095Y1351872D01*
X846895Y1351739D01*
X847595Y1351205D01*
X848195Y1350405D01*
X848595Y1349472D01*
X848795Y1348405D01*
Y1347339D01*
X848595Y1346272D01*
X848195Y1345339D01*
X847595Y1344539D01*
X846895Y1344005D01*
X846095Y1343872D01*
G01X862895Y1348139D02*
X863295Y1348539D01*
X863595Y1349205D01*
X863795Y1350139D01*
X863595Y1350939D01*
X863195Y1351472D01*
X862495Y1351872D01*
X859795D01*
Y1343872D01*
X863095D01*
X863795Y1344405D01*
X864195Y1345205D01*
X864395Y1346139D01*
X864195Y1347072D01*
X863595Y1347872D01*
X862895Y1348139D01*
X859795D01*
G01X872095Y1343872D02*
X868095D01*
Y1351872D01*
X872095D01*
G01X870495Y1348005D02*
X868095D01*
G01X883595Y1343872D02*
X886095Y1351872D01*
X888595Y1343872D01*
G01X887695Y1346672D02*
X884495D01*
G01X891895Y1343872D02*
Y1351872D01*
X893895D01*
X894695Y1351472D01*
X895295Y1350939D01*
X895795Y1350139D01*
X896195Y1349205D01*
X896295Y1347872D01*
X896195Y1346539D01*
X895795Y1345605D01*
X895295Y1344805D01*
X894695Y1344272D01*
X893895Y1343872D01*
X891895D01*
G01X899895D02*
Y1351872D01*
X901895D01*
X902695Y1351472D01*
X903295Y1350939D01*
X903795Y1350139D01*
X904195Y1349205D01*
X904295Y1347872D01*
X904195Y1346539D01*
X903795Y1345605D01*
X903295Y1344805D01*
X902695Y1344272D01*
X901895Y1343872D01*
X899895D01*
G01X912095D02*
X908095D01*
Y1351872D01*
X912095D01*
G01X910495Y1348005D02*
X908095D01*
G01X915895Y1343872D02*
Y1351872D01*
X917895D01*
X918695Y1351472D01*
X919295Y1350939D01*
X919795Y1350139D01*
X920195Y1349205D01*
X920295Y1347872D01*
X920195Y1346539D01*
X919795Y1345605D01*
X919295Y1344805D01*
X918695Y1344272D01*
X917895Y1343872D01*
X915895D01*
G01X934095Y1351872D02*
Y1343872D01*
G01X931795Y1351872D02*
X936395D01*
G01X942095Y1343872D02*
X941295Y1344005D01*
X940595Y1344539D01*
X939995Y1345339D01*
X939595Y1346272D01*
X939395Y1347339D01*
Y1348405D01*
X939595Y1349472D01*
X939995Y1350405D01*
X940595Y1351205D01*
X941295Y1351739D01*
X942095Y1351872D01*
X942895Y1351739D01*
X943595Y1351205D01*
X944195Y1350405D01*
X944595Y1349472D01*
X944795Y1348405D01*
Y1347339D01*
X944595Y1346272D01*
X944195Y1345339D01*
X943595Y1344539D01*
X942895Y1344005D01*
X942095Y1343872D01*
G01X956095D02*
Y1351872D01*
X958495D01*
X959295Y1351472D01*
X959895Y1350539D01*
X960095Y1349472D01*
X959895Y1348405D01*
X959395Y1347605D01*
X958495Y1347205D01*
X956095D01*
G01X964095Y1343872D02*
Y1351872D01*
X966595D01*
X967395Y1351472D01*
X967895Y1350939D01*
X968095Y1349872D01*
X967895Y1348805D01*
X967295Y1348139D01*
X966595Y1347739D01*
X964095D01*
G01X966595D02*
X968095Y1343872D01*
G01X976095D02*
X972095D01*
Y1351872D01*
X976095D01*
G01X974495Y1348005D02*
X972095D01*
G01X979595Y1351872D02*
X982095Y1343872D01*
X984595Y1351872D01*
G01X992095Y1343872D02*
X988095D01*
Y1351872D01*
X992095D01*
G01X990495Y1348005D02*
X988095D01*
G01X995795Y1343872D02*
Y1351872D01*
X1000395Y1343872D01*
Y1351872D01*
G01X1006095D02*
Y1343872D01*
G01X1003795Y1351872D02*
X1008395D01*
G01X1022095D02*
Y1343872D01*
G01X1019795Y1351872D02*
X1024395D01*
G01X1027995Y1343872D02*
Y1351872D01*
G01X1032195D02*
Y1343872D01*
G01Y1347872D02*
X1027995D01*
G01X1040095Y1343872D02*
X1036095D01*
Y1351872D01*
X1040095D01*
G01X1038495Y1348005D02*
X1036095D01*
G01X1052095Y1343872D02*
Y1351872D01*
X1054495D01*
X1055295Y1351472D01*
X1055895Y1350539D01*
X1056095Y1349472D01*
X1055895Y1348405D01*
X1055395Y1347605D01*
X1054495Y1347205D01*
X1052095D01*
G01X1062095Y1343872D02*
X1061295Y1344005D01*
X1060595Y1344539D01*
X1059995Y1345339D01*
X1059595Y1346272D01*
X1059395Y1347339D01*
Y1348405D01*
X1059595Y1349472D01*
X1059995Y1350405D01*
X1060595Y1351205D01*
X1061295Y1351739D01*
X1062095Y1351872D01*
X1062895Y1351739D01*
X1063595Y1351205D01*
X1064195Y1350405D01*
X1064595Y1349472D01*
X1064795Y1348405D01*
Y1347339D01*
X1064595Y1346272D01*
X1064195Y1345339D01*
X1063595Y1344539D01*
X1062895Y1344005D01*
X1062095Y1343872D01*
G01X1070095Y1351872D02*
Y1343872D01*
G01X1067795Y1351872D02*
X1072395D01*
G01X1080095Y1343872D02*
X1076095D01*
Y1351872D01*
X1080095D01*
G01X1078495Y1348005D02*
X1076095D01*
G01X1083795Y1343872D02*
Y1351872D01*
X1088395Y1343872D01*
Y1351872D01*
G01X1094095D02*
Y1343872D01*
G01X1091795Y1351872D02*
X1096395D01*
G01X1100895D02*
X1103295D01*
G01X1102095D02*
Y1343872D01*
G01X1100895D02*
X1103295D01*
G01X1107595D02*
X1110095Y1351872D01*
X1112595Y1343872D01*
G01X1111695Y1346672D02*
X1108495D01*
G01X1116095Y1351872D02*
Y1343872D01*
X1120095D01*
G01X1132095D02*
Y1351872D01*
X1134495D01*
X1135295Y1351472D01*
X1135895Y1350539D01*
X1136095Y1349472D01*
X1135895Y1348405D01*
X1135395Y1347605D01*
X1134495Y1347205D01*
X1132095D01*
G01X1139895Y1351872D02*
Y1346139D01*
X1140295Y1344938D01*
X1141095Y1344139D01*
X1142095Y1343872D01*
X1143095Y1344139D01*
X1143895Y1344938D01*
X1144295Y1346139D01*
Y1351872D01*
G01X1148095D02*
Y1343872D01*
X1152095D01*
G01X1156095Y1351872D02*
Y1343872D01*
X1160095D01*
G01X1171595D02*
X1174095Y1351872D01*
X1176595Y1343872D01*
G01X1175695Y1346672D02*
X1172495D01*
G01X1179095Y1351872D02*
X1180495Y1343872D01*
X1182095Y1351872D01*
X1183695Y1343872D01*
X1185095Y1351872D01*
G01X1187595Y1343872D02*
X1190095Y1351872D01*
X1192595Y1343872D01*
G01X1191695Y1346672D02*
X1188495D01*
G01X1198095Y1343872D02*
Y1347472D01*
X1196095Y1351872D01*
G01X1200095D02*
X1198095Y1347472D01*
G01X1206095Y1343605D02*
X1205895Y1343739D01*
Y1344005D01*
X1206095Y1344139D01*
X1206295Y1344005D01*
Y1343739D01*
X1206095Y1343605D01*
G01X-3605Y1359805D02*
X-2905Y1359139D01*
X-2105Y1358872D01*
X-1305Y1359139D01*
X-605Y1359938D01*
X-105Y1361139D01*
X95Y1362339D01*
Y1363805D01*
X-105Y1365005D01*
X-605Y1366072D01*
X-1205Y1366605D01*
X-1905Y1366872D01*
X-2705Y1366605D01*
X-3305Y1366072D01*
X-3705Y1365272D01*
X-3905Y1364205D01*
X-3705Y1363272D01*
X-3205Y1362339D01*
X-2605Y1361805D01*
X-1905Y1361672D01*
X-1105Y1361938D01*
X-505Y1362605D01*
X95Y1363805D01*
G01X6095Y1358605D02*
X5895Y1358739D01*
Y1359005D01*
X6095Y1359139D01*
X6295Y1359005D01*
Y1358739D01*
X6095Y1358605D01*
G01X11595Y1358872D02*
X14095Y1366872D01*
X16595Y1358872D01*
G01X15695Y1361672D02*
X12495D01*
G01X19795Y1358872D02*
Y1366872D01*
X24395Y1358872D01*
Y1366872D01*
G01X30095Y1358872D02*
Y1362472D01*
X28095Y1366872D01*
G01X32095D02*
X30095Y1362472D01*
G01X43995Y1359938D02*
X44795Y1359272D01*
X45695Y1358872D01*
X46495D01*
X47295Y1359272D01*
X47895Y1359938D01*
X48195Y1360872D01*
X47995Y1361805D01*
X47495Y1362605D01*
X46595Y1363139D01*
X45395Y1363405D01*
X44695Y1363939D01*
X44395Y1364872D01*
X44595Y1365805D01*
X45095Y1366472D01*
X45795Y1366872D01*
X46495D01*
X47195Y1366605D01*
X47795Y1365939D01*
G01X52095Y1358872D02*
Y1366872D01*
X54495D01*
X55295Y1366472D01*
X55895Y1365539D01*
X56095Y1364472D01*
X55895Y1363405D01*
X55395Y1362605D01*
X54495Y1362205D01*
X52095D01*
G01X64095Y1358872D02*
X60095D01*
Y1366872D01*
X64095D01*
G01X62495Y1363005D02*
X60095D01*
G01X72295Y1366205D02*
X71695Y1366605D01*
X70995Y1366872D01*
X70195D01*
X69295Y1366472D01*
X68595Y1365805D01*
X68095Y1365005D01*
X67695Y1363672D01*
X67595Y1362472D01*
X67795Y1361272D01*
X68095Y1360472D01*
X68695Y1359672D01*
X69395Y1359139D01*
X70095Y1358872D01*
X70795D01*
X71495Y1359139D01*
X72095Y1359539D01*
X72595Y1360072D01*
G01X76895Y1366872D02*
X79295D01*
G01X78095D02*
Y1358872D01*
G01X76895D02*
X79295D01*
G01X83595D02*
X86095Y1366872D01*
X88595Y1358872D01*
G01X87695Y1361672D02*
X84495D01*
G01X92095Y1366872D02*
Y1358872D01*
X96095D01*
G01X107895D02*
Y1366872D01*
X109895D01*
X110695Y1366472D01*
X111295Y1365939D01*
X111795Y1365139D01*
X112195Y1364205D01*
X112295Y1362872D01*
X112195Y1361539D01*
X111795Y1360605D01*
X111295Y1359805D01*
X110695Y1359272D01*
X109895Y1358872D01*
X107895D01*
G01X116095D02*
Y1366872D01*
X118595D01*
X119395Y1366472D01*
X119895Y1365939D01*
X120095Y1364872D01*
X119895Y1363805D01*
X119295Y1363139D01*
X118595Y1362739D01*
X116095D01*
G01X118595D02*
X120095Y1358872D01*
G01X124895Y1366872D02*
X127295D01*
G01X126095D02*
Y1358872D01*
G01X124895D02*
X127295D01*
G01X132095Y1366872D02*
Y1358872D01*
X136095D01*
G01X140095Y1366872D02*
Y1358872D01*
X144095D01*
G01X155595D02*
X158095Y1366872D01*
X160595Y1358872D01*
G01X159695Y1361672D02*
X156495D01*
G01X163795Y1358872D02*
Y1366872D01*
X168395Y1358872D01*
Y1366872D01*
G01X171895Y1358872D02*
Y1366872D01*
X173895D01*
X174695Y1366472D01*
X175295Y1365939D01*
X175795Y1365139D01*
X176195Y1364205D01*
X176295Y1362872D01*
X176195Y1361539D01*
X175795Y1360605D01*
X175295Y1359805D01*
X174695Y1359272D01*
X173895Y1358872D01*
X171895D01*
G01X187995Y1359938D02*
X188795Y1359272D01*
X189695Y1358872D01*
X190495D01*
X191295Y1359272D01*
X191895Y1359938D01*
X192195Y1360872D01*
X191995Y1361805D01*
X191495Y1362605D01*
X190595Y1363139D01*
X189395Y1363405D01*
X188695Y1363939D01*
X188395Y1364872D01*
X188595Y1365805D01*
X189095Y1366472D01*
X189795Y1366872D01*
X190495D01*
X191195Y1366605D01*
X191795Y1365939D01*
G01X198095Y1366872D02*
Y1358872D01*
G01X195795Y1366872D02*
X200395D01*
G01X203595Y1358872D02*
X206095Y1366872D01*
X208595Y1358872D01*
G01X207695Y1361672D02*
X204495D01*
G01X216295Y1366205D02*
X215695Y1366605D01*
X214995Y1366872D01*
X214195D01*
X213295Y1366472D01*
X212595Y1365805D01*
X212095Y1365005D01*
X211695Y1363672D01*
X211595Y1362472D01*
X211795Y1361272D01*
X212095Y1360472D01*
X212695Y1359672D01*
X213395Y1359139D01*
X214095Y1358872D01*
X214795D01*
X215495Y1359139D01*
X216095Y1359539D01*
X216595Y1360072D01*
G01X219895Y1358872D02*
Y1366872D01*
G01X223695D02*
X219895Y1361938D01*
G01X224295Y1358872D02*
X221595Y1364205D01*
G01X232095Y1358872D02*
X228095D01*
Y1366872D01*
X232095D01*
G01X230495Y1363005D02*
X228095D01*
G01X235895Y1358872D02*
Y1366872D01*
X237895D01*
X238695Y1366472D01*
X239295Y1365939D01*
X239795Y1365139D01*
X240195Y1364205D01*
X240295Y1362872D01*
X240195Y1361539D01*
X239795Y1360605D01*
X239295Y1359805D01*
X238695Y1359272D01*
X237895Y1358872D01*
X235895D01*
G01X251995D02*
Y1366872D01*
G01X256195D02*
Y1358872D01*
G01Y1362872D02*
X251995D01*
G01X262095Y1358872D02*
X261295Y1359005D01*
X260595Y1359539D01*
X259995Y1360339D01*
X259595Y1361272D01*
X259395Y1362339D01*
Y1363405D01*
X259595Y1364472D01*
X259995Y1365405D01*
X260595Y1366205D01*
X261295Y1366739D01*
X262095Y1366872D01*
X262895Y1366739D01*
X263595Y1366205D01*
X264195Y1365405D01*
X264595Y1364472D01*
X264795Y1363405D01*
Y1362339D01*
X264595Y1361272D01*
X264195Y1360339D01*
X263595Y1359539D01*
X262895Y1359005D01*
X262095Y1358872D01*
G01X268095Y1366872D02*
Y1358872D01*
X272095D01*
G01X280095D02*
X276095D01*
Y1366872D01*
X280095D01*
G01X278495Y1363005D02*
X276095D01*
G01X292095Y1358872D02*
Y1366872D01*
X294495D01*
X295295Y1366472D01*
X295895Y1365539D01*
X296095Y1364472D01*
X295895Y1363405D01*
X295395Y1362605D01*
X294495Y1362205D01*
X292095D01*
G01X300095Y1366872D02*
Y1358872D01*
X304095D01*
G01X312095D02*
X308095D01*
Y1366872D01*
X312095D01*
G01X310495Y1363005D02*
X308095D01*
G01X315595Y1358872D02*
X318095Y1366872D01*
X320595Y1358872D01*
G01X319695Y1361672D02*
X316495D01*
G01X323995Y1359938D02*
X324795Y1359272D01*
X325695Y1358872D01*
X326495D01*
X327295Y1359272D01*
X327895Y1359938D01*
X328195Y1360872D01*
X327995Y1361805D01*
X327495Y1362605D01*
X326595Y1363139D01*
X325395Y1363405D01*
X324695Y1363939D01*
X324395Y1364872D01*
X324595Y1365805D01*
X325095Y1366472D01*
X325795Y1366872D01*
X326495D01*
X327195Y1366605D01*
X327795Y1365939D01*
G01X336095Y1358872D02*
X332095D01*
Y1366872D01*
X336095D01*
G01X334495Y1363005D02*
X332095D01*
G01X348195Y1358872D02*
Y1366872D01*
X351995D01*
G01X350595Y1363005D02*
X348195D01*
G01X358095Y1358872D02*
X357295Y1359005D01*
X356595Y1359539D01*
X355995Y1360339D01*
X355595Y1361272D01*
X355395Y1362339D01*
Y1363405D01*
X355595Y1364472D01*
X355995Y1365405D01*
X356595Y1366205D01*
X357295Y1366739D01*
X358095Y1366872D01*
X358895Y1366739D01*
X359595Y1366205D01*
X360195Y1365405D01*
X360595Y1364472D01*
X360795Y1363405D01*
Y1362339D01*
X360595Y1361272D01*
X360195Y1360339D01*
X359595Y1359539D01*
X358895Y1359005D01*
X358095Y1358872D01*
G01X364095Y1366872D02*
Y1358872D01*
X368095D01*
G01X372095Y1366872D02*
Y1358872D01*
X376095D01*
G01X382095D02*
X381295Y1359005D01*
X380595Y1359539D01*
X379995Y1360339D01*
X379595Y1361272D01*
X379395Y1362339D01*
Y1363405D01*
X379595Y1364472D01*
X379995Y1365405D01*
X380595Y1366205D01*
X381295Y1366739D01*
X382095Y1366872D01*
X382895Y1366739D01*
X383595Y1366205D01*
X384195Y1365405D01*
X384595Y1364472D01*
X384795Y1363405D01*
Y1362339D01*
X384595Y1361272D01*
X384195Y1360339D01*
X383595Y1359539D01*
X382895Y1359005D01*
X382095Y1358872D01*
G01X387095Y1366872D02*
X388495Y1358872D01*
X390095Y1366872D01*
X391695Y1358872D01*
X393095Y1366872D01*
G01X406095Y1358872D02*
X405295Y1359005D01*
X404595Y1359539D01*
X403995Y1360339D01*
X403595Y1361272D01*
X403395Y1362339D01*
Y1363405D01*
X403595Y1364472D01*
X403995Y1365405D01*
X404595Y1366205D01*
X405295Y1366739D01*
X406095Y1366872D01*
X406895Y1366739D01*
X407595Y1366205D01*
X408195Y1365405D01*
X408595Y1364472D01*
X408795Y1363405D01*
Y1362339D01*
X408595Y1361272D01*
X408195Y1360339D01*
X407595Y1359539D01*
X406895Y1359005D01*
X406095Y1358872D01*
G01X411895Y1366872D02*
Y1361139D01*
X412295Y1359938D01*
X413095Y1359139D01*
X414095Y1358872D01*
X415095Y1359139D01*
X415895Y1359938D01*
X416295Y1361139D01*
Y1366872D01*
G01X422095D02*
Y1358872D01*
G01X419795Y1366872D02*
X424395D01*
G01X428095D02*
Y1358872D01*
X432095D01*
G01X436895Y1366872D02*
X439295D01*
G01X438095D02*
Y1358872D01*
G01X436895D02*
X439295D01*
G01X443795D02*
Y1366872D01*
X448395Y1358872D01*
Y1366872D01*
G01X456095Y1358872D02*
X452095D01*
Y1366872D01*
X456095D01*
G01X454495Y1363005D02*
X452095D01*
G01X462095Y1358605D02*
X461895Y1358739D01*
Y1359005D01*
X462095Y1359139D01*
X462295Y1359005D01*
Y1358739D01*
X462095Y1358605D01*
G01X476095Y1358872D02*
Y1366872D01*
X478495D01*
X479295Y1366472D01*
X479895Y1365539D01*
X480095Y1364472D01*
X479895Y1363405D01*
X479395Y1362605D01*
X478495Y1362205D01*
X476095D01*
G01X486095Y1366872D02*
Y1358872D01*
G01X483795Y1366872D02*
X488395D01*
G01X491995Y1358872D02*
Y1366872D01*
G01X496195D02*
Y1358872D01*
G01Y1362872D02*
X491995D01*
G01X510095Y1366872D02*
Y1358872D01*
G01X507795Y1366872D02*
X512395D01*
G01X518095Y1358872D02*
X517295Y1359005D01*
X516595Y1359539D01*
X515995Y1360339D01*
X515595Y1361272D01*
X515395Y1362339D01*
Y1363405D01*
X515595Y1364472D01*
X515995Y1365405D01*
X516595Y1366205D01*
X517295Y1366739D01*
X518095Y1366872D01*
X518895Y1366739D01*
X519595Y1366205D01*
X520195Y1365405D01*
X520595Y1364472D01*
X520795Y1363405D01*
Y1362339D01*
X520595Y1361272D01*
X520195Y1360339D01*
X519595Y1359539D01*
X518895Y1359005D01*
X518095Y1358872D01*
G01X524095Y1366872D02*
Y1358872D01*
X528095D01*
G01X536095D02*
X532095D01*
Y1366872D01*
X536095D01*
G01X534495Y1363005D02*
X532095D01*
G01X540095Y1358872D02*
Y1366872D01*
X542595D01*
X543395Y1366472D01*
X543895Y1365939D01*
X544095Y1364872D01*
X543895Y1363805D01*
X543295Y1363139D01*
X542595Y1362739D01*
X540095D01*
G01X542595D02*
X544095Y1358872D01*
G01X547595D02*
X550095Y1366872D01*
X552595Y1358872D01*
G01X551695Y1361672D02*
X548495D01*
G01X555795Y1358872D02*
Y1366872D01*
X560395Y1358872D01*
Y1366872D01*
G01X568295Y1366205D02*
X567695Y1366605D01*
X566995Y1366872D01*
X566195D01*
X565295Y1366472D01*
X564595Y1365805D01*
X564095Y1365005D01*
X563695Y1363672D01*
X563595Y1362472D01*
X563795Y1361272D01*
X564095Y1360472D01*
X564695Y1359672D01*
X565395Y1359139D01*
X566095Y1358872D01*
X566795D01*
X567495Y1359139D01*
X568095Y1359539D01*
X568595Y1360072D01*
G01X576095Y1358872D02*
X572095D01*
Y1366872D01*
X576095D01*
G01X574495Y1363005D02*
X572095D01*
G01X590095Y1358605D02*
X589895Y1358739D01*
Y1359005D01*
X590095Y1359139D01*
X590295Y1359005D01*
Y1358739D01*
X590095Y1358605D01*
G01Y1362205D02*
X589895Y1362339D01*
Y1362605D01*
X590095Y1362739D01*
X590295Y1362605D01*
Y1362339D01*
X590095Y1362205D01*
G01X604995Y1361539D02*
X607395D01*
G01X606095Y1363272D02*
Y1359805D01*
G01X612295Y1358605D02*
X615895Y1366872D01*
G01X620795Y1361539D02*
X623395D01*
G01X627895Y1360072D02*
X628495Y1359405D01*
X629195Y1359005D01*
X630095Y1358872D01*
X630995Y1359139D01*
X631695Y1359672D01*
X632195Y1360605D01*
X632295Y1361672D01*
X632095Y1362739D01*
X631595Y1363405D01*
X630895Y1363939D01*
X630195Y1364072D01*
X629495Y1363939D01*
X628595Y1363405D01*
X628895Y1366872D01*
X631595D01*
G01X637595Y1356205D02*
X636595Y1357539D01*
X636095Y1358872D01*
Y1364205D01*
X636595Y1365539D01*
X637595Y1366872D01*
G01X643495Y1358872D02*
Y1366872D01*
X646095Y1360205D01*
X648695Y1366872D01*
Y1358872D01*
G01X652895Y1366872D02*
X655295D01*
G01X654095D02*
Y1358872D01*
G01X652895D02*
X655295D01*
G01X660095Y1366872D02*
Y1358872D01*
X664095D01*
G01X670595Y1356205D02*
X671595Y1357539D01*
X672095Y1358872D01*
Y1364205D01*
X671595Y1365539D01*
X670595Y1366872D01*
G01X677895Y1357405D02*
X678295Y1359139D01*
G01X691795Y1358872D02*
Y1366872D01*
X696395Y1358872D01*
Y1366872D01*
G01X700095Y1358872D02*
Y1366872D01*
X702495D01*
X703295Y1366472D01*
X703895Y1365539D01*
X704095Y1364472D01*
X703895Y1363405D01*
X703395Y1362605D01*
X702495Y1362205D01*
X700095D01*
G01X710095Y1366872D02*
Y1358872D01*
G01X707795Y1366872D02*
X712395D01*
G01X715995Y1358872D02*
Y1366872D01*
G01X720195D02*
Y1358872D01*
G01Y1362872D02*
X715995D01*
G01X734095Y1366872D02*
Y1358872D01*
G01X731795Y1366872D02*
X736395D01*
G01X742095Y1358872D02*
X741295Y1359005D01*
X740595Y1359539D01*
X739995Y1360339D01*
X739595Y1361272D01*
X739395Y1362339D01*
Y1363405D01*
X739595Y1364472D01*
X739995Y1365405D01*
X740595Y1366205D01*
X741295Y1366739D01*
X742095Y1366872D01*
X742895Y1366739D01*
X743595Y1366205D01*
X744195Y1365405D01*
X744595Y1364472D01*
X744795Y1363405D01*
Y1362339D01*
X744595Y1361272D01*
X744195Y1360339D01*
X743595Y1359539D01*
X742895Y1359005D01*
X742095Y1358872D01*
G01X748095Y1366872D02*
Y1358872D01*
X752095D01*
G01X760095D02*
X756095D01*
Y1366872D01*
X760095D01*
G01X758495Y1363005D02*
X756095D01*
G01X764095Y1358872D02*
Y1366872D01*
X766595D01*
X767395Y1366472D01*
X767895Y1365939D01*
X768095Y1364872D01*
X767895Y1363805D01*
X767295Y1363139D01*
X766595Y1362739D01*
X764095D01*
G01X766595D02*
X768095Y1358872D01*
G01X771595D02*
X774095Y1366872D01*
X776595Y1358872D01*
G01X775695Y1361672D02*
X772495D01*
G01X779795Y1358872D02*
Y1366872D01*
X784395Y1358872D01*
Y1366872D01*
G01X792295Y1366205D02*
X791695Y1366605D01*
X790995Y1366872D01*
X790195D01*
X789295Y1366472D01*
X788595Y1365805D01*
X788095Y1365005D01*
X787695Y1363672D01*
X787595Y1362472D01*
X787795Y1361272D01*
X788095Y1360472D01*
X788695Y1359672D01*
X789395Y1359139D01*
X790095Y1358872D01*
X790795D01*
X791495Y1359139D01*
X792095Y1359539D01*
X792595Y1360072D01*
G01X800095Y1358872D02*
X796095D01*
Y1366872D01*
X800095D01*
G01X798495Y1363005D02*
X796095D01*
G01X806095Y1358605D02*
X805895Y1358739D01*
Y1359005D01*
X806095Y1359139D01*
X806295Y1359005D01*
Y1358739D01*
X806095Y1358605D01*
G01Y1362205D02*
X805895Y1362339D01*
Y1362605D01*
X806095Y1362739D01*
X806295Y1362605D01*
Y1362339D01*
X806095Y1362205D01*
G01X820995Y1361539D02*
X823395D01*
G01X822095Y1363272D02*
Y1359805D01*
G01X828295Y1358605D02*
X831895Y1366872D01*
G01X836795Y1361539D02*
X839395D01*
G01X847295Y1358872D02*
Y1366872D01*
X843595Y1361139D01*
X848595D01*
G01X853595Y1356205D02*
X852595Y1357539D01*
X852095Y1358872D01*
Y1364205D01*
X852595Y1365539D01*
X853595Y1366872D01*
G01X859495Y1358872D02*
Y1366872D01*
X862095Y1360205D01*
X864695Y1366872D01*
Y1358872D01*
G01X868895Y1366872D02*
X871295D01*
G01X870095D02*
Y1358872D01*
G01X868895D02*
X871295D01*
G01X876095Y1366872D02*
Y1358872D01*
X880095D01*
G01X886595Y1356205D02*
X887595Y1357539D01*
X888095Y1358872D01*
Y1364205D01*
X887595Y1365539D01*
X886595Y1366872D01*
G01X894095Y1358605D02*
X893895Y1358739D01*
Y1359005D01*
X894095Y1359139D01*
X894295Y1359005D01*
Y1358739D01*
X894095Y1358605D01*
G01X-1905Y1373872D02*
X-1205Y1374005D01*
X-405Y1374405D01*
X95Y1375072D01*
X295Y1376005D01*
X95Y1376938D01*
X-505Y1377739D01*
X-1405Y1378139D01*
X-2405D01*
X-3005Y1378405D01*
X-3505Y1379072D01*
X-3705Y1380005D01*
X-3405Y1380939D01*
X-2705Y1381605D01*
X-1905Y1381872D01*
X-1105Y1381605D01*
X-405Y1380939D01*
X-105Y1380005D01*
X-305Y1379072D01*
X-805Y1378405D01*
X-1405Y1378139D01*
X-2405D01*
X-3305Y1377739D01*
X-3905Y1376938D01*
X-4105Y1376005D01*
X-3905Y1375072D01*
X-3405Y1374405D01*
X-2605Y1374005D01*
X-1905Y1373872D01*
G01X6095Y1373605D02*
X5895Y1373739D01*
Y1374005D01*
X6095Y1374139D01*
X6295Y1374005D01*
Y1373739D01*
X6095Y1373605D01*
G01X11795Y1373872D02*
Y1381872D01*
X16395Y1373872D01*
Y1381872D01*
G01X22095Y1373872D02*
X21295Y1374005D01*
X20595Y1374539D01*
X19995Y1375339D01*
X19595Y1376272D01*
X19395Y1377339D01*
Y1378405D01*
X19595Y1379472D01*
X19995Y1380405D01*
X20595Y1381205D01*
X21295Y1381739D01*
X22095Y1381872D01*
X22895Y1381739D01*
X23595Y1381205D01*
X24195Y1380405D01*
X24595Y1379472D01*
X24795Y1378405D01*
Y1377339D01*
X24595Y1376272D01*
X24195Y1375339D01*
X23595Y1374539D01*
X22895Y1374005D01*
X22095Y1373872D01*
G01X30095Y1381872D02*
Y1373872D01*
G01X27795Y1381872D02*
X32395D01*
G01X43595Y1373872D02*
X46095Y1381872D01*
X48595Y1373872D01*
G01X47695Y1376672D02*
X44495D01*
G01X52095Y1381872D02*
Y1373872D01*
X56095D01*
G01X60095Y1381872D02*
Y1373872D01*
X64095D01*
G01X70095D02*
X69295Y1374005D01*
X68595Y1374539D01*
X67995Y1375339D01*
X67595Y1376272D01*
X67395Y1377339D01*
Y1378405D01*
X67595Y1379472D01*
X67995Y1380405D01*
X68595Y1381205D01*
X69295Y1381739D01*
X70095Y1381872D01*
X70895Y1381739D01*
X71595Y1381205D01*
X72195Y1380405D01*
X72595Y1379472D01*
X72795Y1378405D01*
Y1377339D01*
X72595Y1376272D01*
X72195Y1375339D01*
X71595Y1374539D01*
X70895Y1374005D01*
X70095Y1373872D01*
G01X75095Y1381872D02*
X76495Y1373872D01*
X78095Y1381872D01*
X79695Y1373872D01*
X81095Y1381872D01*
G01X94895Y1378139D02*
X95295Y1378539D01*
X95595Y1379205D01*
X95795Y1380139D01*
X95595Y1380939D01*
X95195Y1381472D01*
X94495Y1381872D01*
X91795D01*
Y1373872D01*
X95095D01*
X95795Y1374405D01*
X96195Y1375205D01*
X96395Y1376139D01*
X96195Y1377072D01*
X95595Y1377872D01*
X94895Y1378139D01*
X91795D01*
G01X100095Y1373872D02*
Y1381872D01*
X102595D01*
X103395Y1381472D01*
X103895Y1380939D01*
X104095Y1379872D01*
X103895Y1378805D01*
X103295Y1378139D01*
X102595Y1377739D01*
X100095D01*
G01X102595D02*
X104095Y1373872D01*
G01X112095D02*
X108095D01*
Y1381872D01*
X112095D01*
G01X110495Y1378005D02*
X108095D01*
G01X115595Y1373872D02*
X118095Y1381872D01*
X120595Y1373872D01*
G01X119695Y1376672D02*
X116495D01*
G01X123895Y1373872D02*
Y1381872D01*
G01X127695D02*
X123895Y1376938D01*
G01X128295Y1373872D02*
X125595Y1379205D01*
G01X134095Y1373872D02*
X133295Y1374005D01*
X132595Y1374539D01*
X131995Y1375339D01*
X131595Y1376272D01*
X131395Y1377339D01*
Y1378405D01*
X131595Y1379472D01*
X131995Y1380405D01*
X132595Y1381205D01*
X133295Y1381739D01*
X134095Y1381872D01*
X134895Y1381739D01*
X135595Y1381205D01*
X136195Y1380405D01*
X136595Y1379472D01*
X136795Y1378405D01*
Y1377339D01*
X136595Y1376272D01*
X136195Y1375339D01*
X135595Y1374539D01*
X134895Y1374005D01*
X134095Y1373872D01*
G01X139895Y1381872D02*
Y1376139D01*
X140295Y1374938D01*
X141095Y1374139D01*
X142095Y1373872D01*
X143095Y1374139D01*
X143895Y1374938D01*
X144295Y1376139D01*
Y1381872D01*
G01X150095D02*
Y1373872D01*
G01X147795Y1381872D02*
X152395D01*
G01X164195Y1373872D02*
Y1381872D01*
X167995D01*
G01X166595Y1378005D02*
X164195D01*
G01X174095Y1373872D02*
X173295Y1374005D01*
X172595Y1374539D01*
X171995Y1375339D01*
X171595Y1376272D01*
X171395Y1377339D01*
Y1378405D01*
X171595Y1379472D01*
X171995Y1380405D01*
X172595Y1381205D01*
X173295Y1381739D01*
X174095Y1381872D01*
X174895Y1381739D01*
X175595Y1381205D01*
X176195Y1380405D01*
X176595Y1379472D01*
X176795Y1378405D01*
Y1377339D01*
X176595Y1376272D01*
X176195Y1375339D01*
X175595Y1374539D01*
X174895Y1374005D01*
X174095Y1373872D01*
G01X180095D02*
Y1381872D01*
X182595D01*
X183395Y1381472D01*
X183895Y1380939D01*
X184095Y1379872D01*
X183895Y1378805D01*
X183295Y1378139D01*
X182595Y1377739D01*
X180095D01*
G01X182595D02*
X184095Y1373872D01*
G01X196095Y1381872D02*
Y1373872D01*
X200095D01*
G01X203595D02*
X206095Y1381872D01*
X208595Y1373872D01*
G01X207695Y1376672D02*
X204495D01*
G01X211995Y1374938D02*
X212795Y1374272D01*
X213695Y1373872D01*
X214495D01*
X215295Y1374272D01*
X215895Y1374938D01*
X216195Y1375872D01*
X215995Y1376805D01*
X215495Y1377605D01*
X214595Y1378139D01*
X213395Y1378405D01*
X212695Y1378939D01*
X212395Y1379872D01*
X212595Y1380805D01*
X213095Y1381472D01*
X213795Y1381872D01*
X214495D01*
X215195Y1381605D01*
X215795Y1380939D01*
G01X224095Y1373872D02*
X220095D01*
Y1381872D01*
X224095D01*
G01X222495Y1378005D02*
X220095D01*
G01X228095Y1373872D02*
Y1381872D01*
X230595D01*
X231395Y1381472D01*
X231895Y1380939D01*
X232095Y1379872D01*
X231895Y1378805D01*
X231295Y1378139D01*
X230595Y1377739D01*
X228095D01*
G01X230595D02*
X232095Y1373872D01*
G01X243595Y1381872D02*
X246095Y1373872D01*
X248595Y1381872D01*
G01X252895D02*
X255295D01*
G01X254095D02*
Y1373872D01*
G01X252895D02*
X255295D01*
G01X259595D02*
X262095Y1381872D01*
X264595Y1373872D01*
G01X263695Y1376672D02*
X260495D01*
G01X275995Y1373872D02*
Y1381872D01*
G01X280195D02*
Y1373872D01*
G01Y1377872D02*
X275995D01*
G01X286095Y1373872D02*
X285295Y1374005D01*
X284595Y1374539D01*
X283995Y1375339D01*
X283595Y1376272D01*
X283395Y1377339D01*
Y1378405D01*
X283595Y1379472D01*
X283995Y1380405D01*
X284595Y1381205D01*
X285295Y1381739D01*
X286095Y1381872D01*
X286895Y1381739D01*
X287595Y1381205D01*
X288195Y1380405D01*
X288595Y1379472D01*
X288795Y1378405D01*
Y1377339D01*
X288595Y1376272D01*
X288195Y1375339D01*
X287595Y1374539D01*
X286895Y1374005D01*
X286095Y1373872D01*
G01X292095Y1381872D02*
Y1373872D01*
X296095D01*
G01X304095D02*
X300095D01*
Y1381872D01*
X304095D01*
G01X302495Y1378005D02*
X300095D01*
G01X310095Y1373605D02*
X309895Y1373739D01*
Y1374005D01*
X310095Y1374139D01*
X310295Y1374005D01*
Y1373739D01*
X310095Y1373605D01*
G01X-2105Y1388872D02*
X-1905Y1390605D01*
X-1605Y1392072D01*
X-1205Y1393405D01*
X-705Y1394872D01*
X95Y1396872D01*
X-3905D01*
G01X6095Y1388605D02*
X5895Y1388739D01*
Y1389005D01*
X6095Y1389139D01*
X6295Y1389005D01*
Y1388739D01*
X6095Y1388605D01*
G01X12195Y1388872D02*
Y1396872D01*
X15995D01*
G01X14595Y1393005D02*
X12195D01*
G01X22095Y1388872D02*
X21295Y1389005D01*
X20595Y1389539D01*
X19995Y1390339D01*
X19595Y1391272D01*
X19395Y1392339D01*
Y1393405D01*
X19595Y1394472D01*
X19995Y1395405D01*
X20595Y1396205D01*
X21295Y1396739D01*
X22095Y1396872D01*
X22895Y1396739D01*
X23595Y1396205D01*
X24195Y1395405D01*
X24595Y1394472D01*
X24795Y1393405D01*
Y1392339D01*
X24595Y1391272D01*
X24195Y1390339D01*
X23595Y1389539D01*
X22895Y1389005D01*
X22095Y1388872D01*
G01X28095D02*
Y1396872D01*
X30595D01*
X31395Y1396472D01*
X31895Y1395939D01*
X32095Y1394872D01*
X31895Y1393805D01*
X31295Y1393139D01*
X30595Y1392739D01*
X28095D01*
G01X30595D02*
X32095Y1388872D01*
G01X46095D02*
Y1396872D01*
X44895Y1395272D01*
G01Y1388872D02*
X47295D01*
G01X54095Y1396872D02*
X53295Y1396605D01*
X52695Y1395939D01*
X52295Y1395139D01*
X51995Y1394072D01*
X51895Y1392872D01*
X51995Y1391672D01*
X52295Y1390605D01*
X52695Y1389805D01*
X53295Y1389139D01*
X54095Y1388872D01*
X54895Y1389139D01*
X55495Y1389805D01*
X55895Y1390605D01*
X56195Y1391672D01*
X56295Y1392872D01*
X56195Y1394072D01*
X55895Y1395139D01*
X55495Y1395939D01*
X54895Y1396605D01*
X54095Y1396872D01*
G01X59495Y1388872D02*
Y1396872D01*
X62095Y1390205D01*
X64695Y1396872D01*
Y1388872D01*
G01X68895Y1396872D02*
X71295D01*
G01X70095D02*
Y1388872D01*
G01X68895D02*
X71295D01*
G01X76095Y1396872D02*
Y1388872D01*
X80095D01*
G01X83995Y1389938D02*
X84795Y1389272D01*
X85695Y1388872D01*
X86495D01*
X87295Y1389272D01*
X87895Y1389938D01*
X88195Y1390872D01*
X87995Y1391805D01*
X87495Y1392605D01*
X86595Y1393139D01*
X85395Y1393405D01*
X84695Y1393939D01*
X84395Y1394872D01*
X84595Y1395805D01*
X85095Y1396472D01*
X85795Y1396872D01*
X86495D01*
X87195Y1396605D01*
X87795Y1395939D01*
G01X99595Y1396872D02*
X102095Y1388872D01*
X104595Y1396872D01*
G01X108895D02*
X111295D01*
G01X110095D02*
Y1388872D01*
G01X108895D02*
X111295D01*
G01X115595D02*
X118095Y1396872D01*
X120595Y1388872D01*
G01X119695Y1391672D02*
X116495D01*
G01X123995Y1389938D02*
X124795Y1389272D01*
X125695Y1388872D01*
X126495D01*
X127295Y1389272D01*
X127895Y1389938D01*
X128195Y1390872D01*
X127995Y1391805D01*
X127495Y1392605D01*
X126595Y1393139D01*
X125395Y1393405D01*
X124695Y1393939D01*
X124395Y1394872D01*
X124595Y1395805D01*
X125095Y1396472D01*
X125795Y1396872D01*
X126495D01*
X127195Y1396605D01*
X127795Y1395939D01*
G01X139895Y1396872D02*
Y1391139D01*
X140295Y1389938D01*
X141095Y1389139D01*
X142095Y1388872D01*
X143095Y1389139D01*
X143895Y1389938D01*
X144295Y1391139D01*
Y1396872D01*
G01X147995Y1389938D02*
X148795Y1389272D01*
X149695Y1388872D01*
X150495D01*
X151295Y1389272D01*
X151895Y1389938D01*
X152195Y1390872D01*
X151995Y1391805D01*
X151495Y1392605D01*
X150595Y1393139D01*
X149395Y1393405D01*
X148695Y1393939D01*
X148395Y1394872D01*
X148595Y1395805D01*
X149095Y1396472D01*
X149795Y1396872D01*
X150495D01*
X151195Y1396605D01*
X151795Y1395939D01*
G01X160095Y1388872D02*
X156095D01*
Y1396872D01*
X160095D01*
G01X158495Y1393005D02*
X156095D01*
G01X172395Y1389805D02*
X173095Y1389139D01*
X173895Y1388872D01*
X174695Y1389139D01*
X175395Y1389938D01*
X175895Y1391139D01*
X176095Y1392339D01*
Y1393805D01*
X175895Y1395005D01*
X175395Y1396072D01*
X174795Y1396605D01*
X174095Y1396872D01*
X173295Y1396605D01*
X172695Y1396072D01*
X172295Y1395272D01*
X172095Y1394205D01*
X172295Y1393272D01*
X172795Y1392339D01*
X173395Y1391805D01*
X174095Y1391672D01*
X174895Y1391938D01*
X175495Y1392605D01*
X176095Y1393805D01*
G01X182095Y1388605D02*
X181895Y1388739D01*
Y1389005D01*
X182095Y1389139D01*
X182295Y1389005D01*
Y1388739D01*
X182095Y1388605D01*
G01X190095Y1388872D02*
X190795Y1389005D01*
X191595Y1389405D01*
X192095Y1390072D01*
X192295Y1391005D01*
X192095Y1391938D01*
X191495Y1392739D01*
X190595Y1393139D01*
X189595D01*
X188995Y1393405D01*
X188495Y1394072D01*
X188295Y1395005D01*
X188595Y1395939D01*
X189295Y1396605D01*
X190095Y1396872D01*
X190895Y1396605D01*
X191595Y1395939D01*
X191895Y1395005D01*
X191695Y1394072D01*
X191195Y1393405D01*
X190595Y1393139D01*
X189595D01*
X188695Y1392739D01*
X188095Y1391938D01*
X187895Y1391005D01*
X188095Y1390072D01*
X188595Y1389405D01*
X189395Y1389005D01*
X190095Y1388872D01*
G01X195495D02*
Y1396872D01*
X198095Y1390205D01*
X200695Y1396872D01*
Y1388872D01*
G01X204895Y1396872D02*
X207295D01*
G01X206095D02*
Y1388872D01*
G01X204895D02*
X207295D01*
G01X212095Y1396872D02*
Y1388872D01*
X216095D01*
G01X219995Y1389938D02*
X220795Y1389272D01*
X221695Y1388872D01*
X222495D01*
X223295Y1389272D01*
X223895Y1389938D01*
X224195Y1390872D01*
X223995Y1391805D01*
X223495Y1392605D01*
X222595Y1393139D01*
X221395Y1393405D01*
X220695Y1393939D01*
X220395Y1394872D01*
X220595Y1395805D01*
X221095Y1396472D01*
X221795Y1396872D01*
X222495D01*
X223195Y1396605D01*
X223795Y1395939D01*
G01X235895Y1388872D02*
Y1396872D01*
X237895D01*
X238695Y1396472D01*
X239295Y1395939D01*
X239795Y1395139D01*
X240195Y1394205D01*
X240295Y1392872D01*
X240195Y1391539D01*
X239795Y1390605D01*
X239295Y1389805D01*
X238695Y1389272D01*
X237895Y1388872D01*
X235895D01*
G01X244095D02*
Y1396872D01*
X246595D01*
X247395Y1396472D01*
X247895Y1395939D01*
X248095Y1394872D01*
X247895Y1393805D01*
X247295Y1393139D01*
X246595Y1392739D01*
X244095D01*
G01X246595D02*
X248095Y1388872D01*
G01X252895Y1396872D02*
X255295D01*
G01X254095D02*
Y1388872D01*
G01X252895D02*
X255295D01*
G01X260095Y1396872D02*
Y1388872D01*
X264095D01*
G01X268095Y1396872D02*
Y1388872D01*
X272095D01*
G01X286895Y1393139D02*
X287295Y1393539D01*
X287595Y1394205D01*
X287795Y1395139D01*
X287595Y1395939D01*
X287195Y1396472D01*
X286495Y1396872D01*
X283795D01*
Y1388872D01*
X287095D01*
X287795Y1389405D01*
X288195Y1390205D01*
X288395Y1391139D01*
X288195Y1392072D01*
X287595Y1392872D01*
X286895Y1393139D01*
X283795D01*
G01X292895Y1396872D02*
X295295D01*
G01X294095D02*
Y1388872D01*
G01X292895D02*
X295295D01*
G01X302095Y1396872D02*
Y1388872D01*
G01X299795Y1396872D02*
X304395D01*
G01X310095Y1388605D02*
X309895Y1388739D01*
Y1389005D01*
X310095Y1389139D01*
X310295Y1389005D01*
Y1388739D01*
X310095Y1388605D01*
G01X324195Y1388872D02*
Y1396872D01*
X327995D01*
G01X326595Y1393005D02*
X324195D01*
G01X334095Y1388872D02*
X333295Y1389005D01*
X332595Y1389539D01*
X331995Y1390339D01*
X331595Y1391272D01*
X331395Y1392339D01*
Y1393405D01*
X331595Y1394472D01*
X331995Y1395405D01*
X332595Y1396205D01*
X333295Y1396739D01*
X334095Y1396872D01*
X334895Y1396739D01*
X335595Y1396205D01*
X336195Y1395405D01*
X336595Y1394472D01*
X336795Y1393405D01*
Y1392339D01*
X336595Y1391272D01*
X336195Y1390339D01*
X335595Y1389539D01*
X334895Y1389005D01*
X334095Y1388872D01*
G01X340095D02*
Y1396872D01*
X342595D01*
X343395Y1396472D01*
X343895Y1395939D01*
X344095Y1394872D01*
X343895Y1393805D01*
X343295Y1393139D01*
X342595Y1392739D01*
X340095D01*
G01X342595D02*
X344095Y1388872D01*
G01X358095D02*
X358795Y1389005D01*
X359595Y1389405D01*
X360095Y1390072D01*
X360295Y1391005D01*
X360095Y1391938D01*
X359495Y1392739D01*
X358595Y1393139D01*
X357595D01*
X356995Y1393405D01*
X356495Y1394072D01*
X356295Y1395005D01*
X356595Y1395939D01*
X357295Y1396605D01*
X358095Y1396872D01*
X358895Y1396605D01*
X359595Y1395939D01*
X359895Y1395005D01*
X359695Y1394072D01*
X359195Y1393405D01*
X358595Y1393139D01*
X357595D01*
X356695Y1392739D01*
X356095Y1391938D01*
X355895Y1391005D01*
X356095Y1390072D01*
X356595Y1389405D01*
X357395Y1389005D01*
X358095Y1388872D01*
G01X363495D02*
Y1396872D01*
X366095Y1390205D01*
X368695Y1396872D01*
Y1388872D01*
G01X372895Y1396872D02*
X375295D01*
G01X374095D02*
Y1388872D01*
G01X372895D02*
X375295D01*
G01X380095Y1396872D02*
Y1388872D01*
X384095D01*
G01X387995Y1389938D02*
X388795Y1389272D01*
X389695Y1388872D01*
X390495D01*
X391295Y1389272D01*
X391895Y1389938D01*
X392195Y1390872D01*
X391995Y1391805D01*
X391495Y1392605D01*
X390595Y1393139D01*
X389395Y1393405D01*
X388695Y1393939D01*
X388395Y1394872D01*
X388595Y1395805D01*
X389095Y1396472D01*
X389795Y1396872D01*
X390495D01*
X391195Y1396605D01*
X391795Y1395939D01*
G01X403595Y1396872D02*
X406095Y1388872D01*
X408595Y1396872D01*
G01X412895D02*
X415295D01*
G01X414095D02*
Y1388872D01*
G01X412895D02*
X415295D01*
G01X419595D02*
X422095Y1396872D01*
X424595Y1388872D01*
G01X423695Y1391672D02*
X420495D01*
G01X427995Y1389938D02*
X428795Y1389272D01*
X429695Y1388872D01*
X430495D01*
X431295Y1389272D01*
X431895Y1389938D01*
X432195Y1390872D01*
X431995Y1391805D01*
X431495Y1392605D01*
X430595Y1393139D01*
X429395Y1393405D01*
X428695Y1393939D01*
X428395Y1394872D01*
X428595Y1395805D01*
X429095Y1396472D01*
X429795Y1396872D01*
X430495D01*
X431195Y1396605D01*
X431795Y1395939D01*
G01X443895Y1396872D02*
Y1391139D01*
X444295Y1389938D01*
X445095Y1389139D01*
X446095Y1388872D01*
X447095Y1389139D01*
X447895Y1389938D01*
X448295Y1391139D01*
Y1396872D01*
G01X451995Y1389938D02*
X452795Y1389272D01*
X453695Y1388872D01*
X454495D01*
X455295Y1389272D01*
X455895Y1389938D01*
X456195Y1390872D01*
X455995Y1391805D01*
X455495Y1392605D01*
X454595Y1393139D01*
X453395Y1393405D01*
X452695Y1393939D01*
X452395Y1394872D01*
X452595Y1395805D01*
X453095Y1396472D01*
X453795Y1396872D01*
X454495D01*
X455195Y1396605D01*
X455795Y1395939D01*
G01X464095Y1388872D02*
X460095D01*
Y1396872D01*
X464095D01*
G01X462495Y1393005D02*
X460095D01*
G01X477895Y1388872D02*
X478095Y1390605D01*
X478395Y1392072D01*
X478795Y1393405D01*
X479295Y1394872D01*
X480095Y1396872D01*
X476095D01*
G01X486095Y1388605D02*
X485895Y1388739D01*
Y1389005D01*
X486095Y1389139D01*
X486295Y1389005D01*
Y1388739D01*
X486095Y1388605D01*
G01X492395Y1389805D02*
X493095Y1389139D01*
X493895Y1388872D01*
X494695Y1389139D01*
X495395Y1389938D01*
X495895Y1391139D01*
X496095Y1392339D01*
Y1393805D01*
X495895Y1395005D01*
X495395Y1396072D01*
X494795Y1396605D01*
X494095Y1396872D01*
X493295Y1396605D01*
X492695Y1396072D01*
X492295Y1395272D01*
X492095Y1394205D01*
X492295Y1393272D01*
X492795Y1392339D01*
X493395Y1391805D01*
X494095Y1391672D01*
X494895Y1391938D01*
X495495Y1392605D01*
X496095Y1393805D01*
G01X499495Y1388872D02*
Y1396872D01*
X502095Y1390205D01*
X504695Y1396872D01*
Y1388872D01*
G01X508895Y1396872D02*
X511295D01*
G01X510095D02*
Y1388872D01*
G01X508895D02*
X511295D01*
G01X516095Y1396872D02*
Y1388872D01*
X520095D01*
G01X523995Y1389938D02*
X524795Y1389272D01*
X525695Y1388872D01*
X526495D01*
X527295Y1389272D01*
X527895Y1389938D01*
X528195Y1390872D01*
X527995Y1391805D01*
X527495Y1392605D01*
X526595Y1393139D01*
X525395Y1393405D01*
X524695Y1393939D01*
X524395Y1394872D01*
X524595Y1395805D01*
X525095Y1396472D01*
X525795Y1396872D01*
X526495D01*
X527195Y1396605D01*
X527795Y1395939D01*
G01X539895Y1388872D02*
Y1396872D01*
X541895D01*
X542695Y1396472D01*
X543295Y1395939D01*
X543795Y1395139D01*
X544195Y1394205D01*
X544295Y1392872D01*
X544195Y1391539D01*
X543795Y1390605D01*
X543295Y1389805D01*
X542695Y1389272D01*
X541895Y1388872D01*
X539895D01*
G01X548095D02*
Y1396872D01*
X550595D01*
X551395Y1396472D01*
X551895Y1395939D01*
X552095Y1394872D01*
X551895Y1393805D01*
X551295Y1393139D01*
X550595Y1392739D01*
X548095D01*
G01X550595D02*
X552095Y1388872D01*
G01X556895Y1396872D02*
X559295D01*
G01X558095D02*
Y1388872D01*
G01X556895D02*
X559295D01*
G01X564095Y1396872D02*
Y1388872D01*
X568095D01*
G01X572095Y1396872D02*
Y1388872D01*
X576095D01*
G01X590895Y1393139D02*
X591295Y1393539D01*
X591595Y1394205D01*
X591795Y1395139D01*
X591595Y1395939D01*
X591195Y1396472D01*
X590495Y1396872D01*
X587795D01*
Y1388872D01*
X591095D01*
X591795Y1389405D01*
X592195Y1390205D01*
X592395Y1391139D01*
X592195Y1392072D01*
X591595Y1392872D01*
X590895Y1393139D01*
X587795D01*
G01X596895Y1396872D02*
X599295D01*
G01X598095D02*
Y1388872D01*
G01X596895D02*
X599295D01*
G01X606095Y1396872D02*
Y1388872D01*
G01X603795Y1396872D02*
X608395D01*
G01X614095Y1388605D02*
X613895Y1388739D01*
Y1389005D01*
X614095Y1389139D01*
X614295Y1389005D01*
Y1388739D01*
X614095Y1388605D01*
G01X620195Y1388872D02*
Y1396872D01*
X623995D01*
G01X622595Y1393005D02*
X620195D01*
G01X630095Y1388872D02*
X629295Y1389005D01*
X628595Y1389539D01*
X627995Y1390339D01*
X627595Y1391272D01*
X627395Y1392339D01*
Y1393405D01*
X627595Y1394472D01*
X627995Y1395405D01*
X628595Y1396205D01*
X629295Y1396739D01*
X630095Y1396872D01*
X630895Y1396739D01*
X631595Y1396205D01*
X632195Y1395405D01*
X632595Y1394472D01*
X632795Y1393405D01*
Y1392339D01*
X632595Y1391272D01*
X632195Y1390339D01*
X631595Y1389539D01*
X630895Y1389005D01*
X630095Y1388872D01*
G01X636095D02*
Y1396872D01*
X638595D01*
X639395Y1396472D01*
X639895Y1395939D01*
X640095Y1394872D01*
X639895Y1393805D01*
X639295Y1393139D01*
X638595Y1392739D01*
X636095D01*
G01X638595D02*
X640095Y1388872D01*
G01X652195Y1395539D02*
X652795Y1396339D01*
X653495Y1396739D01*
X654295Y1396872D01*
X655295Y1396605D01*
X655995Y1395939D01*
X656195Y1395139D01*
X656095Y1394338D01*
X655695Y1393672D01*
X653695Y1392339D01*
X652795Y1391405D01*
X652195Y1390072D01*
X651995Y1388872D01*
X656195D01*
G01X662095Y1396872D02*
X661295Y1396605D01*
X660695Y1395939D01*
X660295Y1395139D01*
X659995Y1394072D01*
X659895Y1392872D01*
X659995Y1391672D01*
X660295Y1390605D01*
X660695Y1389805D01*
X661295Y1389139D01*
X662095Y1388872D01*
X662895Y1389139D01*
X663495Y1389805D01*
X663895Y1390605D01*
X664195Y1391672D01*
X664295Y1392872D01*
X664195Y1394072D01*
X663895Y1395139D01*
X663495Y1395939D01*
X662895Y1396605D01*
X662095Y1396872D01*
G01X667495Y1388872D02*
Y1396872D01*
X670095Y1390205D01*
X672695Y1396872D01*
Y1388872D01*
G01X676895Y1396872D02*
X679295D01*
G01X678095D02*
Y1388872D01*
G01X676895D02*
X679295D01*
G01X684095Y1396872D02*
Y1388872D01*
X688095D01*
G01X691995Y1389938D02*
X692795Y1389272D01*
X693695Y1388872D01*
X694495D01*
X695295Y1389272D01*
X695895Y1389938D01*
X696195Y1390872D01*
X695995Y1391805D01*
X695495Y1392605D01*
X694595Y1393139D01*
X693395Y1393405D01*
X692695Y1393939D01*
X692395Y1394872D01*
X692595Y1395805D01*
X693095Y1396472D01*
X693795Y1396872D01*
X694495D01*
X695195Y1396605D01*
X695795Y1395939D01*
G01X707595Y1396872D02*
X710095Y1388872D01*
X712595Y1396872D01*
G01X716895D02*
X719295D01*
G01X718095D02*
Y1388872D01*
G01X716895D02*
X719295D01*
G01X723595D02*
X726095Y1396872D01*
X728595Y1388872D01*
G01X727695Y1391672D02*
X724495D01*
G01X731995Y1389938D02*
X732795Y1389272D01*
X733695Y1388872D01*
X734495D01*
X735295Y1389272D01*
X735895Y1389938D01*
X736195Y1390872D01*
X735995Y1391805D01*
X735495Y1392605D01*
X734595Y1393139D01*
X733395Y1393405D01*
X732695Y1393939D01*
X732395Y1394872D01*
X732595Y1395805D01*
X733095Y1396472D01*
X733795Y1396872D01*
X734495D01*
X735195Y1396605D01*
X735795Y1395939D01*
G01X747895Y1396872D02*
Y1391139D01*
X748295Y1389938D01*
X749095Y1389139D01*
X750095Y1388872D01*
X751095Y1389139D01*
X751895Y1389938D01*
X752295Y1391139D01*
Y1396872D01*
G01X755995Y1389938D02*
X756795Y1389272D01*
X757695Y1388872D01*
X758495D01*
X759295Y1389272D01*
X759895Y1389938D01*
X760195Y1390872D01*
X759995Y1391805D01*
X759495Y1392605D01*
X758595Y1393139D01*
X757395Y1393405D01*
X756695Y1393939D01*
X756395Y1394872D01*
X756595Y1395805D01*
X757095Y1396472D01*
X757795Y1396872D01*
X758495D01*
X759195Y1396605D01*
X759795Y1395939D01*
G01X768095Y1388872D02*
X764095D01*
Y1396872D01*
X768095D01*
G01X766495Y1393005D02*
X764095D01*
G01X782095Y1388872D02*
Y1396872D01*
X780895Y1395272D01*
G01Y1388872D02*
X783295D01*
G01X788395Y1389805D02*
X789095Y1389139D01*
X789895Y1388872D01*
X790695Y1389139D01*
X791395Y1389938D01*
X791895Y1391139D01*
X792095Y1392339D01*
Y1393805D01*
X791895Y1395005D01*
X791395Y1396072D01*
X790795Y1396605D01*
X790095Y1396872D01*
X789295Y1396605D01*
X788695Y1396072D01*
X788295Y1395272D01*
X788095Y1394205D01*
X788295Y1393272D01*
X788795Y1392339D01*
X789395Y1391805D01*
X790095Y1391672D01*
X790895Y1391938D01*
X791495Y1392605D01*
X792095Y1393805D01*
G01X798095Y1388605D02*
X797895Y1388739D01*
Y1389005D01*
X798095Y1389139D01*
X798295Y1389005D01*
Y1388739D01*
X798095Y1388605D01*
G01X805895Y1388872D02*
X806095Y1390605D01*
X806395Y1392072D01*
X806795Y1393405D01*
X807295Y1394872D01*
X808095Y1396872D01*
X804095D01*
G01X811495Y1388872D02*
Y1396872D01*
X814095Y1390205D01*
X816695Y1396872D01*
Y1388872D01*
G01X820895Y1396872D02*
X823295D01*
G01X822095D02*
Y1388872D01*
G01X820895D02*
X823295D01*
G01X828095Y1396872D02*
Y1388872D01*
X832095D01*
G01X835995Y1389938D02*
X836795Y1389272D01*
X837695Y1388872D01*
X838495D01*
X839295Y1389272D01*
X839895Y1389938D01*
X840195Y1390872D01*
X839995Y1391805D01*
X839495Y1392605D01*
X838595Y1393139D01*
X837395Y1393405D01*
X836695Y1393939D01*
X836395Y1394872D01*
X836595Y1395805D01*
X837095Y1396472D01*
X837795Y1396872D01*
X838495D01*
X839195Y1396605D01*
X839795Y1395939D01*
G01X851895Y1388872D02*
Y1396872D01*
X853895D01*
X854695Y1396472D01*
X855295Y1395939D01*
X855795Y1395139D01*
X856195Y1394205D01*
X856295Y1392872D01*
X856195Y1391539D01*
X855795Y1390605D01*
X855295Y1389805D01*
X854695Y1389272D01*
X853895Y1388872D01*
X851895D01*
G01X860095D02*
Y1396872D01*
X862595D01*
X863395Y1396472D01*
X863895Y1395939D01*
X864095Y1394872D01*
X863895Y1393805D01*
X863295Y1393139D01*
X862595Y1392739D01*
X860095D01*
G01X862595D02*
X864095Y1388872D01*
G01X868895Y1396872D02*
X871295D01*
G01X870095D02*
Y1388872D01*
G01X868895D02*
X871295D01*
G01X876095Y1396872D02*
Y1388872D01*
X880095D01*
G01X884095Y1396872D02*
Y1388872D01*
X888095D01*
G01X902895Y1393139D02*
X903295Y1393539D01*
X903595Y1394205D01*
X903795Y1395139D01*
X903595Y1395939D01*
X903195Y1396472D01*
X902495Y1396872D01*
X899795D01*
Y1388872D01*
X903095D01*
X903795Y1389405D01*
X904195Y1390205D01*
X904395Y1391139D01*
X904195Y1392072D01*
X903595Y1392872D01*
X902895Y1393139D01*
X899795D01*
G01X908895Y1396872D02*
X911295D01*
G01X910095D02*
Y1388872D01*
G01X908895D02*
X911295D01*
G01X918095Y1396872D02*
Y1388872D01*
G01X915795Y1396872D02*
X920395D01*
G01X926095Y1388605D02*
X925895Y1388739D01*
Y1389005D01*
X926095Y1389139D01*
X926295Y1389005D01*
Y1388739D01*
X926095Y1388605D01*
G01X-3805Y1407205D02*
X-3105Y1408139D01*
X-2505Y1408672D01*
X-1705Y1408939D01*
X-1005Y1408672D01*
X-505Y1408139D01*
X-105Y1407339D01*
X-5Y1406405D01*
X-105Y1405605D01*
X-505Y1404805D01*
X-1105Y1404139D01*
X-1805Y1403872D01*
X-2605Y1404139D01*
X-3305Y1404938D01*
X-3705Y1406139D01*
X-3805Y1407472D01*
X-3605Y1409205D01*
X-3305Y1410139D01*
X-2805Y1411072D01*
X-2105Y1411739D01*
X-1405Y1411872D01*
X-705Y1411605D01*
X-205Y1410939D01*
G01X6095Y1403605D02*
X5895Y1403739D01*
Y1404005D01*
X6095Y1404139D01*
X6295Y1404005D01*
Y1403739D01*
X6095Y1403605D01*
G01X12195Y1410539D02*
X12795Y1411339D01*
X13495Y1411739D01*
X14295Y1411872D01*
X15295Y1411605D01*
X15995Y1410939D01*
X16195Y1410139D01*
X16095Y1409338D01*
X15695Y1408672D01*
X13695Y1407339D01*
X12795Y1406405D01*
X12195Y1405072D01*
X11995Y1403872D01*
X16195D01*
G01X30095D02*
X29295Y1404005D01*
X28595Y1404539D01*
X27995Y1405339D01*
X27595Y1406272D01*
X27395Y1407339D01*
Y1408405D01*
X27595Y1409472D01*
X27995Y1410405D01*
X28595Y1411205D01*
X29295Y1411739D01*
X30095Y1411872D01*
X30895Y1411739D01*
X31595Y1411205D01*
X32195Y1410405D01*
X32595Y1409472D01*
X32795Y1408405D01*
Y1407339D01*
X32595Y1406272D01*
X32195Y1405339D01*
X31595Y1404539D01*
X30895Y1404005D01*
X30095Y1403872D01*
G01X35895Y1411872D02*
Y1406139D01*
X36295Y1404938D01*
X37095Y1404139D01*
X38095Y1403872D01*
X39095Y1404139D01*
X39895Y1404938D01*
X40295Y1406139D01*
Y1411872D01*
G01X46095D02*
Y1403872D01*
G01X43795Y1411872D02*
X48395D01*
G01X51995Y1404938D02*
X52795Y1404272D01*
X53695Y1403872D01*
X54495D01*
X55295Y1404272D01*
X55895Y1404938D01*
X56195Y1405872D01*
X55995Y1406805D01*
X55495Y1407605D01*
X54595Y1408139D01*
X53395Y1408405D01*
X52695Y1408939D01*
X52395Y1409872D01*
X52595Y1410805D01*
X53095Y1411472D01*
X53795Y1411872D01*
X54495D01*
X55195Y1411605D01*
X55795Y1410939D01*
G01X60895Y1411872D02*
X63295D01*
G01X62095D02*
Y1403872D01*
G01X60895D02*
X63295D01*
G01X67895D02*
Y1411872D01*
X69895D01*
X70695Y1411472D01*
X71295Y1410939D01*
X71795Y1410139D01*
X72195Y1409205D01*
X72295Y1407872D01*
X72195Y1406539D01*
X71795Y1405605D01*
X71295Y1404805D01*
X70695Y1404272D01*
X69895Y1403872D01*
X67895D01*
G01X80095D02*
X76095D01*
Y1411872D01*
X80095D01*
G01X78495Y1408005D02*
X76095D01*
G01X94895Y1408139D02*
X95295Y1408539D01*
X95595Y1409205D01*
X95795Y1410139D01*
X95595Y1410939D01*
X95195Y1411472D01*
X94495Y1411872D01*
X91795D01*
Y1403872D01*
X95095D01*
X95795Y1404405D01*
X96195Y1405205D01*
X96395Y1406139D01*
X96195Y1407072D01*
X95595Y1407872D01*
X94895Y1408139D01*
X91795D01*
G01X102095Y1403872D02*
X101295Y1404005D01*
X100595Y1404539D01*
X99995Y1405339D01*
X99595Y1406272D01*
X99395Y1407339D01*
Y1408405D01*
X99595Y1409472D01*
X99995Y1410405D01*
X100595Y1411205D01*
X101295Y1411739D01*
X102095Y1411872D01*
X102895Y1411739D01*
X103595Y1411205D01*
X104195Y1410405D01*
X104595Y1409472D01*
X104795Y1408405D01*
Y1407339D01*
X104595Y1406272D01*
X104195Y1405339D01*
X103595Y1404539D01*
X102895Y1404005D01*
X102095Y1403872D01*
G01X107595D02*
X110095Y1411872D01*
X112595Y1403872D01*
G01X111695Y1406672D02*
X108495D01*
G01X116095Y1403872D02*
Y1411872D01*
X118595D01*
X119395Y1411472D01*
X119895Y1410939D01*
X120095Y1409872D01*
X119895Y1408805D01*
X119295Y1408139D01*
X118595Y1407739D01*
X116095D01*
G01X118595D02*
X120095Y1403872D01*
G01X123895D02*
Y1411872D01*
X125895D01*
X126695Y1411472D01*
X127295Y1410939D01*
X127795Y1410139D01*
X128195Y1409205D01*
X128295Y1407872D01*
X128195Y1406539D01*
X127795Y1405605D01*
X127295Y1404805D01*
X126695Y1404272D01*
X125895Y1403872D01*
X123895D01*
G01X142095D02*
X141295Y1404005D01*
X140595Y1404539D01*
X139995Y1405339D01*
X139595Y1406272D01*
X139395Y1407339D01*
Y1408405D01*
X139595Y1409472D01*
X139995Y1410405D01*
X140595Y1411205D01*
X141295Y1411739D01*
X142095Y1411872D01*
X142895Y1411739D01*
X143595Y1411205D01*
X144195Y1410405D01*
X144595Y1409472D01*
X144795Y1408405D01*
Y1407339D01*
X144595Y1406272D01*
X144195Y1405339D01*
X143595Y1404539D01*
X142895Y1404005D01*
X142095Y1403872D01*
G01X147895Y1411872D02*
Y1406139D01*
X148295Y1404938D01*
X149095Y1404139D01*
X150095Y1403872D01*
X151095Y1404139D01*
X151895Y1404938D01*
X152295Y1406139D01*
Y1411872D01*
G01X158095D02*
Y1403872D01*
G01X155795Y1411872D02*
X160395D01*
G01X164095D02*
Y1403872D01*
X168095D01*
G01X172895Y1411872D02*
X175295D01*
G01X174095D02*
Y1403872D01*
G01X172895D02*
X175295D01*
G01X179795D02*
Y1411872D01*
X184395Y1403872D01*
Y1411872D01*
G01X192095Y1403872D02*
X188095D01*
Y1411872D01*
X192095D01*
G01X190495Y1408005D02*
X188095D01*
G01X204195Y1403872D02*
Y1411872D01*
X207995D01*
G01X206595Y1408005D02*
X204195D01*
G01X214095Y1403872D02*
X213295Y1404005D01*
X212595Y1404539D01*
X211995Y1405339D01*
X211595Y1406272D01*
X211395Y1407339D01*
Y1408405D01*
X211595Y1409472D01*
X211995Y1410405D01*
X212595Y1411205D01*
X213295Y1411739D01*
X214095Y1411872D01*
X214895Y1411739D01*
X215595Y1411205D01*
X216195Y1410405D01*
X216595Y1409472D01*
X216795Y1408405D01*
Y1407339D01*
X216595Y1406272D01*
X216195Y1405339D01*
X215595Y1404539D01*
X214895Y1404005D01*
X214095Y1403872D01*
G01X220095Y1411872D02*
Y1403872D01*
X224095D01*
G01X228095Y1411872D02*
Y1403872D01*
X232095D01*
G01X238095D02*
X237295Y1404005D01*
X236595Y1404539D01*
X235995Y1405339D01*
X235595Y1406272D01*
X235395Y1407339D01*
Y1408405D01*
X235595Y1409472D01*
X235995Y1410405D01*
X236595Y1411205D01*
X237295Y1411739D01*
X238095Y1411872D01*
X238895Y1411739D01*
X239595Y1411205D01*
X240195Y1410405D01*
X240595Y1409472D01*
X240795Y1408405D01*
Y1407339D01*
X240595Y1406272D01*
X240195Y1405339D01*
X239595Y1404539D01*
X238895Y1404005D01*
X238095Y1403872D01*
G01X243095Y1411872D02*
X244495Y1403872D01*
X246095Y1411872D01*
X247695Y1403872D01*
X249095Y1411872D01*
G01X260095Y1403872D02*
Y1411872D01*
X262495D01*
X263295Y1411472D01*
X263895Y1410539D01*
X264095Y1409472D01*
X263895Y1408405D01*
X263395Y1407605D01*
X262495Y1407205D01*
X260095D01*
G01X272295Y1411205D02*
X271695Y1411605D01*
X270995Y1411872D01*
X270195D01*
X269295Y1411472D01*
X268595Y1410805D01*
X268095Y1410005D01*
X267695Y1408672D01*
X267595Y1407472D01*
X267795Y1406272D01*
X268095Y1405472D01*
X268695Y1404672D01*
X269395Y1404139D01*
X270095Y1403872D01*
X270795D01*
X271495Y1404139D01*
X272095Y1404539D01*
X272595Y1405072D01*
G01X278895Y1408139D02*
X279295Y1408539D01*
X279595Y1409205D01*
X279795Y1410139D01*
X279595Y1410939D01*
X279195Y1411472D01*
X278495Y1411872D01*
X275795D01*
Y1403872D01*
X279095D01*
X279795Y1404405D01*
X280195Y1405205D01*
X280395Y1406139D01*
X280195Y1407072D01*
X279595Y1407872D01*
X278895Y1408139D01*
X275795D01*
G01X291995Y1404938D02*
X292795Y1404272D01*
X293695Y1403872D01*
X294495D01*
X295295Y1404272D01*
X295895Y1404938D01*
X296195Y1405872D01*
X295995Y1406805D01*
X295495Y1407605D01*
X294595Y1408139D01*
X293395Y1408405D01*
X292695Y1408939D01*
X292395Y1409872D01*
X292595Y1410805D01*
X293095Y1411472D01*
X293795Y1411872D01*
X294495D01*
X295195Y1411605D01*
X295795Y1410939D01*
G01X299995Y1403872D02*
Y1411872D01*
G01X304195D02*
Y1403872D01*
G01Y1407872D02*
X299995D01*
G01X310095Y1403872D02*
X309295Y1404005D01*
X308595Y1404539D01*
X307995Y1405339D01*
X307595Y1406272D01*
X307395Y1407339D01*
Y1408405D01*
X307595Y1409472D01*
X307995Y1410405D01*
X308595Y1411205D01*
X309295Y1411739D01*
X310095Y1411872D01*
X310895Y1411739D01*
X311595Y1411205D01*
X312195Y1410405D01*
X312595Y1409472D01*
X312795Y1408405D01*
Y1407339D01*
X312595Y1406272D01*
X312195Y1405339D01*
X311595Y1404539D01*
X310895Y1404005D01*
X310095Y1403872D01*
G01X316095D02*
Y1411872D01*
X318495D01*
X319295Y1411472D01*
X319895Y1410539D01*
X320095Y1409472D01*
X319895Y1408405D01*
X319395Y1407605D01*
X318495Y1407205D01*
X316095D01*
G01X332095Y1403872D02*
Y1411872D01*
X334495D01*
X335295Y1411472D01*
X335895Y1410539D01*
X336095Y1409472D01*
X335895Y1408405D01*
X335395Y1407605D01*
X334495Y1407205D01*
X332095D01*
G01X340095Y1403872D02*
Y1411872D01*
X342595D01*
X343395Y1411472D01*
X343895Y1410939D01*
X344095Y1409872D01*
X343895Y1408805D01*
X343295Y1408139D01*
X342595Y1407739D01*
X340095D01*
G01X342595D02*
X344095Y1403872D01*
G01X352095D02*
X348095D01*
Y1411872D01*
X352095D01*
G01X350495Y1408005D02*
X348095D01*
G01X356195Y1403872D02*
Y1411872D01*
X359995D01*
G01X358595Y1408005D02*
X356195D01*
G01X368095Y1403872D02*
X364095D01*
Y1411872D01*
X368095D01*
G01X366495Y1408005D02*
X364095D01*
G01X372095Y1403872D02*
Y1411872D01*
X374595D01*
X375395Y1411472D01*
X375895Y1410939D01*
X376095Y1409872D01*
X375895Y1408805D01*
X375295Y1408139D01*
X374595Y1407739D01*
X372095D01*
G01X374595D02*
X376095Y1403872D01*
G01X384095D02*
X380095D01*
Y1411872D01*
X384095D01*
G01X382495Y1408005D02*
X380095D01*
G01X387795Y1403872D02*
Y1411872D01*
X392395Y1403872D01*
Y1411872D01*
G01X400295Y1411205D02*
X399695Y1411605D01*
X398995Y1411872D01*
X398195D01*
X397295Y1411472D01*
X396595Y1410805D01*
X396095Y1410005D01*
X395695Y1408672D01*
X395595Y1407472D01*
X395795Y1406272D01*
X396095Y1405472D01*
X396695Y1404672D01*
X397395Y1404139D01*
X398095Y1403872D01*
X398795D01*
X399495Y1404139D01*
X400095Y1404539D01*
X400595Y1405072D01*
G01X408095Y1403872D02*
X404095D01*
Y1411872D01*
X408095D01*
G01X406495Y1408005D02*
X404095D01*
G01X422895Y1408139D02*
X423295Y1408539D01*
X423595Y1409205D01*
X423795Y1410139D01*
X423595Y1410939D01*
X423195Y1411472D01*
X422495Y1411872D01*
X419795D01*
Y1403872D01*
X423095D01*
X423795Y1404405D01*
X424195Y1405205D01*
X424395Y1406139D01*
X424195Y1407072D01*
X423595Y1407872D01*
X422895Y1408139D01*
X419795D01*
G01X427895Y1411872D02*
Y1406139D01*
X428295Y1404938D01*
X429095Y1404139D01*
X430095Y1403872D01*
X431095Y1404139D01*
X431895Y1404938D01*
X432295Y1406139D01*
Y1411872D01*
G01X438095D02*
Y1403872D01*
G01X435795Y1411872D02*
X440395D01*
G01X456295Y1411205D02*
X455695Y1411605D01*
X454995Y1411872D01*
X454195D01*
X453295Y1411472D01*
X452595Y1410805D01*
X452095Y1410005D01*
X451695Y1408672D01*
X451595Y1407472D01*
X451795Y1406272D01*
X452095Y1405472D01*
X452695Y1404672D01*
X453395Y1404139D01*
X454095Y1403872D01*
X454795D01*
X455495Y1404139D01*
X456095Y1404539D01*
X456595Y1405072D01*
G01X462095Y1403872D02*
X461295Y1404005D01*
X460595Y1404539D01*
X459995Y1405339D01*
X459595Y1406272D01*
X459395Y1407339D01*
Y1408405D01*
X459595Y1409472D01*
X459995Y1410405D01*
X460595Y1411205D01*
X461295Y1411739D01*
X462095Y1411872D01*
X462895Y1411739D01*
X463595Y1411205D01*
X464195Y1410405D01*
X464595Y1409472D01*
X464795Y1408405D01*
Y1407339D01*
X464595Y1406272D01*
X464195Y1405339D01*
X463595Y1404539D01*
X462895Y1404005D01*
X462095Y1403872D01*
G01X467895Y1411872D02*
Y1406139D01*
X468295Y1404938D01*
X469095Y1404139D01*
X470095Y1403872D01*
X471095Y1404139D01*
X471895Y1404938D01*
X472295Y1406139D01*
Y1411872D01*
G01X476095Y1403872D02*
Y1411872D01*
X478495D01*
X479295Y1411472D01*
X479895Y1410539D01*
X480095Y1409472D01*
X479895Y1408405D01*
X479395Y1407605D01*
X478495Y1407205D01*
X476095D01*
G01X486095Y1403872D02*
X485295Y1404005D01*
X484595Y1404539D01*
X483995Y1405339D01*
X483595Y1406272D01*
X483395Y1407339D01*
Y1408405D01*
X483595Y1409472D01*
X483995Y1410405D01*
X484595Y1411205D01*
X485295Y1411739D01*
X486095Y1411872D01*
X486895Y1411739D01*
X487595Y1411205D01*
X488195Y1410405D01*
X488595Y1409472D01*
X488795Y1408405D01*
Y1407339D01*
X488595Y1406272D01*
X488195Y1405339D01*
X487595Y1404539D01*
X486895Y1404005D01*
X486095Y1403872D01*
G01X491795D02*
Y1411872D01*
X496395Y1403872D01*
Y1411872D01*
G01X500295Y1403605D02*
X503895Y1411872D01*
G01X508195Y1403872D02*
Y1411872D01*
X511995D01*
G01X510595Y1408005D02*
X508195D01*
G01X516895Y1411872D02*
X519295D01*
G01X518095D02*
Y1403872D01*
G01X516895D02*
X519295D01*
G01X523895D02*
Y1411872D01*
X525895D01*
X526695Y1411472D01*
X527295Y1410939D01*
X527795Y1410139D01*
X528195Y1409205D01*
X528295Y1407872D01*
X528195Y1406539D01*
X527795Y1405605D01*
X527295Y1404805D01*
X526695Y1404272D01*
X525895Y1403872D01*
X523895D01*
G01X531895Y1411872D02*
Y1406139D01*
X532295Y1404938D01*
X533095Y1404139D01*
X534095Y1403872D01*
X535095Y1404139D01*
X535895Y1404938D01*
X536295Y1406139D01*
Y1411872D01*
G01X544295Y1411205D02*
X543695Y1411605D01*
X542995Y1411872D01*
X542195D01*
X541295Y1411472D01*
X540595Y1410805D01*
X540095Y1410005D01*
X539695Y1408672D01*
X539595Y1407472D01*
X539795Y1406272D01*
X540095Y1405472D01*
X540695Y1404672D01*
X541395Y1404139D01*
X542095Y1403872D01*
X542795D01*
X543495Y1404139D01*
X544095Y1404539D01*
X544595Y1405072D01*
G01X548895Y1411872D02*
X551295D01*
G01X550095D02*
Y1403872D01*
G01X548895D02*
X551295D01*
G01X555595D02*
X558095Y1411872D01*
X560595Y1403872D01*
G01X559695Y1406672D02*
X556495D01*
G01X564095Y1411872D02*
Y1403872D01*
X568095D01*
G01X579495D02*
Y1411872D01*
X582095Y1405205D01*
X584695Y1411872D01*
Y1403872D01*
G01X587595D02*
X590095Y1411872D01*
X592595Y1403872D01*
G01X591695Y1406672D02*
X588495D01*
G01X596095Y1403872D02*
Y1411872D01*
X598595D01*
X599395Y1411472D01*
X599895Y1410939D01*
X600095Y1409872D01*
X599895Y1408805D01*
X599295Y1408139D01*
X598595Y1407739D01*
X596095D01*
G01X598595D02*
X600095Y1403872D01*
G01X603895D02*
Y1411872D01*
G01X607695D02*
X603895Y1406938D01*
G01X608295Y1403872D02*
X605595Y1409205D01*
G01X612295Y1403605D02*
X615895Y1411872D01*
G01X622095D02*
Y1403872D01*
G01X619795Y1411872D02*
X624395D01*
G01X630095Y1403872D02*
X629295Y1404005D01*
X628595Y1404539D01*
X627995Y1405339D01*
X627595Y1406272D01*
X627395Y1407339D01*
Y1408405D01*
X627595Y1409472D01*
X627995Y1410405D01*
X628595Y1411205D01*
X629295Y1411739D01*
X630095Y1411872D01*
X630895Y1411739D01*
X631595Y1411205D01*
X632195Y1410405D01*
X632595Y1409472D01*
X632795Y1408405D01*
Y1407339D01*
X632595Y1406272D01*
X632195Y1405339D01*
X631595Y1404539D01*
X630895Y1404005D01*
X630095Y1403872D01*
G01X638095D02*
X637295Y1404005D01*
X636595Y1404539D01*
X635995Y1405339D01*
X635595Y1406272D01*
X635395Y1407339D01*
Y1408405D01*
X635595Y1409472D01*
X635995Y1410405D01*
X636595Y1411205D01*
X637295Y1411739D01*
X638095Y1411872D01*
X638895Y1411739D01*
X639595Y1411205D01*
X640195Y1410405D01*
X640595Y1409472D01*
X640795Y1408405D01*
Y1407339D01*
X640595Y1406272D01*
X640195Y1405339D01*
X639595Y1404539D01*
X638895Y1404005D01*
X638095Y1403872D01*
G01X644095Y1411872D02*
Y1403872D01*
X648095D01*
G01X652895Y1411872D02*
X655295D01*
G01X654095D02*
Y1403872D01*
G01X652895D02*
X655295D01*
G01X659795D02*
Y1411872D01*
X664395Y1403872D01*
Y1411872D01*
G01X670695Y1407872D02*
X672695D01*
Y1405472D01*
X672095Y1404672D01*
X671395Y1404139D01*
X670395Y1403872D01*
X669395Y1404139D01*
X668695Y1404672D01*
X668095Y1405472D01*
X667695Y1406405D01*
X667495Y1407472D01*
Y1408405D01*
X667695Y1409205D01*
X668095Y1410139D01*
X668695Y1410939D01*
X669295Y1411472D01*
X670095Y1411872D01*
X670795D01*
X671595Y1411605D01*
X672195Y1411072D01*
G01X683995Y1403872D02*
Y1411872D01*
G01X688195D02*
Y1403872D01*
G01Y1407872D02*
X683995D01*
G01X694095Y1403872D02*
X693295Y1404005D01*
X692595Y1404539D01*
X691995Y1405339D01*
X691595Y1406272D01*
X691395Y1407339D01*
Y1408405D01*
X691595Y1409472D01*
X691995Y1410405D01*
X692595Y1411205D01*
X693295Y1411739D01*
X694095Y1411872D01*
X694895Y1411739D01*
X695595Y1411205D01*
X696195Y1410405D01*
X696595Y1409472D01*
X696795Y1408405D01*
Y1407339D01*
X696595Y1406272D01*
X696195Y1405339D01*
X695595Y1404539D01*
X694895Y1404005D01*
X694095Y1403872D01*
G01X700095Y1411872D02*
Y1403872D01*
X704095D01*
G01X712095D02*
X708095D01*
Y1411872D01*
X712095D01*
G01X710495Y1408005D02*
X708095D01*
G01X723995Y1404938D02*
X724795Y1404272D01*
X725695Y1403872D01*
X726495D01*
X727295Y1404272D01*
X727895Y1404938D01*
X728195Y1405872D01*
X727995Y1406805D01*
X727495Y1407605D01*
X726595Y1408139D01*
X725395Y1408405D01*
X724695Y1408939D01*
X724395Y1409872D01*
X724595Y1410805D01*
X725095Y1411472D01*
X725795Y1411872D01*
X726495D01*
X727195Y1411605D01*
X727795Y1410939D01*
G01X732095Y1403872D02*
Y1411872D01*
X734495D01*
X735295Y1411472D01*
X735895Y1410539D01*
X736095Y1409472D01*
X735895Y1408405D01*
X735395Y1407605D01*
X734495Y1407205D01*
X732095D01*
G01X739595Y1403872D02*
X742095Y1411872D01*
X744595Y1403872D01*
G01X743695Y1406672D02*
X740495D01*
G01X752295Y1411205D02*
X751695Y1411605D01*
X750995Y1411872D01*
X750195D01*
X749295Y1411472D01*
X748595Y1410805D01*
X748095Y1410005D01*
X747695Y1408672D01*
X747595Y1407472D01*
X747795Y1406272D01*
X748095Y1405472D01*
X748695Y1404672D01*
X749395Y1404139D01*
X750095Y1403872D01*
X750795D01*
X751495Y1404139D01*
X752095Y1404539D01*
X752595Y1405072D01*
G01X756895Y1411872D02*
X759295D01*
G01X758095D02*
Y1403872D01*
G01X756895D02*
X759295D01*
G01X763795D02*
Y1411872D01*
X768395Y1403872D01*
Y1411872D01*
G01X774695Y1407872D02*
X776695D01*
Y1405472D01*
X776095Y1404672D01*
X775395Y1404139D01*
X774395Y1403872D01*
X773395Y1404139D01*
X772695Y1404672D01*
X772095Y1405472D01*
X771695Y1406405D01*
X771495Y1407472D01*
Y1408405D01*
X771695Y1409205D01*
X772095Y1410139D01*
X772695Y1410939D01*
X773295Y1411472D01*
X774095Y1411872D01*
X774795D01*
X775595Y1411605D01*
X776195Y1411072D01*
G01X787595Y1403872D02*
X790095Y1411872D01*
X792595Y1403872D01*
G01X791695Y1406672D02*
X788495D01*
G01X796095Y1411872D02*
Y1403872D01*
X800095D01*
G01X804095Y1411872D02*
Y1403872D01*
X808095D01*
G01X819895Y1411872D02*
Y1406139D01*
X820295Y1404938D01*
X821095Y1404139D01*
X822095Y1403872D01*
X823095Y1404139D01*
X823895Y1404938D01*
X824295Y1406139D01*
Y1411872D01*
G01X827995Y1404938D02*
X828795Y1404272D01*
X829695Y1403872D01*
X830495D01*
X831295Y1404272D01*
X831895Y1404938D01*
X832195Y1405872D01*
X831995Y1406805D01*
X831495Y1407605D01*
X830595Y1408139D01*
X829395Y1408405D01*
X828695Y1408939D01*
X828395Y1409872D01*
X828595Y1410805D01*
X829095Y1411472D01*
X829795Y1411872D01*
X830495D01*
X831195Y1411605D01*
X831795Y1410939D01*
G01X836895Y1411872D02*
X839295D01*
G01X838095D02*
Y1403872D01*
G01X836895D02*
X839295D01*
G01X843795D02*
Y1411872D01*
X848395Y1403872D01*
Y1411872D01*
G01X854695Y1407872D02*
X856695D01*
Y1405472D01*
X856095Y1404672D01*
X855395Y1404139D01*
X854395Y1403872D01*
X853395Y1404139D01*
X852695Y1404672D01*
X852095Y1405472D01*
X851695Y1406405D01*
X851495Y1407472D01*
Y1408405D01*
X851695Y1409205D01*
X852095Y1410139D01*
X852695Y1410939D01*
X853295Y1411472D01*
X854095Y1411872D01*
X854795D01*
X855595Y1411605D01*
X856195Y1411072D01*
G01X867895Y1405072D02*
X868495Y1404405D01*
X869195Y1404005D01*
X870095Y1403872D01*
X870995Y1404139D01*
X871695Y1404672D01*
X872195Y1405605D01*
X872295Y1406672D01*
X872095Y1407739D01*
X871595Y1408405D01*
X870895Y1408939D01*
X870195Y1409072D01*
X869495Y1408939D01*
X868595Y1408405D01*
X868895Y1411872D01*
X871595D01*
G01X878095D02*
X877295Y1411605D01*
X876695Y1410939D01*
X876295Y1410139D01*
X875995Y1409072D01*
X875895Y1407872D01*
X875995Y1406672D01*
X876295Y1405605D01*
X876695Y1404805D01*
X877295Y1404139D01*
X878095Y1403872D01*
X878895Y1404139D01*
X879495Y1404805D01*
X879895Y1405605D01*
X880195Y1406672D01*
X880295Y1407872D01*
X880195Y1409072D01*
X879895Y1410139D01*
X879495Y1410939D01*
X878895Y1411605D01*
X878095Y1411872D01*
G01X883495Y1403872D02*
Y1411872D01*
X886095Y1405205D01*
X888695Y1411872D01*
Y1403872D01*
G01X892895Y1411872D02*
X895295D01*
G01X894095D02*
Y1403872D01*
G01X892895D02*
X895295D01*
G01X900095Y1411872D02*
Y1403872D01*
X904095D01*
G01X907995Y1404938D02*
X908795Y1404272D01*
X909695Y1403872D01*
X910495D01*
X911295Y1404272D01*
X911895Y1404938D01*
X912195Y1405872D01*
X911995Y1406805D01*
X911495Y1407605D01*
X910595Y1408139D01*
X909395Y1408405D01*
X908695Y1408939D01*
X908395Y1409872D01*
X908595Y1410805D01*
X909095Y1411472D01*
X909795Y1411872D01*
X910495D01*
X911195Y1411605D01*
X911795Y1410939D01*
G01X918095Y1403605D02*
X917895Y1403739D01*
Y1404005D01*
X918095Y1404139D01*
X918295Y1404005D01*
Y1403739D01*
X918095Y1403605D01*
G01X-3805Y1422205D02*
X-3105Y1423139D01*
X-2505Y1423672D01*
X-1705Y1423939D01*
X-1005Y1423672D01*
X-505Y1423139D01*
X-105Y1422339D01*
X-5Y1421405D01*
X-105Y1420605D01*
X-505Y1419805D01*
X-1105Y1419139D01*
X-1805Y1418872D01*
X-2605Y1419139D01*
X-3305Y1419938D01*
X-3705Y1421139D01*
X-3805Y1422472D01*
X-3605Y1424205D01*
X-3305Y1425139D01*
X-2805Y1426072D01*
X-2105Y1426739D01*
X-1405Y1426872D01*
X-705Y1426605D01*
X-205Y1425939D01*
G01X6095Y1418605D02*
X5895Y1418739D01*
Y1419005D01*
X6095Y1419139D01*
X6295Y1419005D01*
Y1418739D01*
X6095Y1418605D01*
G01X14095Y1418872D02*
Y1426872D01*
X12895Y1425272D01*
G01Y1418872D02*
X15295D01*
G01X28895Y1426872D02*
X31295D01*
G01X30095D02*
Y1418872D01*
G01X28895D02*
X31295D01*
G01X35795D02*
Y1426872D01*
X40395Y1418872D01*
Y1426872D01*
G01X43995Y1419938D02*
X44795Y1419272D01*
X45695Y1418872D01*
X46495D01*
X47295Y1419272D01*
X47895Y1419938D01*
X48195Y1420872D01*
X47995Y1421805D01*
X47495Y1422605D01*
X46595Y1423139D01*
X45395Y1423405D01*
X44695Y1423939D01*
X44395Y1424872D01*
X44595Y1425805D01*
X45095Y1426472D01*
X45795Y1426872D01*
X46495D01*
X47195Y1426605D01*
X47795Y1425939D01*
G01X52895Y1426872D02*
X55295D01*
G01X54095D02*
Y1418872D01*
G01X52895D02*
X55295D01*
G01X59895D02*
Y1426872D01*
X61895D01*
X62695Y1426472D01*
X63295Y1425939D01*
X63795Y1425139D01*
X64195Y1424205D01*
X64295Y1422872D01*
X64195Y1421539D01*
X63795Y1420605D01*
X63295Y1419805D01*
X62695Y1419272D01*
X61895Y1418872D01*
X59895D01*
G01X72095D02*
X68095D01*
Y1426872D01*
X72095D01*
G01X70495Y1423005D02*
X68095D01*
G01X86895Y1423139D02*
X87295Y1423539D01*
X87595Y1424205D01*
X87795Y1425139D01*
X87595Y1425939D01*
X87195Y1426472D01*
X86495Y1426872D01*
X83795D01*
Y1418872D01*
X87095D01*
X87795Y1419405D01*
X88195Y1420205D01*
X88395Y1421139D01*
X88195Y1422072D01*
X87595Y1422872D01*
X86895Y1423139D01*
X83795D01*
G01X94095Y1418872D02*
X93295Y1419005D01*
X92595Y1419539D01*
X91995Y1420339D01*
X91595Y1421272D01*
X91395Y1422339D01*
Y1423405D01*
X91595Y1424472D01*
X91995Y1425405D01*
X92595Y1426205D01*
X93295Y1426739D01*
X94095Y1426872D01*
X94895Y1426739D01*
X95595Y1426205D01*
X96195Y1425405D01*
X96595Y1424472D01*
X96795Y1423405D01*
Y1422339D01*
X96595Y1421272D01*
X96195Y1420339D01*
X95595Y1419539D01*
X94895Y1419005D01*
X94095Y1418872D01*
G01X99595D02*
X102095Y1426872D01*
X104595Y1418872D01*
G01X103695Y1421672D02*
X100495D01*
G01X108095Y1418872D02*
Y1426872D01*
X110595D01*
X111395Y1426472D01*
X111895Y1425939D01*
X112095Y1424872D01*
X111895Y1423805D01*
X111295Y1423139D01*
X110595Y1422739D01*
X108095D01*
G01X110595D02*
X112095Y1418872D01*
G01X115895D02*
Y1426872D01*
X117895D01*
X118695Y1426472D01*
X119295Y1425939D01*
X119795Y1425139D01*
X120195Y1424205D01*
X120295Y1422872D01*
X120195Y1421539D01*
X119795Y1420605D01*
X119295Y1419805D01*
X118695Y1419272D01*
X117895Y1418872D01*
X115895D01*
G01X134095D02*
X133295Y1419005D01*
X132595Y1419539D01*
X131995Y1420339D01*
X131595Y1421272D01*
X131395Y1422339D01*
Y1423405D01*
X131595Y1424472D01*
X131995Y1425405D01*
X132595Y1426205D01*
X133295Y1426739D01*
X134095Y1426872D01*
X134895Y1426739D01*
X135595Y1426205D01*
X136195Y1425405D01*
X136595Y1424472D01*
X136795Y1423405D01*
Y1422339D01*
X136595Y1421272D01*
X136195Y1420339D01*
X135595Y1419539D01*
X134895Y1419005D01*
X134095Y1418872D01*
G01X139895Y1426872D02*
Y1421139D01*
X140295Y1419938D01*
X141095Y1419139D01*
X142095Y1418872D01*
X143095Y1419139D01*
X143895Y1419938D01*
X144295Y1421139D01*
Y1426872D01*
G01X150095D02*
Y1418872D01*
G01X147795Y1426872D02*
X152395D01*
G01X156095D02*
Y1418872D01*
X160095D01*
G01X164895Y1426872D02*
X167295D01*
G01X166095D02*
Y1418872D01*
G01X164895D02*
X167295D01*
G01X171795D02*
Y1426872D01*
X176395Y1418872D01*
Y1426872D01*
G01X184095Y1418872D02*
X180095D01*
Y1426872D01*
X184095D01*
G01X182495Y1423005D02*
X180095D01*
G01X195895Y1418872D02*
Y1426872D01*
X197895D01*
X198695Y1426472D01*
X199295Y1425939D01*
X199795Y1425139D01*
X200195Y1424205D01*
X200295Y1422872D01*
X200195Y1421539D01*
X199795Y1420605D01*
X199295Y1419805D01*
X198695Y1419272D01*
X197895Y1418872D01*
X195895D01*
G01X203895Y1426872D02*
Y1421139D01*
X204295Y1419938D01*
X205095Y1419139D01*
X206095Y1418872D01*
X207095Y1419139D01*
X207895Y1419938D01*
X208295Y1421139D01*
Y1426872D01*
G01X211495Y1418872D02*
Y1426872D01*
X214095Y1420205D01*
X216695Y1426872D01*
Y1418872D01*
G01X219495D02*
Y1426872D01*
X222095Y1420205D01*
X224695Y1426872D01*
Y1418872D01*
G01X230095D02*
Y1422472D01*
X228095Y1426872D01*
G01X232095D02*
X230095Y1422472D01*
G01X244095Y1418872D02*
Y1426872D01*
X246495D01*
X247295Y1426472D01*
X247895Y1425539D01*
X248095Y1424472D01*
X247895Y1423405D01*
X247395Y1422605D01*
X246495Y1422205D01*
X244095D01*
G01X251595Y1418872D02*
X254095Y1426872D01*
X256595Y1418872D01*
G01X255695Y1421672D02*
X252495D01*
G01X259895Y1418872D02*
Y1426872D01*
X261895D01*
X262695Y1426472D01*
X263295Y1425939D01*
X263795Y1425139D01*
X264195Y1424205D01*
X264295Y1422872D01*
X264195Y1421539D01*
X263795Y1420605D01*
X263295Y1419805D01*
X262695Y1419272D01*
X261895Y1418872D01*
X259895D01*
G01X275895D02*
Y1426872D01*
X277895D01*
X278695Y1426472D01*
X279295Y1425939D01*
X279795Y1425139D01*
X280195Y1424205D01*
X280295Y1422872D01*
X280195Y1421539D01*
X279795Y1420605D01*
X279295Y1419805D01*
X278695Y1419272D01*
X277895Y1418872D01*
X275895D01*
G01X288095D02*
X284095D01*
Y1426872D01*
X288095D01*
G01X286495Y1423005D02*
X284095D01*
G01X291995Y1419938D02*
X292795Y1419272D01*
X293695Y1418872D01*
X294495D01*
X295295Y1419272D01*
X295895Y1419938D01*
X296195Y1420872D01*
X295995Y1421805D01*
X295495Y1422605D01*
X294595Y1423139D01*
X293395Y1423405D01*
X292695Y1423939D01*
X292395Y1424872D01*
X292595Y1425805D01*
X293095Y1426472D01*
X293795Y1426872D01*
X294495D01*
X295195Y1426605D01*
X295795Y1425939D01*
G01X300895Y1426872D02*
X303295D01*
G01X302095D02*
Y1418872D01*
G01X300895D02*
X303295D01*
G01X310695Y1422872D02*
X312695D01*
Y1420472D01*
X312095Y1419672D01*
X311395Y1419139D01*
X310395Y1418872D01*
X309395Y1419139D01*
X308695Y1419672D01*
X308095Y1420472D01*
X307695Y1421405D01*
X307495Y1422472D01*
Y1423405D01*
X307695Y1424205D01*
X308095Y1425139D01*
X308695Y1425939D01*
X309295Y1426472D01*
X310095Y1426872D01*
X310795D01*
X311595Y1426605D01*
X312195Y1426072D01*
G01X315795Y1418872D02*
Y1426872D01*
X320395Y1418872D01*
Y1426872D01*
G01X332895D02*
X335295D01*
G01X334095D02*
Y1418872D01*
G01X332895D02*
X335295D01*
G01X339795D02*
Y1426872D01*
X344395Y1418872D01*
Y1426872D01*
G01X355995Y1419938D02*
X356795Y1419272D01*
X357695Y1418872D01*
X358495D01*
X359295Y1419272D01*
X359895Y1419938D01*
X360195Y1420872D01*
X359995Y1421805D01*
X359495Y1422605D01*
X358595Y1423139D01*
X357395Y1423405D01*
X356695Y1423939D01*
X356395Y1424872D01*
X356595Y1425805D01*
X357095Y1426472D01*
X357795Y1426872D01*
X358495D01*
X359195Y1426605D01*
X359795Y1425939D01*
G01X366095Y1418872D02*
X365295Y1419005D01*
X364595Y1419539D01*
X363995Y1420339D01*
X363595Y1421272D01*
X363395Y1422339D01*
Y1423405D01*
X363595Y1424472D01*
X363995Y1425405D01*
X364595Y1426205D01*
X365295Y1426739D01*
X366095Y1426872D01*
X366895Y1426739D01*
X367595Y1426205D01*
X368195Y1425405D01*
X368595Y1424472D01*
X368795Y1423405D01*
Y1422339D01*
X368595Y1421272D01*
X368195Y1420339D01*
X367595Y1419539D01*
X366895Y1419005D01*
X366095Y1418872D01*
G01X366895Y1421005D02*
X368095Y1418872D01*
G01X371895Y1426872D02*
Y1421139D01*
X372295Y1419938D01*
X373095Y1419139D01*
X374095Y1418872D01*
X375095Y1419139D01*
X375895Y1419938D01*
X376295Y1421139D01*
Y1426872D01*
G01X379595Y1418872D02*
X382095Y1426872D01*
X384595Y1418872D01*
G01X383695Y1421672D02*
X380495D01*
G01X388095Y1418872D02*
Y1426872D01*
X390595D01*
X391395Y1426472D01*
X391895Y1425939D01*
X392095Y1424872D01*
X391895Y1423805D01*
X391295Y1423139D01*
X390595Y1422739D01*
X388095D01*
G01X390595D02*
X392095Y1418872D01*
G01X400095D02*
X396095D01*
Y1426872D01*
X400095D01*
G01X398495Y1423005D02*
X396095D01*
G01X411995Y1419938D02*
X412795Y1419272D01*
X413695Y1418872D01*
X414495D01*
X415295Y1419272D01*
X415895Y1419938D01*
X416195Y1420872D01*
X415995Y1421805D01*
X415495Y1422605D01*
X414595Y1423139D01*
X413395Y1423405D01*
X412695Y1423939D01*
X412395Y1424872D01*
X412595Y1425805D01*
X413095Y1426472D01*
X413795Y1426872D01*
X414495D01*
X415195Y1426605D01*
X415795Y1425939D01*
G01X419995Y1418872D02*
Y1426872D01*
G01X424195D02*
Y1418872D01*
G01Y1422872D02*
X419995D01*
G01X427595Y1418872D02*
X430095Y1426872D01*
X432595Y1418872D01*
G01X431695Y1421672D02*
X428495D01*
G01X436095Y1418872D02*
Y1426872D01*
X438495D01*
X439295Y1426472D01*
X439895Y1425539D01*
X440095Y1424472D01*
X439895Y1423405D01*
X439395Y1422605D01*
X438495Y1422205D01*
X436095D01*
G01X448095Y1418872D02*
X444095D01*
Y1426872D01*
X448095D01*
G01X446495Y1423005D02*
X444095D01*
G01X452795Y1421539D02*
X455395D01*
G01X467995Y1419938D02*
X468795Y1419272D01*
X469695Y1418872D01*
X470495D01*
X471295Y1419272D01*
X471895Y1419938D01*
X472195Y1420872D01*
X471995Y1421805D01*
X471495Y1422605D01*
X470595Y1423139D01*
X469395Y1423405D01*
X468695Y1423939D01*
X468395Y1424872D01*
X468595Y1425805D01*
X469095Y1426472D01*
X469795Y1426872D01*
X470495D01*
X471195Y1426605D01*
X471795Y1425939D01*
G01X475995Y1418872D02*
Y1426872D01*
G01X480195D02*
Y1418872D01*
G01Y1422872D02*
X475995D01*
G01X483595Y1418872D02*
X486095Y1426872D01*
X488595Y1418872D01*
G01X487695Y1421672D02*
X484495D01*
G01X492095Y1418872D02*
Y1426872D01*
X494495D01*
X495295Y1426472D01*
X495895Y1425539D01*
X496095Y1424472D01*
X495895Y1423405D01*
X495395Y1422605D01*
X494495Y1422205D01*
X492095D01*
G01X504095Y1418872D02*
X500095D01*
Y1426872D01*
X504095D01*
G01X502495Y1423005D02*
X500095D01*
G01X515995Y1419938D02*
X516795Y1419272D01*
X517695Y1418872D01*
X518495D01*
X519295Y1419272D01*
X519895Y1419938D01*
X520195Y1420872D01*
X519995Y1421805D01*
X519495Y1422605D01*
X518595Y1423139D01*
X517395Y1423405D01*
X516695Y1423939D01*
X516395Y1424872D01*
X516595Y1425805D01*
X517095Y1426472D01*
X517795Y1426872D01*
X518495D01*
X519195Y1426605D01*
X519795Y1425939D01*
G01X524895Y1426872D02*
X527295D01*
G01X526095D02*
Y1418872D01*
G01X524895D02*
X527295D01*
G01X532195Y1426872D02*
X535995D01*
X532195Y1418872D01*
X535995D01*
G01X544095D02*
X540095D01*
Y1426872D01*
X544095D01*
G01X542495Y1423005D02*
X540095D01*
G01X555895Y1420072D02*
X556495Y1419405D01*
X557195Y1419005D01*
X558095Y1418872D01*
X558995Y1419139D01*
X559695Y1419672D01*
X560195Y1420605D01*
X560295Y1421672D01*
X560095Y1422739D01*
X559595Y1423405D01*
X558895Y1423939D01*
X558195Y1424072D01*
X557495Y1423939D01*
X556595Y1423405D01*
X556895Y1426872D01*
X559595D01*
G01X566095D02*
X565295Y1426605D01*
X564695Y1425939D01*
X564295Y1425139D01*
X563995Y1424072D01*
X563895Y1422872D01*
X563995Y1421672D01*
X564295Y1420605D01*
X564695Y1419805D01*
X565295Y1419139D01*
X566095Y1418872D01*
X566895Y1419139D01*
X567495Y1419805D01*
X567895Y1420605D01*
X568195Y1421672D01*
X568295Y1422872D01*
X568195Y1424072D01*
X567895Y1425139D01*
X567495Y1425939D01*
X566895Y1426605D01*
X566095Y1426872D01*
G01X571495Y1418872D02*
Y1426872D01*
X574095Y1420205D01*
X576695Y1426872D01*
Y1418872D01*
G01X580895Y1426872D02*
X583295D01*
G01X582095D02*
Y1418872D01*
G01X580895D02*
X583295D01*
G01X588095Y1426872D02*
Y1418872D01*
X592095D01*
G01X595995Y1419938D02*
X596795Y1419272D01*
X597695Y1418872D01*
X598495D01*
X599295Y1419272D01*
X599895Y1419938D01*
X600195Y1420872D01*
X599995Y1421805D01*
X599495Y1422605D01*
X598595Y1423139D01*
X597395Y1423405D01*
X596695Y1423939D01*
X596395Y1424872D01*
X596595Y1425805D01*
X597095Y1426472D01*
X597795Y1426872D01*
X598495D01*
X599195Y1426605D01*
X599795Y1425939D01*
G01X605895Y1417405D02*
X606295Y1419139D01*
G01X620095Y1418872D02*
Y1426872D01*
X622495D01*
X623295Y1426472D01*
X623895Y1425539D01*
X624095Y1424472D01*
X623895Y1423405D01*
X623395Y1422605D01*
X622495Y1422205D01*
X620095D01*
G01X628895Y1426872D02*
X631295D01*
G01X630095D02*
Y1418872D01*
G01X628895D02*
X631295D01*
G01X638095Y1426872D02*
Y1418872D01*
G01X635795Y1426872D02*
X640395D01*
G01X648295Y1426205D02*
X647695Y1426605D01*
X646995Y1426872D01*
X646195D01*
X645295Y1426472D01*
X644595Y1425805D01*
X644095Y1425005D01*
X643695Y1423672D01*
X643595Y1422472D01*
X643795Y1421272D01*
X644095Y1420472D01*
X644695Y1419672D01*
X645395Y1419139D01*
X646095Y1418872D01*
X646795D01*
X647495Y1419139D01*
X648095Y1419539D01*
X648595Y1420072D01*
G01X651995Y1418872D02*
Y1426872D01*
G01X656195D02*
Y1418872D01*
G01Y1422872D02*
X651995D01*
G01X669595Y1416205D02*
X668595Y1417539D01*
X668095Y1418872D01*
Y1424205D01*
X668595Y1425539D01*
X669595Y1426872D01*
G01X675995Y1419938D02*
X676795Y1419272D01*
X677695Y1418872D01*
X678495D01*
X679295Y1419272D01*
X679895Y1419938D01*
X680195Y1420872D01*
X679995Y1421805D01*
X679495Y1422605D01*
X678595Y1423139D01*
X677395Y1423405D01*
X676695Y1423939D01*
X676395Y1424872D01*
X676595Y1425805D01*
X677095Y1426472D01*
X677795Y1426872D01*
X678495D01*
X679195Y1426605D01*
X679795Y1425939D01*
G01X683995Y1418872D02*
Y1426872D01*
G01X688195D02*
Y1418872D01*
G01Y1422872D02*
X683995D01*
G01X691595Y1418872D02*
X694095Y1426872D01*
X696595Y1418872D01*
G01X695695Y1421672D02*
X692495D01*
G01X700095Y1418872D02*
Y1426872D01*
X702495D01*
X703295Y1426472D01*
X703895Y1425539D01*
X704095Y1424472D01*
X703895Y1423405D01*
X703395Y1422605D01*
X702495Y1422205D01*
X700095D01*
G01X712095Y1418872D02*
X708095D01*
Y1426872D01*
X712095D01*
G01X710495Y1423005D02*
X708095D01*
G01X728295Y1426205D02*
X727695Y1426605D01*
X726995Y1426872D01*
X726195D01*
X725295Y1426472D01*
X724595Y1425805D01*
X724095Y1425005D01*
X723695Y1423672D01*
X723595Y1422472D01*
X723795Y1421272D01*
X724095Y1420472D01*
X724695Y1419672D01*
X725395Y1419139D01*
X726095Y1418872D01*
X726795D01*
X727495Y1419139D01*
X728095Y1419539D01*
X728595Y1420072D01*
G01X736095Y1418872D02*
X732095D01*
Y1426872D01*
X736095D01*
G01X734495Y1423005D02*
X732095D01*
G01X739795Y1418872D02*
Y1426872D01*
X744395Y1418872D01*
Y1426872D01*
G01X750095D02*
Y1418872D01*
G01X747795Y1426872D02*
X752395D01*
G01X760095Y1418872D02*
X756095D01*
Y1426872D01*
X760095D01*
G01X758495Y1423005D02*
X756095D01*
G01X764095Y1418872D02*
Y1426872D01*
X766595D01*
X767395Y1426472D01*
X767895Y1425939D01*
X768095Y1424872D01*
X767895Y1423805D01*
X767295Y1423139D01*
X766595Y1422739D01*
X764095D01*
G01X766595D02*
X768095Y1418872D01*
G01X782095Y1426872D02*
Y1418872D01*
G01X779795Y1426872D02*
X784395D01*
G01X790095Y1418872D02*
X789295Y1419005D01*
X788595Y1419539D01*
X787995Y1420339D01*
X787595Y1421272D01*
X787395Y1422339D01*
Y1423405D01*
X787595Y1424472D01*
X787995Y1425405D01*
X788595Y1426205D01*
X789295Y1426739D01*
X790095Y1426872D01*
X790895Y1426739D01*
X791595Y1426205D01*
X792195Y1425405D01*
X792595Y1424472D01*
X792795Y1423405D01*
Y1422339D01*
X792595Y1421272D01*
X792195Y1420339D01*
X791595Y1419539D01*
X790895Y1419005D01*
X790095Y1418872D01*
G01X808295Y1426205D02*
X807695Y1426605D01*
X806995Y1426872D01*
X806195D01*
X805295Y1426472D01*
X804595Y1425805D01*
X804095Y1425005D01*
X803695Y1423672D01*
X803595Y1422472D01*
X803795Y1421272D01*
X804095Y1420472D01*
X804695Y1419672D01*
X805395Y1419139D01*
X806095Y1418872D01*
X806795D01*
X807495Y1419139D01*
X808095Y1419539D01*
X808595Y1420072D01*
G01X816095Y1418872D02*
X812095D01*
Y1426872D01*
X816095D01*
G01X814495Y1423005D02*
X812095D01*
G01X819795Y1418872D02*
Y1426872D01*
X824395Y1418872D01*
Y1426872D01*
G01X830095D02*
Y1418872D01*
G01X827795Y1426872D02*
X832395D01*
G01X840095Y1418872D02*
X836095D01*
Y1426872D01*
X840095D01*
G01X838495Y1423005D02*
X836095D01*
G01X844095Y1418872D02*
Y1426872D01*
X846595D01*
X847395Y1426472D01*
X847895Y1425939D01*
X848095Y1424872D01*
X847895Y1423805D01*
X847295Y1423139D01*
X846595Y1422739D01*
X844095D01*
G01X846595D02*
X848095Y1418872D01*
G01X854595Y1416205D02*
X855595Y1417539D01*
X856095Y1418872D01*
Y1424205D01*
X855595Y1425539D01*
X854595Y1426872D01*
G01X862095Y1418605D02*
X861895Y1418739D01*
Y1419005D01*
X862095Y1419139D01*
X862295Y1419005D01*
Y1418739D01*
X862095Y1418605D01*
G01Y1422205D02*
X861895Y1422339D01*
Y1422605D01*
X862095Y1422739D01*
X862295Y1422605D01*
Y1422339D01*
X862095Y1422205D01*
G01X878095Y1418872D02*
Y1426872D01*
X876895Y1425272D01*
G01Y1418872D02*
X879295D01*
G01X886095Y1426872D02*
X885295Y1426605D01*
X884695Y1425939D01*
X884295Y1425139D01*
X883995Y1424072D01*
X883895Y1422872D01*
X883995Y1421672D01*
X884295Y1420605D01*
X884695Y1419805D01*
X885295Y1419139D01*
X886095Y1418872D01*
X886895Y1419139D01*
X887495Y1419805D01*
X887895Y1420605D01*
X888195Y1421672D01*
X888295Y1422872D01*
X888195Y1424072D01*
X887895Y1425139D01*
X887495Y1425939D01*
X886895Y1426605D01*
X886095Y1426872D01*
G01X894095D02*
X893295Y1426605D01*
X892695Y1425939D01*
X892295Y1425139D01*
X891995Y1424072D01*
X891895Y1422872D01*
X891995Y1421672D01*
X892295Y1420605D01*
X892695Y1419805D01*
X893295Y1419139D01*
X894095Y1418872D01*
X894895Y1419139D01*
X895495Y1419805D01*
X895895Y1420605D01*
X896195Y1421672D01*
X896295Y1422872D01*
X896195Y1424072D01*
X895895Y1425139D01*
X895495Y1425939D01*
X894895Y1426605D01*
X894095Y1426872D01*
G01X899495Y1418872D02*
Y1426872D01*
X902095Y1420205D01*
X904695Y1426872D01*
Y1418872D01*
G01X908895Y1426872D02*
X911295D01*
G01X910095D02*
Y1418872D01*
G01X908895D02*
X911295D01*
G01X916095Y1426872D02*
Y1418872D01*
X920095D01*
G01X923995Y1419938D02*
X924795Y1419272D01*
X925695Y1418872D01*
X926495D01*
X927295Y1419272D01*
X927895Y1419938D01*
X928195Y1420872D01*
X927995Y1421805D01*
X927495Y1422605D01*
X926595Y1423139D01*
X925395Y1423405D01*
X924695Y1423939D01*
X924395Y1424872D01*
X924595Y1425805D01*
X925095Y1426472D01*
X925795Y1426872D01*
X926495D01*
X927195Y1426605D01*
X927795Y1425939D01*
G01X934095Y1418605D02*
X933895Y1418739D01*
Y1419005D01*
X934095Y1419139D01*
X934295Y1419005D01*
Y1418739D01*
X934095Y1418605D01*
G01X947895Y1418872D02*
Y1426872D01*
X949895D01*
X950695Y1426472D01*
X951295Y1425939D01*
X951795Y1425139D01*
X952195Y1424205D01*
X952295Y1422872D01*
X952195Y1421539D01*
X951795Y1420605D01*
X951295Y1419805D01*
X950695Y1419272D01*
X949895Y1418872D01*
X947895D01*
G01X956095D02*
Y1426872D01*
X958595D01*
X959395Y1426472D01*
X959895Y1425939D01*
X960095Y1424872D01*
X959895Y1423805D01*
X959295Y1423139D01*
X958595Y1422739D01*
X956095D01*
G01X958595D02*
X960095Y1418872D01*
G01X964895Y1426872D02*
X967295D01*
G01X966095D02*
Y1418872D01*
G01X964895D02*
X967295D01*
G01X972095Y1426872D02*
Y1418872D01*
X976095D01*
G01X980095Y1426872D02*
Y1418872D01*
X984095D01*
G01X988295Y1418605D02*
X991895Y1426872D01*
G01X996195Y1418872D02*
Y1426872D01*
X999995D01*
G01X998595Y1423005D02*
X996195D01*
G01X1008095Y1418872D02*
X1004095D01*
Y1426872D01*
X1008095D01*
G01X1006495Y1423005D02*
X1004095D01*
G01X1011595Y1418872D02*
X1014095Y1426872D01*
X1016595Y1418872D01*
G01X1015695Y1421672D02*
X1012495D01*
G01X1022095Y1426872D02*
Y1418872D01*
G01X1019795Y1426872D02*
X1024395D01*
G01X1027895D02*
Y1421139D01*
X1028295Y1419938D01*
X1029095Y1419139D01*
X1030095Y1418872D01*
X1031095Y1419139D01*
X1031895Y1419938D01*
X1032295Y1421139D01*
Y1426872D01*
G01X1036095Y1418872D02*
Y1426872D01*
X1038595D01*
X1039395Y1426472D01*
X1039895Y1425939D01*
X1040095Y1424872D01*
X1039895Y1423805D01*
X1039295Y1423139D01*
X1038595Y1422739D01*
X1036095D01*
G01X1038595D02*
X1040095Y1418872D01*
G01X1048095D02*
X1044095D01*
Y1426872D01*
X1048095D01*
G01X1046495Y1423005D02*
X1044095D01*
G01X1052295Y1418605D02*
X1055895Y1426872D01*
G01X1060095Y1418872D02*
Y1426872D01*
X1062595D01*
X1063395Y1426472D01*
X1063895Y1425939D01*
X1064095Y1424872D01*
X1063895Y1423805D01*
X1063295Y1423139D01*
X1062595Y1422739D01*
X1060095D01*
G01X1062595D02*
X1064095Y1418872D01*
G01X1070095D02*
X1069295Y1419005D01*
X1068595Y1419539D01*
X1067995Y1420339D01*
X1067595Y1421272D01*
X1067395Y1422339D01*
Y1423405D01*
X1067595Y1424472D01*
X1067995Y1425405D01*
X1068595Y1426205D01*
X1069295Y1426739D01*
X1070095Y1426872D01*
X1070895Y1426739D01*
X1071595Y1426205D01*
X1072195Y1425405D01*
X1072595Y1424472D01*
X1072795Y1423405D01*
Y1422339D01*
X1072595Y1421272D01*
X1072195Y1420339D01*
X1071595Y1419539D01*
X1070895Y1419005D01*
X1070095Y1418872D01*
G01X1075895Y1426872D02*
Y1421139D01*
X1076295Y1419938D01*
X1077095Y1419139D01*
X1078095Y1418872D01*
X1079095Y1419139D01*
X1079895Y1419938D01*
X1080295Y1421139D01*
Y1426872D01*
G01X1086095D02*
Y1418872D01*
G01X1083795Y1426872D02*
X1088395D01*
G01X1096095Y1418872D02*
X1092095D01*
Y1426872D01*
X1096095D01*
G01X1094495Y1423005D02*
X1092095D01*
G01X1100295Y1418605D02*
X1103895Y1426872D01*
G01X1108095Y1418872D02*
Y1426872D01*
X1110495D01*
X1111295Y1426472D01*
X1111895Y1425539D01*
X1112095Y1424472D01*
X1111895Y1423405D01*
X1111395Y1422605D01*
X1110495Y1422205D01*
X1108095D01*
G01X1116095Y1418872D02*
Y1426872D01*
X1118595D01*
X1119395Y1426472D01*
X1119895Y1425939D01*
X1120095Y1424872D01*
X1119895Y1423805D01*
X1119295Y1423139D01*
X1118595Y1422739D01*
X1116095D01*
G01X1118595D02*
X1120095Y1418872D01*
G01X1126095D02*
X1125295Y1419005D01*
X1124595Y1419539D01*
X1123995Y1420339D01*
X1123595Y1421272D01*
X1123395Y1422339D01*
Y1423405D01*
X1123595Y1424472D01*
X1123995Y1425405D01*
X1124595Y1426205D01*
X1125295Y1426739D01*
X1126095Y1426872D01*
X1126895Y1426739D01*
X1127595Y1426205D01*
X1128195Y1425405D01*
X1128595Y1424472D01*
X1128795Y1423405D01*
Y1422339D01*
X1128595Y1421272D01*
X1128195Y1420339D01*
X1127595Y1419539D01*
X1126895Y1419005D01*
X1126095Y1418872D01*
G01X1132195D02*
Y1426872D01*
X1135995D01*
G01X1134595Y1423005D02*
X1132195D01*
G01X1140895Y1426872D02*
X1143295D01*
G01X1142095D02*
Y1418872D01*
G01X1140895D02*
X1143295D01*
G01X1148095Y1426872D02*
Y1418872D01*
X1152095D01*
G01X1160095D02*
X1156095D01*
Y1426872D01*
X1160095D01*
G01X1158495Y1423005D02*
X1156095D01*
G01X1171995Y1419938D02*
X1172795Y1419272D01*
X1173695Y1418872D01*
X1174495D01*
X1175295Y1419272D01*
X1175895Y1419938D01*
X1176195Y1420872D01*
X1175995Y1421805D01*
X1175495Y1422605D01*
X1174595Y1423139D01*
X1173395Y1423405D01*
X1172695Y1423939D01*
X1172395Y1424872D01*
X1172595Y1425805D01*
X1173095Y1426472D01*
X1173795Y1426872D01*
X1174495D01*
X1175195Y1426605D01*
X1175795Y1425939D01*
G01X1180095Y1418872D02*
Y1426872D01*
X1182495D01*
X1183295Y1426472D01*
X1183895Y1425539D01*
X1184095Y1424472D01*
X1183895Y1423405D01*
X1183395Y1422605D01*
X1182495Y1422205D01*
X1180095D01*
G01X1187595Y1418872D02*
X1190095Y1426872D01*
X1192595Y1418872D01*
G01X1191695Y1421672D02*
X1188495D01*
G01X1200295Y1426205D02*
X1199695Y1426605D01*
X1198995Y1426872D01*
X1198195D01*
X1197295Y1426472D01*
X1196595Y1425805D01*
X1196095Y1425005D01*
X1195695Y1423672D01*
X1195595Y1422472D01*
X1195795Y1421272D01*
X1196095Y1420472D01*
X1196695Y1419672D01*
X1197395Y1419139D01*
X1198095Y1418872D01*
X1198795D01*
X1199495Y1419139D01*
X1200095Y1419539D01*
X1200595Y1420072D01*
G01X1204895Y1426872D02*
X1207295D01*
G01X1206095D02*
Y1418872D01*
G01X1204895D02*
X1207295D01*
G01X1211795D02*
Y1426872D01*
X1216395Y1418872D01*
Y1426872D01*
G01X1222695Y1422872D02*
X1224695D01*
Y1420472D01*
X1224095Y1419672D01*
X1223395Y1419139D01*
X1222395Y1418872D01*
X1221395Y1419139D01*
X1220695Y1419672D01*
X1220095Y1420472D01*
X1219695Y1421405D01*
X1219495Y1422472D01*
Y1423405D01*
X1219695Y1424205D01*
X1220095Y1425139D01*
X1220695Y1425939D01*
X1221295Y1426472D01*
X1222095Y1426872D01*
X1222795D01*
X1223595Y1426605D01*
X1224195Y1426072D01*
G01X1235595Y1418872D02*
X1238095Y1426872D01*
X1240595Y1418872D01*
G01X1239695Y1421672D02*
X1236495D01*
G01X1244095Y1426872D02*
Y1418872D01*
X1248095D01*
G01X1252095Y1426872D02*
Y1418872D01*
X1256095D01*
G01X1267895Y1426872D02*
Y1421139D01*
X1268295Y1419938D01*
X1269095Y1419139D01*
X1270095Y1418872D01*
X1271095Y1419139D01*
X1271895Y1419938D01*
X1272295Y1421139D01*
Y1426872D01*
G01X1275995Y1419938D02*
X1276795Y1419272D01*
X1277695Y1418872D01*
X1278495D01*
X1279295Y1419272D01*
X1279895Y1419938D01*
X1280195Y1420872D01*
X1279995Y1421805D01*
X1279495Y1422605D01*
X1278595Y1423139D01*
X1277395Y1423405D01*
X1276695Y1423939D01*
X1276395Y1424872D01*
X1276595Y1425805D01*
X1277095Y1426472D01*
X1277795Y1426872D01*
X1278495D01*
X1279195Y1426605D01*
X1279795Y1425939D01*
G01X1284895Y1426872D02*
X1287295D01*
G01X1286095D02*
Y1418872D01*
G01X1284895D02*
X1287295D01*
G01X1291795D02*
Y1426872D01*
X1296395Y1418872D01*
Y1426872D01*
G01X1302695Y1422872D02*
X1304695D01*
Y1420472D01*
X1304095Y1419672D01*
X1303395Y1419139D01*
X1302395Y1418872D01*
X1301395Y1419139D01*
X1300695Y1419672D01*
X1300095Y1420472D01*
X1299695Y1421405D01*
X1299495Y1422472D01*
Y1423405D01*
X1299695Y1424205D01*
X1300095Y1425139D01*
X1300695Y1425939D01*
X1301295Y1426472D01*
X1302095Y1426872D01*
X1302795D01*
X1303595Y1426605D01*
X1304195Y1426072D01*
G01X1318095Y1418872D02*
Y1426872D01*
X1316895Y1425272D01*
G01Y1418872D02*
X1319295D01*
G01X1326095Y1426872D02*
X1325295Y1426605D01*
X1324695Y1425939D01*
X1324295Y1425139D01*
X1323995Y1424072D01*
X1323895Y1422872D01*
X1323995Y1421672D01*
X1324295Y1420605D01*
X1324695Y1419805D01*
X1325295Y1419139D01*
X1326095Y1418872D01*
X1326895Y1419139D01*
X1327495Y1419805D01*
X1327895Y1420605D01*
X1328195Y1421672D01*
X1328295Y1422872D01*
X1328195Y1424072D01*
X1327895Y1425139D01*
X1327495Y1425939D01*
X1326895Y1426605D01*
X1326095Y1426872D01*
G01X1334095D02*
X1333295Y1426605D01*
X1332695Y1425939D01*
X1332295Y1425139D01*
X1331995Y1424072D01*
X1331895Y1422872D01*
X1331995Y1421672D01*
X1332295Y1420605D01*
X1332695Y1419805D01*
X1333295Y1419139D01*
X1334095Y1418872D01*
X1334895Y1419139D01*
X1335495Y1419805D01*
X1335895Y1420605D01*
X1336195Y1421672D01*
X1336295Y1422872D01*
X1336195Y1424072D01*
X1335895Y1425139D01*
X1335495Y1425939D01*
X1334895Y1426605D01*
X1334095Y1426872D01*
G01X1339495Y1418872D02*
Y1426872D01*
X1342095Y1420205D01*
X1344695Y1426872D01*
Y1418872D01*
G01X1348895Y1426872D02*
X1351295D01*
G01X1350095D02*
Y1418872D01*
G01X1348895D02*
X1351295D01*
G01X1356095Y1426872D02*
Y1418872D01*
X1360095D01*
G01X1363995Y1419938D02*
X1364795Y1419272D01*
X1365695Y1418872D01*
X1366495D01*
X1367295Y1419272D01*
X1367895Y1419938D01*
X1368195Y1420872D01*
X1367995Y1421805D01*
X1367495Y1422605D01*
X1366595Y1423139D01*
X1365395Y1423405D01*
X1364695Y1423939D01*
X1364395Y1424872D01*
X1364595Y1425805D01*
X1365095Y1426472D01*
X1365795Y1426872D01*
X1366495D01*
X1367195Y1426605D01*
X1367795Y1425939D01*
G01X1374095Y1418605D02*
X1373895Y1418739D01*
Y1419005D01*
X1374095Y1419139D01*
X1374295Y1419005D01*
Y1418739D01*
X1374095Y1418605D01*
G01X1396095Y1426872D02*
Y1418872D01*
X1400095D01*
G01X1403595D02*
X1406095Y1426872D01*
X1408595Y1418872D01*
G01X1407695Y1421672D02*
X1404495D01*
G01X1414895Y1423139D02*
X1415295Y1423539D01*
X1415595Y1424205D01*
X1415795Y1425139D01*
X1415595Y1425939D01*
X1415195Y1426472D01*
X1414495Y1426872D01*
X1411795D01*
Y1418872D01*
X1415095D01*
X1415795Y1419405D01*
X1416195Y1420205D01*
X1416395Y1421139D01*
X1416195Y1422072D01*
X1415595Y1422872D01*
X1414895Y1423139D01*
X1411795D01*
G01X1424095Y1418872D02*
X1420095D01*
Y1426872D01*
X1424095D01*
G01X1422495Y1423005D02*
X1420095D01*
G01X1428095Y1426872D02*
Y1418872D01*
X1432095D01*
G01X1443595D02*
X1446095Y1426872D01*
X1448595Y1418872D01*
G01X1447695Y1421672D02*
X1444495D01*
G01X1452095Y1418872D02*
Y1426872D01*
X1454595D01*
X1455395Y1426472D01*
X1455895Y1425939D01*
X1456095Y1424872D01*
X1455895Y1423805D01*
X1455295Y1423139D01*
X1454595Y1422739D01*
X1452095D01*
G01X1454595D02*
X1456095Y1418872D01*
G01X1464095D02*
X1460095D01*
Y1426872D01*
X1464095D01*
G01X1462495Y1423005D02*
X1460095D01*
G01X1467595Y1418872D02*
X1470095Y1426872D01*
X1472595Y1418872D01*
G01X1471695Y1421672D02*
X1468495D01*
G01X1483795Y1418872D02*
Y1426872D01*
X1488395Y1418872D01*
Y1426872D01*
G01X1494095Y1418872D02*
X1493295Y1419005D01*
X1492595Y1419539D01*
X1491995Y1420339D01*
X1491595Y1421272D01*
X1491395Y1422339D01*
Y1423405D01*
X1491595Y1424472D01*
X1491995Y1425405D01*
X1492595Y1426205D01*
X1493295Y1426739D01*
X1494095Y1426872D01*
X1494895Y1426739D01*
X1495595Y1426205D01*
X1496195Y1425405D01*
X1496595Y1424472D01*
X1496795Y1423405D01*
Y1422339D01*
X1496595Y1421272D01*
X1496195Y1420339D01*
X1495595Y1419539D01*
X1494895Y1419005D01*
X1494095Y1418872D01*
G01X1507595D02*
X1510095Y1426872D01*
X1512595Y1418872D01*
G01X1511695Y1421672D02*
X1508495D01*
G01X1515895Y1418872D02*
Y1426872D01*
X1517895D01*
X1518695Y1426472D01*
X1519295Y1425939D01*
X1519795Y1425139D01*
X1520195Y1424205D01*
X1520295Y1422872D01*
X1520195Y1421539D01*
X1519795Y1420605D01*
X1519295Y1419805D01*
X1518695Y1419272D01*
X1517895Y1418872D01*
X1515895D01*
G01X1523895D02*
Y1426872D01*
X1525895D01*
X1526695Y1426472D01*
X1527295Y1425939D01*
X1527795Y1425139D01*
X1528195Y1424205D01*
X1528295Y1422872D01*
X1528195Y1421539D01*
X1527795Y1420605D01*
X1527295Y1419805D01*
X1526695Y1419272D01*
X1525895Y1418872D01*
X1523895D01*
G01X1539895D02*
Y1426872D01*
X1541895D01*
X1542695Y1426472D01*
X1543295Y1425939D01*
X1543795Y1425139D01*
X1544195Y1424205D01*
X1544295Y1422872D01*
X1544195Y1421539D01*
X1543795Y1420605D01*
X1543295Y1419805D01*
X1542695Y1419272D01*
X1541895Y1418872D01*
X1539895D01*
G01X1547895Y1426872D02*
Y1421139D01*
X1548295Y1419938D01*
X1549095Y1419139D01*
X1550095Y1418872D01*
X1551095Y1419139D01*
X1551895Y1419938D01*
X1552295Y1421139D01*
Y1426872D01*
G01X1555495Y1418872D02*
Y1426872D01*
X1558095Y1420205D01*
X1560695Y1426872D01*
Y1418872D01*
G01X1563495D02*
Y1426872D01*
X1566095Y1420205D01*
X1568695Y1426872D01*
Y1418872D01*
G01X1574095D02*
Y1422472D01*
X1572095Y1426872D01*
G01X1576095D02*
X1574095Y1422472D01*
G01X1588095Y1418872D02*
Y1426872D01*
X1590495D01*
X1591295Y1426472D01*
X1591895Y1425539D01*
X1592095Y1424472D01*
X1591895Y1423405D01*
X1591395Y1422605D01*
X1590495Y1422205D01*
X1588095D01*
G01X1595595Y1418872D02*
X1598095Y1426872D01*
X1600595Y1418872D01*
G01X1599695Y1421672D02*
X1596495D01*
G01X1603895Y1418872D02*
Y1426872D01*
X1605895D01*
X1606695Y1426472D01*
X1607295Y1425939D01*
X1607795Y1425139D01*
X1608195Y1424205D01*
X1608295Y1422872D01*
X1608195Y1421539D01*
X1607795Y1420605D01*
X1607295Y1419805D01*
X1606695Y1419272D01*
X1605895Y1418872D01*
X1603895D01*
G01X1614095Y1418605D02*
X1613895Y1418739D01*
Y1419005D01*
X1614095Y1419139D01*
X1614295Y1419005D01*
Y1418739D01*
X1614095Y1418605D01*
G01X-4105Y1480072D02*
X-3505Y1479405D01*
X-2805Y1479005D01*
X-1905Y1478872D01*
X-1005Y1479139D01*
X-305Y1479672D01*
X195Y1480605D01*
X295Y1481672D01*
X95Y1482739D01*
X-405Y1483405D01*
X-1105Y1483939D01*
X-1805Y1484072D01*
X-2505Y1483939D01*
X-3405Y1483405D01*
X-3105Y1486872D01*
X-405D01*
G01X6095Y1478605D02*
X5895Y1478739D01*
Y1479005D01*
X6095Y1479139D01*
X6295Y1479005D01*
Y1478739D01*
X6095Y1478605D01*
G01X12095Y1478872D02*
Y1486872D01*
X14495D01*
X15295Y1486472D01*
X15895Y1485539D01*
X16095Y1484472D01*
X15895Y1483405D01*
X15395Y1482605D01*
X14495Y1482205D01*
X12095D01*
G01X24095Y1478872D02*
X20095D01*
Y1486872D01*
X24095D01*
G01X22495Y1483005D02*
X20095D01*
G01X32095Y1478872D02*
X28095D01*
Y1486872D01*
X32095D01*
G01X30495Y1483005D02*
X28095D01*
G01X36095Y1486872D02*
Y1478872D01*
X40095D01*
G01X44895Y1486872D02*
X47295D01*
G01X46095D02*
Y1478872D01*
G01X44895D02*
X47295D01*
G01X51795D02*
Y1486872D01*
X56395Y1478872D01*
Y1486872D01*
G01X62695Y1482872D02*
X64695D01*
Y1480472D01*
X64095Y1479672D01*
X63395Y1479139D01*
X62395Y1478872D01*
X61395Y1479139D01*
X60695Y1479672D01*
X60095Y1480472D01*
X59695Y1481405D01*
X59495Y1482472D01*
Y1483405D01*
X59695Y1484205D01*
X60095Y1485139D01*
X60695Y1485939D01*
X61295Y1486472D01*
X62095Y1486872D01*
X62795D01*
X63595Y1486605D01*
X64195Y1486072D01*
G01X75995Y1479938D02*
X76795Y1479272D01*
X77695Y1478872D01*
X78495D01*
X79295Y1479272D01*
X79895Y1479938D01*
X80195Y1480872D01*
X79995Y1481805D01*
X79495Y1482605D01*
X78595Y1483139D01*
X77395Y1483405D01*
X76695Y1483939D01*
X76395Y1484872D01*
X76595Y1485805D01*
X77095Y1486472D01*
X77795Y1486872D01*
X78495D01*
X79195Y1486605D01*
X79795Y1485939D01*
G01X86095Y1486872D02*
Y1478872D01*
G01X83795Y1486872D02*
X88395D01*
G01X92095Y1478872D02*
Y1486872D01*
X94595D01*
X95395Y1486472D01*
X95895Y1485939D01*
X96095Y1484872D01*
X95895Y1483805D01*
X95295Y1483139D01*
X94595Y1482739D01*
X92095D01*
G01X94595D02*
X96095Y1478872D01*
G01X104095D02*
X100095D01*
Y1486872D01*
X104095D01*
G01X102495Y1483005D02*
X100095D01*
G01X107795Y1478872D02*
Y1486872D01*
X112395Y1478872D01*
Y1486872D01*
G01X118695Y1482872D02*
X120695D01*
Y1480472D01*
X120095Y1479672D01*
X119395Y1479139D01*
X118395Y1478872D01*
X117395Y1479139D01*
X116695Y1479672D01*
X116095Y1480472D01*
X115695Y1481405D01*
X115495Y1482472D01*
Y1483405D01*
X115695Y1484205D01*
X116095Y1485139D01*
X116695Y1485939D01*
X117295Y1486472D01*
X118095Y1486872D01*
X118795D01*
X119595Y1486605D01*
X120195Y1486072D01*
G01X126095Y1486872D02*
Y1478872D01*
G01X123795Y1486872D02*
X128395D01*
G01X131995Y1478872D02*
Y1486872D01*
G01X136195D02*
Y1478872D01*
G01Y1482872D02*
X131995D01*
G01X147595Y1478872D02*
X150095Y1486872D01*
X152595Y1478872D01*
G01X151695Y1481672D02*
X148495D01*
G01X155795Y1478872D02*
Y1486872D01*
X160395Y1478872D01*
Y1486872D01*
G01X163895Y1478872D02*
Y1486872D01*
X165895D01*
X166695Y1486472D01*
X167295Y1485939D01*
X167795Y1485139D01*
X168195Y1484205D01*
X168295Y1482872D01*
X168195Y1481539D01*
X167795Y1480605D01*
X167295Y1479805D01*
X166695Y1479272D01*
X165895Y1478872D01*
X163895D01*
G01X182895Y1483139D02*
X183295Y1483539D01*
X183595Y1484205D01*
X183795Y1485139D01*
X183595Y1485939D01*
X183195Y1486472D01*
X182495Y1486872D01*
X179795D01*
Y1478872D01*
X183095D01*
X183795Y1479405D01*
X184195Y1480205D01*
X184395Y1481139D01*
X184195Y1482072D01*
X183595Y1482872D01*
X182895Y1483139D01*
X179795D01*
G01X190695Y1482872D02*
X192695D01*
Y1480472D01*
X192095Y1479672D01*
X191395Y1479139D01*
X190395Y1478872D01*
X189395Y1479139D01*
X188695Y1479672D01*
X188095Y1480472D01*
X187695Y1481405D01*
X187495Y1482472D01*
Y1483405D01*
X187695Y1484205D01*
X188095Y1485139D01*
X188695Y1485939D01*
X189295Y1486472D01*
X190095Y1486872D01*
X190795D01*
X191595Y1486605D01*
X192195Y1486072D01*
G01X195595Y1478872D02*
X198095Y1486872D01*
X200595Y1478872D01*
G01X199695Y1481672D02*
X196495D01*
G01X212095Y1478872D02*
Y1486872D01*
X214495D01*
X215295Y1486472D01*
X215895Y1485539D01*
X216095Y1484472D01*
X215895Y1483405D01*
X215395Y1482605D01*
X214495Y1482205D01*
X212095D01*
G01X219595Y1478872D02*
X222095Y1486872D01*
X224595Y1478872D01*
G01X223695Y1481672D02*
X220495D01*
G01X227895Y1478872D02*
Y1486872D01*
X229895D01*
X230695Y1486472D01*
X231295Y1485939D01*
X231795Y1485139D01*
X232195Y1484205D01*
X232295Y1482872D01*
X232195Y1481539D01*
X231795Y1480605D01*
X231295Y1479805D01*
X230695Y1479272D01*
X229895Y1478872D01*
X227895D01*
G01X235995Y1479938D02*
X236795Y1479272D01*
X237695Y1478872D01*
X238495D01*
X239295Y1479272D01*
X239895Y1479938D01*
X240195Y1480872D01*
X239995Y1481805D01*
X239495Y1482605D01*
X238595Y1483139D01*
X237395Y1483405D01*
X236695Y1483939D01*
X236395Y1484872D01*
X236595Y1485805D01*
X237095Y1486472D01*
X237795Y1486872D01*
X238495D01*
X239195Y1486605D01*
X239795Y1485939D01*
G01X251595Y1478872D02*
X254095Y1486872D01*
X256595Y1478872D01*
G01X255695Y1481672D02*
X252495D01*
G01X259895Y1478872D02*
Y1486872D01*
X261895D01*
X262695Y1486472D01*
X263295Y1485939D01*
X263795Y1485139D01*
X264195Y1484205D01*
X264295Y1482872D01*
X264195Y1481539D01*
X263795Y1480605D01*
X263295Y1479805D01*
X262695Y1479272D01*
X261895Y1478872D01*
X259895D01*
G01X267995D02*
Y1486872D01*
G01X272195D02*
Y1478872D01*
G01Y1482872D02*
X267995D01*
G01X280095Y1478872D02*
X276095D01*
Y1486872D01*
X280095D01*
G01X278495Y1483005D02*
X276095D01*
G01X283995Y1479938D02*
X284795Y1479272D01*
X285695Y1478872D01*
X286495D01*
X287295Y1479272D01*
X287895Y1479938D01*
X288195Y1480872D01*
X287995Y1481805D01*
X287495Y1482605D01*
X286595Y1483139D01*
X285395Y1483405D01*
X284695Y1483939D01*
X284395Y1484872D01*
X284595Y1485805D01*
X285095Y1486472D01*
X285795Y1486872D01*
X286495D01*
X287195Y1486605D01*
X287795Y1485939D01*
G01X292895Y1486872D02*
X295295D01*
G01X294095D02*
Y1478872D01*
G01X292895D02*
X295295D01*
G01X302095D02*
X301295Y1479005D01*
X300595Y1479539D01*
X299995Y1480339D01*
X299595Y1481272D01*
X299395Y1482339D01*
Y1483405D01*
X299595Y1484472D01*
X299995Y1485405D01*
X300595Y1486205D01*
X301295Y1486739D01*
X302095Y1486872D01*
X302895Y1486739D01*
X303595Y1486205D01*
X304195Y1485405D01*
X304595Y1484472D01*
X304795Y1483405D01*
Y1482339D01*
X304595Y1481272D01*
X304195Y1480339D01*
X303595Y1479539D01*
X302895Y1479005D01*
X302095Y1478872D01*
G01X307795D02*
Y1486872D01*
X312395Y1478872D01*
Y1486872D01*
G01X326095D02*
Y1478872D01*
G01X323795Y1486872D02*
X328395D01*
G01X336095Y1478872D02*
X332095D01*
Y1486872D01*
X336095D01*
G01X334495Y1483005D02*
X332095D01*
G01X339995Y1479938D02*
X340795Y1479272D01*
X341695Y1478872D01*
X342495D01*
X343295Y1479272D01*
X343895Y1479938D01*
X344195Y1480872D01*
X343995Y1481805D01*
X343495Y1482605D01*
X342595Y1483139D01*
X341395Y1483405D01*
X340695Y1483939D01*
X340395Y1484872D01*
X340595Y1485805D01*
X341095Y1486472D01*
X341795Y1486872D01*
X342495D01*
X343195Y1486605D01*
X343795Y1485939D01*
G01X350095Y1486872D02*
Y1478872D01*
G01X347795Y1486872D02*
X352395D01*
G01X364095Y1478872D02*
Y1486872D01*
X366495D01*
X367295Y1486472D01*
X367895Y1485539D01*
X368095Y1484472D01*
X367895Y1483405D01*
X367395Y1482605D01*
X366495Y1482205D01*
X364095D01*
G01X371595Y1478872D02*
X374095Y1486872D01*
X376595Y1478872D01*
G01X375695Y1481672D02*
X372495D01*
G01X382095Y1486872D02*
Y1478872D01*
G01X379795Y1486872D02*
X384395D01*
G01X390095D02*
Y1478872D01*
G01X387795Y1486872D02*
X392395D01*
G01X400095Y1478872D02*
X396095D01*
Y1486872D01*
X400095D01*
G01X398495Y1483005D02*
X396095D01*
G01X404095Y1478872D02*
Y1486872D01*
X406595D01*
X407395Y1486472D01*
X407895Y1485939D01*
X408095Y1484872D01*
X407895Y1483805D01*
X407295Y1483139D01*
X406595Y1482739D01*
X404095D01*
G01X406595D02*
X408095Y1478872D01*
G01X411795D02*
Y1486872D01*
X416395Y1478872D01*
Y1486872D01*
G01X419995Y1479938D02*
X420795Y1479272D01*
X421695Y1478872D01*
X422495D01*
X423295Y1479272D01*
X423895Y1479938D01*
X424195Y1480872D01*
X423995Y1481805D01*
X423495Y1482605D01*
X422595Y1483139D01*
X421395Y1483405D01*
X420695Y1483939D01*
X420395Y1484872D01*
X420595Y1485805D01*
X421095Y1486472D01*
X421795Y1486872D01*
X422495D01*
X423195Y1486605D01*
X423795Y1485939D01*
G01X430095Y1478605D02*
X429895Y1478739D01*
Y1479005D01*
X430095Y1479139D01*
X430295Y1479005D01*
Y1478739D01*
X430095Y1478605D01*
G01X16695Y1572872D02*
X18695D01*
Y1570472D01*
X18095Y1569672D01*
X17395Y1569139D01*
X16395Y1568872D01*
X15395Y1569139D01*
X14695Y1569672D01*
X14095Y1570472D01*
X13695Y1571405D01*
X13495Y1572472D01*
Y1573405D01*
X13695Y1574205D01*
X14095Y1575139D01*
X14695Y1575939D01*
X15295Y1576472D01*
X16095Y1576872D01*
X16795D01*
X17595Y1576605D01*
X18195Y1576072D01*
G01X24095Y1568605D02*
X23895Y1568739D01*
Y1569005D01*
X24095Y1569139D01*
X24295Y1569005D01*
Y1568739D01*
X24095Y1568605D01*
G01X29795Y1568872D02*
Y1576872D01*
X34395Y1568872D01*
Y1576872D01*
G01X42095Y1568872D02*
X38095D01*
Y1576872D01*
X42095D01*
G01X40495Y1573005D02*
X38095D01*
G01X50095Y1568872D02*
X46095D01*
Y1576872D01*
X50095D01*
G01X48495Y1573005D02*
X46095D01*
G01X53895Y1568872D02*
Y1576872D01*
X55895D01*
X56695Y1576472D01*
X57295Y1575939D01*
X57795Y1575139D01*
X58195Y1574205D01*
X58295Y1572872D01*
X58195Y1571539D01*
X57795Y1570605D01*
X57295Y1569805D01*
X56695Y1569272D01*
X55895Y1568872D01*
X53895D01*
G01X69895Y1576872D02*
Y1571139D01*
X70295Y1569938D01*
X71095Y1569139D01*
X72095Y1568872D01*
X73095Y1569139D01*
X73895Y1569938D01*
X74295Y1571139D01*
Y1576872D01*
G01X78095D02*
Y1568872D01*
X82095D01*
G01X93495D02*
Y1576872D01*
X96095Y1570205D01*
X98695Y1576872D01*
Y1568872D01*
G01X101595D02*
X104095Y1576872D01*
X106595Y1568872D01*
G01X105695Y1571672D02*
X102495D01*
G01X110095Y1568872D02*
Y1576872D01*
X112595D01*
X113395Y1576472D01*
X113895Y1575939D01*
X114095Y1574872D01*
X113895Y1573805D01*
X113295Y1573139D01*
X112595Y1572739D01*
X110095D01*
G01X112595D02*
X114095Y1568872D01*
G01X117895D02*
Y1576872D01*
G01X121695D02*
X117895Y1571938D01*
G01X122295Y1568872D02*
X119595Y1574205D01*
G01X133595Y1568872D02*
X136095Y1576872D01*
X138595Y1568872D01*
G01X137695Y1571672D02*
X134495D01*
G01X141795Y1568872D02*
Y1576872D01*
X146395Y1568872D01*
Y1576872D01*
G01X149895Y1568872D02*
Y1576872D01*
X151895D01*
X152695Y1576472D01*
X153295Y1575939D01*
X153795Y1575139D01*
X154195Y1574205D01*
X154295Y1572872D01*
X154195Y1571539D01*
X153795Y1570605D01*
X153295Y1569805D01*
X152695Y1569272D01*
X151895Y1568872D01*
X149895D01*
G01X165895Y1576872D02*
Y1571139D01*
X166295Y1569938D01*
X167095Y1569139D01*
X168095Y1568872D01*
X169095Y1569139D01*
X169895Y1569938D01*
X170295Y1571139D01*
Y1576872D01*
G01X174095D02*
Y1568872D01*
X178095D01*
G01X190195D02*
Y1576872D01*
X193995D01*
G01X192595Y1573005D02*
X190195D01*
G01X198895Y1576872D02*
X201295D01*
G01X200095D02*
Y1568872D01*
G01X198895D02*
X201295D01*
G01X206095Y1576872D02*
Y1568872D01*
X210095D01*
G01X218095D02*
X214095D01*
Y1576872D01*
X218095D01*
G01X216495Y1573005D02*
X214095D01*
G01X229795Y1568872D02*
Y1576872D01*
X234395Y1568872D01*
Y1576872D01*
G01X237895D02*
Y1571139D01*
X238295Y1569938D01*
X239095Y1569139D01*
X240095Y1568872D01*
X241095Y1569139D01*
X241895Y1569938D01*
X242295Y1571139D01*
Y1576872D01*
G01X245495Y1568872D02*
Y1576872D01*
X248095Y1570205D01*
X250695Y1576872D01*
Y1568872D01*
G01X256895Y1573139D02*
X257295Y1573539D01*
X257595Y1574205D01*
X257795Y1575139D01*
X257595Y1575939D01*
X257195Y1576472D01*
X256495Y1576872D01*
X253795D01*
Y1568872D01*
X257095D01*
X257795Y1569405D01*
X258195Y1570205D01*
X258395Y1571139D01*
X258195Y1572072D01*
X257595Y1572872D01*
X256895Y1573139D01*
X253795D01*
G01X266095Y1568872D02*
X262095D01*
Y1576872D01*
X266095D01*
G01X264495Y1573005D02*
X262095D01*
G01X270095Y1568872D02*
Y1576872D01*
X272595D01*
X273395Y1576472D01*
X273895Y1575939D01*
X274095Y1574872D01*
X273895Y1573805D01*
X273295Y1573139D01*
X272595Y1572739D01*
X270095D01*
G01X272595D02*
X274095Y1568872D01*
G01X288095D02*
X287495Y1569005D01*
X286895Y1569539D01*
X286495Y1570472D01*
X286295Y1571539D01*
X286495Y1572605D01*
X286895Y1573539D01*
X287495Y1574072D01*
X288095Y1574205D01*
X288695Y1574072D01*
X289295Y1573539D01*
X289695Y1572605D01*
X289795Y1571539D01*
X289695Y1570472D01*
X289295Y1569539D01*
X288695Y1569005D01*
X288095Y1568872D01*
G01X294395D02*
Y1574205D01*
G01Y1572872D02*
X294795Y1573539D01*
X295395Y1574072D01*
X296195Y1574205D01*
X296895Y1574072D01*
X297495Y1573539D01*
X297795Y1572605D01*
Y1568872D01*
G01X309995Y1569938D02*
X310795Y1569272D01*
X311695Y1568872D01*
X312495D01*
X313295Y1569272D01*
X313895Y1569938D01*
X314195Y1570872D01*
X313995Y1571805D01*
X313495Y1572605D01*
X312595Y1573139D01*
X311395Y1573405D01*
X310695Y1573939D01*
X310395Y1574872D01*
X310595Y1575805D01*
X311095Y1576472D01*
X311795Y1576872D01*
X312495D01*
X313195Y1576605D01*
X313795Y1575939D01*
G01X318895Y1576872D02*
X321295D01*
G01X320095D02*
Y1568872D01*
G01X318895D02*
X321295D01*
G01X326095Y1576872D02*
Y1568872D01*
X330095D01*
G01X333895D02*
Y1576872D01*
G01X337695D02*
X333895Y1571938D01*
G01X338295Y1568872D02*
X335595Y1574205D01*
G01X341995Y1569938D02*
X342795Y1569272D01*
X343695Y1568872D01*
X344495D01*
X345295Y1569272D01*
X345895Y1569938D01*
X346195Y1570872D01*
X345995Y1571805D01*
X345495Y1572605D01*
X344595Y1573139D01*
X343395Y1573405D01*
X342695Y1573939D01*
X342395Y1574872D01*
X342595Y1575805D01*
X343095Y1576472D01*
X343795Y1576872D01*
X344495D01*
X345195Y1576605D01*
X345795Y1575939D01*
G01X354295Y1576205D02*
X353695Y1576605D01*
X352995Y1576872D01*
X352195D01*
X351295Y1576472D01*
X350595Y1575805D01*
X350095Y1575005D01*
X349695Y1573672D01*
X349595Y1572472D01*
X349795Y1571272D01*
X350095Y1570472D01*
X350695Y1569672D01*
X351395Y1569139D01*
X352095Y1568872D01*
X352795D01*
X353495Y1569139D01*
X354095Y1569539D01*
X354595Y1570072D01*
G01X358095Y1568872D02*
Y1576872D01*
X360595D01*
X361395Y1576472D01*
X361895Y1575939D01*
X362095Y1574872D01*
X361895Y1573805D01*
X361295Y1573139D01*
X360595Y1572739D01*
X358095D01*
G01X360595D02*
X362095Y1568872D01*
G01X370095D02*
X366095D01*
Y1576872D01*
X370095D01*
G01X368495Y1573005D02*
X366095D01*
G01X378095Y1568872D02*
X374095D01*
Y1576872D01*
X378095D01*
G01X376495Y1573005D02*
X374095D01*
G01X381795Y1568872D02*
Y1576872D01*
X386395Y1568872D01*
Y1576872D01*
G01X400095D02*
Y1568872D01*
G01X397795Y1576872D02*
X402395D01*
G01X408095Y1568872D02*
X407295Y1569005D01*
X406595Y1569539D01*
X405995Y1570339D01*
X405595Y1571272D01*
X405395Y1572339D01*
Y1573405D01*
X405595Y1574472D01*
X405995Y1575405D01*
X406595Y1576205D01*
X407295Y1576739D01*
X408095Y1576872D01*
X408895Y1576739D01*
X409595Y1576205D01*
X410195Y1575405D01*
X410595Y1574472D01*
X410795Y1573405D01*
Y1572339D01*
X410595Y1571272D01*
X410195Y1570339D01*
X409595Y1569539D01*
X408895Y1569005D01*
X408095Y1568872D01*
G01X414095D02*
Y1576872D01*
X416495D01*
X417295Y1576472D01*
X417895Y1575539D01*
X418095Y1574472D01*
X417895Y1573405D01*
X417395Y1572605D01*
X416495Y1572205D01*
X414095D01*
G01X429995Y1569938D02*
X430795Y1569272D01*
X431695Y1568872D01*
X432495D01*
X433295Y1569272D01*
X433895Y1569938D01*
X434195Y1570872D01*
X433995Y1571805D01*
X433495Y1572605D01*
X432595Y1573139D01*
X431395Y1573405D01*
X430695Y1573939D01*
X430395Y1574872D01*
X430595Y1575805D01*
X431095Y1576472D01*
X431795Y1576872D01*
X432495D01*
X433195Y1576605D01*
X433795Y1575939D01*
G01X438895Y1576872D02*
X441295D01*
G01X440095D02*
Y1568872D01*
G01X438895D02*
X441295D01*
G01X445895D02*
Y1576872D01*
X447895D01*
X448695Y1576472D01*
X449295Y1575939D01*
X449795Y1575139D01*
X450195Y1574205D01*
X450295Y1572872D01*
X450195Y1571539D01*
X449795Y1570605D01*
X449295Y1569805D01*
X448695Y1569272D01*
X447895Y1568872D01*
X445895D01*
G01X458095D02*
X454095D01*
Y1576872D01*
X458095D01*
G01X456495Y1573005D02*
X454095D01*
G01X-705Y1553872D02*
Y1561872D01*
X-4405Y1556139D01*
X595D01*
G01X6095Y1553605D02*
X5895Y1553739D01*
Y1554005D01*
X6095Y1554139D01*
X6295Y1554005D01*
Y1553739D01*
X6095Y1553605D01*
G01X16295Y1561205D02*
X15695Y1561605D01*
X14995Y1561872D01*
X14195D01*
X13295Y1561472D01*
X12595Y1560805D01*
X12095Y1560005D01*
X11695Y1558672D01*
X11595Y1557472D01*
X11795Y1556272D01*
X12095Y1555472D01*
X12695Y1554672D01*
X13395Y1554139D01*
X14095Y1553872D01*
X14795D01*
X15495Y1554139D01*
X16095Y1554539D01*
X16595Y1555072D01*
G01X22095Y1553872D02*
X21295Y1554005D01*
X20595Y1554539D01*
X19995Y1555339D01*
X19595Y1556272D01*
X19395Y1557339D01*
Y1558405D01*
X19595Y1559472D01*
X19995Y1560405D01*
X20595Y1561205D01*
X21295Y1561739D01*
X22095Y1561872D01*
X22895Y1561739D01*
X23595Y1561205D01*
X24195Y1560405D01*
X24595Y1559472D01*
X24795Y1558405D01*
Y1557339D01*
X24595Y1556272D01*
X24195Y1555339D01*
X23595Y1554539D01*
X22895Y1554005D01*
X22095Y1553872D01*
G01X27795D02*
Y1561872D01*
X32395Y1553872D01*
Y1561872D01*
G01X38095D02*
Y1553872D01*
G01X35795Y1561872D02*
X40395D01*
G01X44095Y1553872D02*
Y1561872D01*
X46595D01*
X47395Y1561472D01*
X47895Y1560939D01*
X48095Y1559872D01*
X47895Y1558805D01*
X47295Y1558139D01*
X46595Y1557739D01*
X44095D01*
G01X46595D02*
X48095Y1553872D01*
G01X54095D02*
X53295Y1554005D01*
X52595Y1554539D01*
X51995Y1555339D01*
X51595Y1556272D01*
X51395Y1557339D01*
Y1558405D01*
X51595Y1559472D01*
X51995Y1560405D01*
X52595Y1561205D01*
X53295Y1561739D01*
X54095Y1561872D01*
X54895Y1561739D01*
X55595Y1561205D01*
X56195Y1560405D01*
X56595Y1559472D01*
X56795Y1558405D01*
Y1557339D01*
X56595Y1556272D01*
X56195Y1555339D01*
X55595Y1554539D01*
X54895Y1554005D01*
X54095Y1553872D01*
G01X60095Y1561872D02*
Y1553872D01*
X64095D01*
G01X68095Y1561872D02*
Y1553872D01*
X72095D01*
G01X80095D02*
X76095D01*
Y1561872D01*
X80095D01*
G01X78495Y1558005D02*
X76095D01*
G01X83895Y1553872D02*
Y1561872D01*
X85895D01*
X86695Y1561472D01*
X87295Y1560939D01*
X87795Y1560139D01*
X88195Y1559205D01*
X88295Y1557872D01*
X88195Y1556539D01*
X87795Y1555605D01*
X87295Y1554805D01*
X86695Y1554272D01*
X85895Y1553872D01*
X83895D01*
G01X100895Y1561872D02*
X103295D01*
G01X102095D02*
Y1553872D01*
G01X100895D02*
X103295D01*
G01X107495D02*
Y1561872D01*
X110095Y1555205D01*
X112695Y1561872D01*
Y1553872D01*
G01X116095D02*
Y1561872D01*
X118495D01*
X119295Y1561472D01*
X119895Y1560539D01*
X120095Y1559472D01*
X119895Y1558405D01*
X119395Y1557605D01*
X118495Y1557205D01*
X116095D01*
G01X128095Y1553872D02*
X124095D01*
Y1561872D01*
X128095D01*
G01X126495Y1558005D02*
X124095D01*
G01X131895Y1553872D02*
Y1561872D01*
X133895D01*
X134695Y1561472D01*
X135295Y1560939D01*
X135795Y1560139D01*
X136195Y1559205D01*
X136295Y1557872D01*
X136195Y1556539D01*
X135795Y1555605D01*
X135295Y1554805D01*
X134695Y1554272D01*
X133895Y1553872D01*
X131895D01*
G01X139595D02*
X142095Y1561872D01*
X144595Y1553872D01*
G01X143695Y1556672D02*
X140495D01*
G01X147795Y1553872D02*
Y1561872D01*
X152395Y1553872D01*
Y1561872D01*
G01X160295Y1561205D02*
X159695Y1561605D01*
X158995Y1561872D01*
X158195D01*
X157295Y1561472D01*
X156595Y1560805D01*
X156095Y1560005D01*
X155695Y1558672D01*
X155595Y1557472D01*
X155795Y1556272D01*
X156095Y1555472D01*
X156695Y1554672D01*
X157395Y1554139D01*
X158095Y1553872D01*
X158795D01*
X159495Y1554139D01*
X160095Y1554539D01*
X160595Y1555072D01*
G01X168095Y1553872D02*
X164095D01*
Y1561872D01*
X168095D01*
G01X166495Y1558005D02*
X164095D01*
G01X182895Y1558139D02*
X183295Y1558539D01*
X183595Y1559205D01*
X183795Y1560139D01*
X183595Y1560939D01*
X183195Y1561472D01*
X182495Y1561872D01*
X179795D01*
Y1553872D01*
X183095D01*
X183795Y1554405D01*
X184195Y1555205D01*
X184395Y1556139D01*
X184195Y1557072D01*
X183595Y1557872D01*
X182895Y1558139D01*
X179795D01*
G01X190095Y1553872D02*
X189295Y1554005D01*
X188595Y1554539D01*
X187995Y1555339D01*
X187595Y1556272D01*
X187395Y1557339D01*
Y1558405D01*
X187595Y1559472D01*
X187995Y1560405D01*
X188595Y1561205D01*
X189295Y1561739D01*
X190095Y1561872D01*
X190895Y1561739D01*
X191595Y1561205D01*
X192195Y1560405D01*
X192595Y1559472D01*
X192795Y1558405D01*
Y1557339D01*
X192595Y1556272D01*
X192195Y1555339D01*
X191595Y1554539D01*
X190895Y1554005D01*
X190095Y1553872D01*
G01X195595D02*
X198095Y1561872D01*
X200595Y1553872D01*
G01X199695Y1556672D02*
X196495D01*
G01X204095Y1553872D02*
Y1561872D01*
X206595D01*
X207395Y1561472D01*
X207895Y1560939D01*
X208095Y1559872D01*
X207895Y1558805D01*
X207295Y1558139D01*
X206595Y1557739D01*
X204095D01*
G01X206595D02*
X208095Y1553872D01*
G01X211895D02*
Y1561872D01*
X213895D01*
X214695Y1561472D01*
X215295Y1560939D01*
X215795Y1560139D01*
X216195Y1559205D01*
X216295Y1557872D01*
X216195Y1556539D01*
X215795Y1555605D01*
X215295Y1554805D01*
X214695Y1554272D01*
X213895Y1553872D01*
X211895D01*
G01X222095Y1553605D02*
X221895Y1553739D01*
Y1554005D01*
X222095Y1554139D01*
X222295Y1554005D01*
Y1553739D01*
X222095Y1553605D01*
G01X235995Y1554938D02*
X236795Y1554272D01*
X237695Y1553872D01*
X238495D01*
X239295Y1554272D01*
X239895Y1554938D01*
X240195Y1555872D01*
X239995Y1556805D01*
X239495Y1557605D01*
X238595Y1558139D01*
X237395Y1558405D01*
X236695Y1558939D01*
X236395Y1559872D01*
X236595Y1560805D01*
X237095Y1561472D01*
X237795Y1561872D01*
X238495D01*
X239195Y1561605D01*
X239795Y1560939D01*
G01X248095Y1553872D02*
X244095D01*
Y1561872D01*
X248095D01*
G01X246495Y1558005D02*
X244095D01*
G01X256095Y1553872D02*
X252095D01*
Y1561872D01*
X256095D01*
G01X254495Y1558005D02*
X252095D01*
G01X268095Y1561872D02*
Y1553872D01*
X272095D01*
G01X275595D02*
X278095Y1561872D01*
X280595Y1553872D01*
G01X279695Y1556672D02*
X276495D01*
G01X286095Y1553872D02*
Y1557472D01*
X284095Y1561872D01*
G01X288095D02*
X286095Y1557472D01*
G01X296095Y1553872D02*
X292095D01*
Y1561872D01*
X296095D01*
G01X294495Y1558005D02*
X292095D01*
G01X300095Y1553872D02*
Y1561872D01*
X302595D01*
X303395Y1561472D01*
X303895Y1560939D01*
X304095Y1559872D01*
X303895Y1558805D01*
X303295Y1558139D01*
X302595Y1557739D01*
X300095D01*
G01X302595D02*
X304095Y1553872D01*
G01X315995Y1554938D02*
X316795Y1554272D01*
X317695Y1553872D01*
X318495D01*
X319295Y1554272D01*
X319895Y1554938D01*
X320195Y1555872D01*
X319995Y1556805D01*
X319495Y1557605D01*
X318595Y1558139D01*
X317395Y1558405D01*
X316695Y1558939D01*
X316395Y1559872D01*
X316595Y1560805D01*
X317095Y1561472D01*
X317795Y1561872D01*
X318495D01*
X319195Y1561605D01*
X319795Y1560939D01*
G01X326095Y1561872D02*
Y1553872D01*
G01X323795Y1561872D02*
X328395D01*
G01X331595Y1553872D02*
X334095Y1561872D01*
X336595Y1553872D01*
G01X335695Y1556672D02*
X332495D01*
G01X344295Y1561205D02*
X343695Y1561605D01*
X342995Y1561872D01*
X342195D01*
X341295Y1561472D01*
X340595Y1560805D01*
X340095Y1560005D01*
X339695Y1558672D01*
X339595Y1557472D01*
X339795Y1556272D01*
X340095Y1555472D01*
X340695Y1554672D01*
X341395Y1554139D01*
X342095Y1553872D01*
X342795D01*
X343495Y1554139D01*
X344095Y1554539D01*
X344595Y1555072D01*
G01X347895Y1553872D02*
Y1561872D01*
G01X351695D02*
X347895Y1556938D01*
G01X352295Y1553872D02*
X349595Y1559205D01*
G01X355895Y1561872D02*
Y1556139D01*
X356295Y1554938D01*
X357095Y1554139D01*
X358095Y1553872D01*
X359095Y1554139D01*
X359895Y1554938D01*
X360295Y1556139D01*
Y1561872D01*
G01X364095Y1553872D02*
Y1561872D01*
X366495D01*
X367295Y1561472D01*
X367895Y1560539D01*
X368095Y1559472D01*
X367895Y1558405D01*
X367395Y1557605D01*
X366495Y1557205D01*
X364095D01*
G01X379595Y1553872D02*
X382095Y1561872D01*
X384595Y1553872D01*
G01X383695Y1556672D02*
X380495D01*
G01X387795Y1553872D02*
Y1561872D01*
X392395Y1553872D01*
Y1561872D01*
G01X395895Y1553872D02*
Y1561872D01*
X397895D01*
X398695Y1561472D01*
X399295Y1560939D01*
X399795Y1560139D01*
X400195Y1559205D01*
X400295Y1557872D01*
X400195Y1556539D01*
X399795Y1555605D01*
X399295Y1554805D01*
X398695Y1554272D01*
X397895Y1553872D01*
X395895D01*
G01X412895Y1561872D02*
X415295D01*
G01X414095D02*
Y1553872D01*
G01X412895D02*
X415295D01*
G01X419495D02*
Y1561872D01*
X422095Y1555205D01*
X424695Y1561872D01*
Y1553872D01*
G01X428095D02*
Y1561872D01*
X430495D01*
X431295Y1561472D01*
X431895Y1560539D01*
X432095Y1559472D01*
X431895Y1558405D01*
X431395Y1557605D01*
X430495Y1557205D01*
X428095D01*
G01X440095Y1553872D02*
X436095D01*
Y1561872D01*
X440095D01*
G01X438495Y1558005D02*
X436095D01*
G01X443895Y1553872D02*
Y1561872D01*
X445895D01*
X446695Y1561472D01*
X447295Y1560939D01*
X447795Y1560139D01*
X448195Y1559205D01*
X448295Y1557872D01*
X448195Y1556539D01*
X447795Y1555605D01*
X447295Y1554805D01*
X446695Y1554272D01*
X445895Y1553872D01*
X443895D01*
G01X451595D02*
X454095Y1561872D01*
X456595Y1553872D01*
G01X455695Y1556672D02*
X452495D01*
G01X459795Y1553872D02*
Y1561872D01*
X464395Y1553872D01*
Y1561872D01*
G01X472295Y1561205D02*
X471695Y1561605D01*
X470995Y1561872D01*
X470195D01*
X469295Y1561472D01*
X468595Y1560805D01*
X468095Y1560005D01*
X467695Y1558672D01*
X467595Y1557472D01*
X467795Y1556272D01*
X468095Y1555472D01*
X468695Y1554672D01*
X469395Y1554139D01*
X470095Y1553872D01*
X470795D01*
X471495Y1554139D01*
X472095Y1554539D01*
X472595Y1555072D01*
G01X480095Y1553872D02*
X476095D01*
Y1561872D01*
X480095D01*
G01X478495Y1558005D02*
X476095D01*
G01X18095Y1598872D02*
X14095D01*
Y1606872D01*
X18095D01*
G01X16495Y1603005D02*
X14095D01*
G01X24095Y1598605D02*
X23895Y1598739D01*
Y1599005D01*
X24095Y1599139D01*
X24295Y1599005D01*
Y1598739D01*
X24095Y1598605D01*
G01X30095Y1598872D02*
Y1606872D01*
X32495D01*
X33295Y1606472D01*
X33895Y1605539D01*
X34095Y1604472D01*
X33895Y1603405D01*
X33395Y1602605D01*
X32495Y1602205D01*
X30095D01*
G01X38095Y1598872D02*
Y1606872D01*
X40595D01*
X41395Y1606472D01*
X41895Y1605939D01*
X42095Y1604872D01*
X41895Y1603805D01*
X41295Y1603139D01*
X40595Y1602739D01*
X38095D01*
G01X40595D02*
X42095Y1598872D01*
G01X48095D02*
X47295Y1599005D01*
X46595Y1599539D01*
X45995Y1600339D01*
X45595Y1601272D01*
X45395Y1602339D01*
Y1603405D01*
X45595Y1604472D01*
X45995Y1605405D01*
X46595Y1606205D01*
X47295Y1606739D01*
X48095Y1606872D01*
X48895Y1606739D01*
X49595Y1606205D01*
X50195Y1605405D01*
X50595Y1604472D01*
X50795Y1603405D01*
Y1602339D01*
X50595Y1601272D01*
X50195Y1600339D01*
X49595Y1599539D01*
X48895Y1599005D01*
X48095Y1598872D01*
G01X53595Y1606872D02*
X56095Y1598872D01*
X58595Y1606872D01*
G01X62895D02*
X65295D01*
G01X64095D02*
Y1598872D01*
G01X62895D02*
X65295D01*
G01X69895D02*
Y1606872D01*
X71895D01*
X72695Y1606472D01*
X73295Y1605939D01*
X73795Y1605139D01*
X74195Y1604205D01*
X74295Y1602872D01*
X74195Y1601539D01*
X73795Y1600605D01*
X73295Y1599805D01*
X72695Y1599272D01*
X71895Y1598872D01*
X69895D01*
G01X82095D02*
X78095D01*
Y1606872D01*
X82095D01*
G01X80495Y1603005D02*
X78095D01*
G01X94095Y1598872D02*
Y1606872D01*
X96495D01*
X97295Y1606472D01*
X97895Y1605539D01*
X98095Y1604472D01*
X97895Y1603405D01*
X97395Y1602605D01*
X96495Y1602205D01*
X94095D01*
G01X106295Y1606205D02*
X105695Y1606605D01*
X104995Y1606872D01*
X104195D01*
X103295Y1606472D01*
X102595Y1605805D01*
X102095Y1605005D01*
X101695Y1603672D01*
X101595Y1602472D01*
X101795Y1601272D01*
X102095Y1600472D01*
X102695Y1599672D01*
X103395Y1599139D01*
X104095Y1598872D01*
X104795D01*
X105495Y1599139D01*
X106095Y1599539D01*
X106595Y1600072D01*
G01X112895Y1603139D02*
X113295Y1603539D01*
X113595Y1604205D01*
X113795Y1605139D01*
X113595Y1605939D01*
X113195Y1606472D01*
X112495Y1606872D01*
X109795D01*
Y1598872D01*
X113095D01*
X113795Y1599405D01*
X114195Y1600205D01*
X114395Y1601139D01*
X114195Y1602072D01*
X113595Y1602872D01*
X112895Y1603139D01*
X109795D01*
G01X126195Y1598872D02*
Y1606872D01*
X129995D01*
G01X128595Y1603005D02*
X126195D01*
G01X134895Y1606872D02*
X137295D01*
G01X136095D02*
Y1598872D01*
G01X134895D02*
X137295D01*
G01X142095Y1606872D02*
Y1598872D01*
X146095D01*
G01X149495D02*
Y1606872D01*
X152095Y1600205D01*
X154695Y1606872D01*
Y1598872D01*
G01X14195Y1583872D02*
Y1591872D01*
X17995D01*
G01X16595Y1588005D02*
X14195D01*
G01X24095Y1583605D02*
X23895Y1583739D01*
Y1584005D01*
X24095Y1584139D01*
X24295Y1584005D01*
Y1583739D01*
X24095Y1583605D01*
G01X29795Y1583872D02*
Y1591872D01*
X34395Y1583872D01*
Y1591872D01*
G01X42095Y1583872D02*
X38095D01*
Y1591872D01*
X42095D01*
G01X40495Y1588005D02*
X38095D01*
G01X50095Y1583872D02*
X46095D01*
Y1591872D01*
X50095D01*
G01X48495Y1588005D02*
X46095D01*
G01X53895Y1583872D02*
Y1591872D01*
X55895D01*
X56695Y1591472D01*
X57295Y1590939D01*
X57795Y1590139D01*
X58195Y1589205D01*
X58295Y1587872D01*
X58195Y1586539D01*
X57795Y1585605D01*
X57295Y1584805D01*
X56695Y1584272D01*
X55895Y1583872D01*
X53895D01*
G01X70095D02*
Y1591872D01*
X72495D01*
X73295Y1591472D01*
X73895Y1590539D01*
X74095Y1589472D01*
X73895Y1588405D01*
X73395Y1587605D01*
X72495Y1587205D01*
X70095D01*
G01X82295Y1591205D02*
X81695Y1591605D01*
X80995Y1591872D01*
X80195D01*
X79295Y1591472D01*
X78595Y1590805D01*
X78095Y1590005D01*
X77695Y1588672D01*
X77595Y1587472D01*
X77795Y1586272D01*
X78095Y1585472D01*
X78695Y1584672D01*
X79395Y1584139D01*
X80095Y1583872D01*
X80795D01*
X81495Y1584139D01*
X82095Y1584539D01*
X82595Y1585072D01*
G01X88895Y1588139D02*
X89295Y1588539D01*
X89595Y1589205D01*
X89795Y1590139D01*
X89595Y1590939D01*
X89195Y1591472D01*
X88495Y1591872D01*
X85795D01*
Y1583872D01*
X89095D01*
X89795Y1584405D01*
X90195Y1585205D01*
X90395Y1586139D01*
X90195Y1587072D01*
X89595Y1587872D01*
X88895Y1588139D01*
X85795D01*
G01X101495Y1583872D02*
Y1591872D01*
X104095Y1585205D01*
X106695Y1591872D01*
Y1583872D01*
G01X109595D02*
X112095Y1591872D01*
X114595Y1583872D01*
G01X113695Y1586672D02*
X110495D01*
G01X117895Y1583872D02*
Y1591872D01*
G01X121695D02*
X117895Y1586938D01*
G01X122295Y1583872D02*
X119595Y1589205D01*
G01X130095Y1583872D02*
X126095D01*
Y1591872D01*
X130095D01*
G01X128495Y1588005D02*
X126095D01*
G01X134095Y1583872D02*
Y1591872D01*
X136595D01*
X137395Y1591472D01*
X137895Y1590939D01*
X138095Y1589872D01*
X137895Y1588805D01*
X137295Y1588139D01*
X136595Y1587739D01*
X134095D01*
G01X136595D02*
X138095Y1583872D01*
G01X150095Y1591872D02*
Y1583872D01*
X154095D01*
G01X160095D02*
X159295Y1584005D01*
X158595Y1584539D01*
X157995Y1585339D01*
X157595Y1586272D01*
X157395Y1587339D01*
Y1588405D01*
X157595Y1589472D01*
X157995Y1590405D01*
X158595Y1591205D01*
X159295Y1591739D01*
X160095Y1591872D01*
X160895Y1591739D01*
X161595Y1591205D01*
X162195Y1590405D01*
X162595Y1589472D01*
X162795Y1588405D01*
Y1587339D01*
X162595Y1586272D01*
X162195Y1585339D01*
X161595Y1584539D01*
X160895Y1584005D01*
X160095Y1583872D01*
G01X168695Y1587872D02*
X170695D01*
Y1585472D01*
X170095Y1584672D01*
X169395Y1584139D01*
X168395Y1583872D01*
X167395Y1584139D01*
X166695Y1584672D01*
X166095Y1585472D01*
X165695Y1586405D01*
X165495Y1587472D01*
Y1588405D01*
X165695Y1589205D01*
X166095Y1590139D01*
X166695Y1590939D01*
X167295Y1591472D01*
X168095Y1591872D01*
X168795D01*
X169595Y1591605D01*
X170195Y1591072D01*
G01X176095Y1583872D02*
X175295Y1584005D01*
X174595Y1584539D01*
X173995Y1585339D01*
X173595Y1586272D01*
X173395Y1587339D01*
Y1588405D01*
X173595Y1589472D01*
X173995Y1590405D01*
X174595Y1591205D01*
X175295Y1591739D01*
X176095Y1591872D01*
X176895Y1591739D01*
X177595Y1591205D01*
X178195Y1590405D01*
X178595Y1589472D01*
X178795Y1588405D01*
Y1587339D01*
X178595Y1586272D01*
X178195Y1585339D01*
X177595Y1584539D01*
X176895Y1584005D01*
X176095Y1583872D01*
G01X189595D02*
X192095Y1591872D01*
X194595Y1583872D01*
G01X193695Y1586672D02*
X190495D01*
G01X197795Y1583872D02*
Y1591872D01*
X202395Y1583872D01*
Y1591872D01*
G01X205895Y1583872D02*
Y1591872D01*
X207895D01*
X208695Y1591472D01*
X209295Y1590939D01*
X209795Y1590139D01*
X210195Y1589205D01*
X210295Y1587872D01*
X210195Y1586539D01*
X209795Y1585605D01*
X209295Y1584805D01*
X208695Y1584272D01*
X207895Y1583872D01*
X205895D01*
G01X221895D02*
Y1591872D01*
X223895D01*
X224695Y1591472D01*
X225295Y1590939D01*
X225795Y1590139D01*
X226195Y1589205D01*
X226295Y1587872D01*
X226195Y1586539D01*
X225795Y1585605D01*
X225295Y1584805D01*
X224695Y1584272D01*
X223895Y1583872D01*
X221895D01*
G01X229595D02*
X232095Y1591872D01*
X234595Y1583872D01*
G01X233695Y1586672D02*
X230495D01*
G01X240095Y1591872D02*
Y1583872D01*
G01X237795Y1591872D02*
X242395D01*
G01X250095Y1583872D02*
X246095D01*
Y1591872D01*
X250095D01*
G01X248495Y1588005D02*
X246095D01*
G01X266295Y1591205D02*
X265695Y1591605D01*
X264995Y1591872D01*
X264195D01*
X263295Y1591472D01*
X262595Y1590805D01*
X262095Y1590005D01*
X261695Y1588672D01*
X261595Y1587472D01*
X261795Y1586272D01*
X262095Y1585472D01*
X262695Y1584672D01*
X263395Y1584139D01*
X264095Y1583872D01*
X264795D01*
X265495Y1584139D01*
X266095Y1584539D01*
X266595Y1585072D01*
G01X272095Y1583872D02*
X271295Y1584005D01*
X270595Y1584539D01*
X269995Y1585339D01*
X269595Y1586272D01*
X269395Y1587339D01*
Y1588405D01*
X269595Y1589472D01*
X269995Y1590405D01*
X270595Y1591205D01*
X271295Y1591739D01*
X272095Y1591872D01*
X272895Y1591739D01*
X273595Y1591205D01*
X274195Y1590405D01*
X274595Y1589472D01*
X274795Y1588405D01*
Y1587339D01*
X274595Y1586272D01*
X274195Y1585339D01*
X273595Y1584539D01*
X272895Y1584005D01*
X272095Y1583872D01*
G01X277895D02*
Y1591872D01*
X279895D01*
X280695Y1591472D01*
X281295Y1590939D01*
X281795Y1590139D01*
X282195Y1589205D01*
X282295Y1587872D01*
X282195Y1586539D01*
X281795Y1585605D01*
X281295Y1584805D01*
X280695Y1584272D01*
X279895Y1583872D01*
X277895D01*
G01X290095D02*
X286095D01*
Y1591872D01*
X290095D01*
G01X288495Y1588005D02*
X286095D01*
G01X303595Y1581205D02*
X302595Y1582539D01*
X302095Y1583872D01*
Y1589205D01*
X302595Y1590539D01*
X303595Y1591872D01*
G01X309095D02*
X310495Y1583872D01*
X312095Y1591872D01*
X313695Y1583872D01*
X315095Y1591872D01*
G01X317095D02*
X318495Y1583872D01*
X320095Y1591872D01*
X321695Y1583872D01*
X323095Y1591872D01*
G01X328095Y1583872D02*
Y1587472D01*
X326095Y1591872D01*
G01X330095D02*
X328095Y1587472D01*
G01X336095Y1583872D02*
Y1587472D01*
X334095Y1591872D01*
G01X338095D02*
X336095Y1587472D01*
G01X344595Y1581205D02*
X345595Y1582539D01*
X346095Y1583872D01*
Y1589205D01*
X345595Y1590539D01*
X344595Y1591872D01*
G01X360095Y1583872D02*
X359495Y1584005D01*
X358895Y1584539D01*
X358495Y1585472D01*
X358295Y1586539D01*
X358495Y1587605D01*
X358895Y1588539D01*
X359495Y1589072D01*
X360095Y1589205D01*
X360695Y1589072D01*
X361295Y1588539D01*
X361695Y1587605D01*
X361795Y1586539D01*
X361695Y1585472D01*
X361295Y1584539D01*
X360695Y1584005D01*
X360095Y1583872D01*
G01X366395D02*
Y1589205D01*
G01Y1587872D02*
X366795Y1588539D01*
X367395Y1589072D01*
X368195Y1589205D01*
X368895Y1589072D01*
X369495Y1588539D01*
X369795Y1587605D01*
Y1583872D01*
G01X381995Y1584938D02*
X382795Y1584272D01*
X383695Y1583872D01*
X384495D01*
X385295Y1584272D01*
X385895Y1584938D01*
X386195Y1585872D01*
X385995Y1586805D01*
X385495Y1587605D01*
X384595Y1588139D01*
X383395Y1588405D01*
X382695Y1588939D01*
X382395Y1589872D01*
X382595Y1590805D01*
X383095Y1591472D01*
X383795Y1591872D01*
X384495D01*
X385195Y1591605D01*
X385795Y1590939D01*
G01X390895Y1591872D02*
X393295D01*
G01X392095D02*
Y1583872D01*
G01X390895D02*
X393295D01*
G01X398095Y1591872D02*
Y1583872D01*
X402095D01*
G01X405895D02*
Y1591872D01*
G01X409695D02*
X405895Y1586938D01*
G01X410295Y1583872D02*
X407595Y1589205D01*
G01X413995Y1584938D02*
X414795Y1584272D01*
X415695Y1583872D01*
X416495D01*
X417295Y1584272D01*
X417895Y1584938D01*
X418195Y1585872D01*
X417995Y1586805D01*
X417495Y1587605D01*
X416595Y1588139D01*
X415395Y1588405D01*
X414695Y1588939D01*
X414395Y1589872D01*
X414595Y1590805D01*
X415095Y1591472D01*
X415795Y1591872D01*
X416495D01*
X417195Y1591605D01*
X417795Y1590939D01*
G01X426295Y1591205D02*
X425695Y1591605D01*
X424995Y1591872D01*
X424195D01*
X423295Y1591472D01*
X422595Y1590805D01*
X422095Y1590005D01*
X421695Y1588672D01*
X421595Y1587472D01*
X421795Y1586272D01*
X422095Y1585472D01*
X422695Y1584672D01*
X423395Y1584139D01*
X424095Y1583872D01*
X424795D01*
X425495Y1584139D01*
X426095Y1584539D01*
X426595Y1585072D01*
G01X430095Y1583872D02*
Y1591872D01*
X432595D01*
X433395Y1591472D01*
X433895Y1590939D01*
X434095Y1589872D01*
X433895Y1588805D01*
X433295Y1588139D01*
X432595Y1587739D01*
X430095D01*
G01X432595D02*
X434095Y1583872D01*
G01X442095D02*
X438095D01*
Y1591872D01*
X442095D01*
G01X440495Y1588005D02*
X438095D01*
G01X450095Y1583872D02*
X446095D01*
Y1591872D01*
X450095D01*
G01X448495Y1588005D02*
X446095D01*
G01X453795Y1583872D02*
Y1591872D01*
X458395Y1583872D01*
Y1591872D01*
G01X472095D02*
Y1583872D01*
G01X469795Y1591872D02*
X474395D01*
G01X480095Y1583872D02*
X479295Y1584005D01*
X478595Y1584539D01*
X477995Y1585339D01*
X477595Y1586272D01*
X477395Y1587339D01*
Y1588405D01*
X477595Y1589472D01*
X477995Y1590405D01*
X478595Y1591205D01*
X479295Y1591739D01*
X480095Y1591872D01*
X480895Y1591739D01*
X481595Y1591205D01*
X482195Y1590405D01*
X482595Y1589472D01*
X482795Y1588405D01*
Y1587339D01*
X482595Y1586272D01*
X482195Y1585339D01*
X481595Y1584539D01*
X480895Y1584005D01*
X480095Y1583872D01*
G01X486095D02*
Y1591872D01*
X488495D01*
X489295Y1591472D01*
X489895Y1590539D01*
X490095Y1589472D01*
X489895Y1588405D01*
X489395Y1587605D01*
X488495Y1587205D01*
X486095D01*
G01X501995Y1584938D02*
X502795Y1584272D01*
X503695Y1583872D01*
X504495D01*
X505295Y1584272D01*
X505895Y1584938D01*
X506195Y1585872D01*
X505995Y1586805D01*
X505495Y1587605D01*
X504595Y1588139D01*
X503395Y1588405D01*
X502695Y1588939D01*
X502395Y1589872D01*
X502595Y1590805D01*
X503095Y1591472D01*
X503795Y1591872D01*
X504495D01*
X505195Y1591605D01*
X505795Y1590939D01*
G01X510895Y1591872D02*
X513295D01*
G01X512095D02*
Y1583872D01*
G01X510895D02*
X513295D01*
G01X517895D02*
Y1591872D01*
X519895D01*
X520695Y1591472D01*
X521295Y1590939D01*
X521795Y1590139D01*
X522195Y1589205D01*
X522295Y1587872D01*
X522195Y1586539D01*
X521795Y1585605D01*
X521295Y1584805D01*
X520695Y1584272D01*
X519895Y1583872D01*
X517895D01*
G01X530095D02*
X526095D01*
Y1591872D01*
X530095D01*
G01X528495Y1588005D02*
X526095D01*
G01X547095Y1581205D02*
X542095Y1589205D01*
Y1590539D01*
X543095Y1591872D01*
X544095D01*
X545095Y1590539D01*
Y1589205D01*
X544095Y1587872D01*
X542095Y1586539D01*
X541095Y1585205D01*
Y1582539D01*
X542095Y1581205D01*
X545095D01*
X547095Y1583872D01*
G01X560895Y1588139D02*
X561295Y1588539D01*
X561595Y1589205D01*
X561795Y1590139D01*
X561595Y1590939D01*
X561195Y1591472D01*
X560495Y1591872D01*
X557795D01*
Y1583872D01*
X561095D01*
X561795Y1584405D01*
X562195Y1585205D01*
X562395Y1586139D01*
X562195Y1587072D01*
X561595Y1587872D01*
X560895Y1588139D01*
X557795D01*
G01X566095Y1583872D02*
Y1591872D01*
X568595D01*
X569395Y1591472D01*
X569895Y1590939D01*
X570095Y1589872D01*
X569895Y1588805D01*
X569295Y1588139D01*
X568595Y1587739D01*
X566095D01*
G01X568595D02*
X570095Y1583872D01*
G01X578095D02*
X574095D01*
Y1591872D01*
X578095D01*
G01X576495Y1588005D02*
X574095D01*
G01X581595Y1583872D02*
X584095Y1591872D01*
X586595Y1583872D01*
G01X585695Y1586672D02*
X582495D01*
G01X589895Y1583872D02*
Y1591872D01*
G01X593695D02*
X589895Y1586938D01*
G01X594295Y1583872D02*
X591595Y1589205D01*
G01X597595Y1583872D02*
X600095Y1591872D01*
X602595Y1583872D01*
G01X601695Y1586672D02*
X598495D01*
G01X605095Y1591872D02*
X606495Y1583872D01*
X608095Y1591872D01*
X609695Y1583872D01*
X611095Y1591872D01*
G01X613595Y1583872D02*
X616095Y1591872D01*
X618595Y1583872D01*
G01X617695Y1586672D02*
X614495D01*
G01X624095Y1583872D02*
Y1587472D01*
X622095Y1591872D01*
G01X626095D02*
X624095Y1587472D01*
G01X18295Y1636205D02*
X17695Y1636605D01*
X16995Y1636872D01*
X16195D01*
X15295Y1636472D01*
X14595Y1635805D01*
X14095Y1635005D01*
X13695Y1633672D01*
X13595Y1632472D01*
X13795Y1631272D01*
X14095Y1630472D01*
X14695Y1629672D01*
X15395Y1629139D01*
X16095Y1628872D01*
X16795D01*
X17495Y1629139D01*
X18095Y1629539D01*
X18595Y1630072D01*
G01X24095Y1628605D02*
X23895Y1628739D01*
Y1629005D01*
X24095Y1629139D01*
X24295Y1629005D01*
Y1628739D01*
X24095Y1628605D01*
G01X29795Y1628872D02*
Y1636872D01*
X34395Y1628872D01*
Y1636872D01*
G01X40095Y1628872D02*
X39295Y1629005D01*
X38595Y1629539D01*
X37995Y1630339D01*
X37595Y1631272D01*
X37395Y1632339D01*
Y1633405D01*
X37595Y1634472D01*
X37995Y1635405D01*
X38595Y1636205D01*
X39295Y1636739D01*
X40095Y1636872D01*
X40895Y1636739D01*
X41595Y1636205D01*
X42195Y1635405D01*
X42595Y1634472D01*
X42795Y1633405D01*
Y1632339D01*
X42595Y1631272D01*
X42195Y1630339D01*
X41595Y1629539D01*
X40895Y1629005D01*
X40095Y1628872D01*
G01X53795D02*
Y1636872D01*
X58395Y1628872D01*
Y1636872D01*
G01X66095Y1628872D02*
X62095D01*
Y1636872D01*
X66095D01*
G01X64495Y1633005D02*
X62095D01*
G01X74095Y1628872D02*
X70095D01*
Y1636872D01*
X74095D01*
G01X72495Y1633005D02*
X70095D01*
G01X77895Y1628872D02*
Y1636872D01*
X79895D01*
X80695Y1636472D01*
X81295Y1635939D01*
X81795Y1635139D01*
X82195Y1634205D01*
X82295Y1632872D01*
X82195Y1631539D01*
X81795Y1630605D01*
X81295Y1629805D01*
X80695Y1629272D01*
X79895Y1628872D01*
X77895D01*
G01X96095Y1636872D02*
Y1628872D01*
G01X93795Y1636872D02*
X98395D01*
G01X104095Y1628872D02*
X103295Y1629005D01*
X102595Y1629539D01*
X101995Y1630339D01*
X101595Y1631272D01*
X101395Y1632339D01*
Y1633405D01*
X101595Y1634472D01*
X101995Y1635405D01*
X102595Y1636205D01*
X103295Y1636739D01*
X104095Y1636872D01*
X104895Y1636739D01*
X105595Y1636205D01*
X106195Y1635405D01*
X106595Y1634472D01*
X106795Y1633405D01*
Y1632339D01*
X106595Y1631272D01*
X106195Y1630339D01*
X105595Y1629539D01*
X104895Y1629005D01*
X104095Y1628872D01*
G01X118095D02*
Y1636872D01*
X120495D01*
X121295Y1636472D01*
X121895Y1635539D01*
X122095Y1634472D01*
X121895Y1633405D01*
X121395Y1632605D01*
X120495Y1632205D01*
X118095D01*
G01X126095Y1636872D02*
Y1628872D01*
X130095D01*
G01X133895Y1636872D02*
Y1631139D01*
X134295Y1629938D01*
X135095Y1629139D01*
X136095Y1628872D01*
X137095Y1629139D01*
X137895Y1629938D01*
X138295Y1631139D01*
Y1636872D01*
G01X144695Y1632872D02*
X146695D01*
Y1630472D01*
X146095Y1629672D01*
X145395Y1629139D01*
X144395Y1628872D01*
X143395Y1629139D01*
X142695Y1629672D01*
X142095Y1630472D01*
X141695Y1631405D01*
X141495Y1632472D01*
Y1633405D01*
X141695Y1634205D01*
X142095Y1635139D01*
X142695Y1635939D01*
X143295Y1636472D01*
X144095Y1636872D01*
X144795D01*
X145595Y1636605D01*
X146195Y1636072D01*
G01X160095Y1628872D02*
X160795Y1629005D01*
X161595Y1629405D01*
X162095Y1630072D01*
X162295Y1631005D01*
X162095Y1631938D01*
X161495Y1632739D01*
X160595Y1633139D01*
X159595D01*
X158995Y1633405D01*
X158495Y1634072D01*
X158295Y1635005D01*
X158595Y1635939D01*
X159295Y1636605D01*
X160095Y1636872D01*
X160895Y1636605D01*
X161595Y1635939D01*
X161895Y1635005D01*
X161695Y1634072D01*
X161195Y1633405D01*
X160595Y1633139D01*
X159595D01*
X158695Y1632739D01*
X158095Y1631938D01*
X157895Y1631005D01*
X158095Y1630072D01*
X158595Y1629405D01*
X159395Y1629005D01*
X160095Y1628872D01*
G01X173995D02*
Y1636872D01*
G01X178195D02*
Y1628872D01*
G01Y1632872D02*
X173995D01*
G01X184095Y1628872D02*
X183295Y1629005D01*
X182595Y1629539D01*
X181995Y1630339D01*
X181595Y1631272D01*
X181395Y1632339D01*
Y1633405D01*
X181595Y1634472D01*
X181995Y1635405D01*
X182595Y1636205D01*
X183295Y1636739D01*
X184095Y1636872D01*
X184895Y1636739D01*
X185595Y1636205D01*
X186195Y1635405D01*
X186595Y1634472D01*
X186795Y1633405D01*
Y1632339D01*
X186595Y1631272D01*
X186195Y1630339D01*
X185595Y1629539D01*
X184895Y1629005D01*
X184095Y1628872D01*
G01X190095Y1636872D02*
Y1628872D01*
X194095D01*
G01X202095D02*
X198095D01*
Y1636872D01*
X202095D01*
G01X200495Y1633005D02*
X198095D01*
G01X205995Y1629938D02*
X206795Y1629272D01*
X207695Y1628872D01*
X208495D01*
X209295Y1629272D01*
X209895Y1629938D01*
X210195Y1630872D01*
X209995Y1631805D01*
X209495Y1632605D01*
X208595Y1633139D01*
X207395Y1633405D01*
X206695Y1633939D01*
X206395Y1634872D01*
X206595Y1635805D01*
X207095Y1636472D01*
X207795Y1636872D01*
X208495D01*
X209195Y1636605D01*
X209795Y1635939D01*
G01X221995Y1629938D02*
X222795Y1629272D01*
X223695Y1628872D01*
X224495D01*
X225295Y1629272D01*
X225895Y1629938D01*
X226195Y1630872D01*
X225995Y1631805D01*
X225495Y1632605D01*
X224595Y1633139D01*
X223395Y1633405D01*
X222695Y1633939D01*
X222395Y1634872D01*
X222595Y1635805D01*
X223095Y1636472D01*
X223795Y1636872D01*
X224495D01*
X225195Y1636605D01*
X225795Y1635939D01*
G01X229895Y1636872D02*
Y1631139D01*
X230295Y1629938D01*
X231095Y1629139D01*
X232095Y1628872D01*
X233095Y1629139D01*
X233895Y1629938D01*
X234295Y1631139D01*
Y1636872D01*
G01X238095Y1628872D02*
Y1636872D01*
X240595D01*
X241395Y1636472D01*
X241895Y1635939D01*
X242095Y1634872D01*
X241895Y1633805D01*
X241295Y1633139D01*
X240595Y1632739D01*
X238095D01*
G01X240595D02*
X242095Y1628872D01*
G01X246095D02*
Y1636872D01*
X248595D01*
X249395Y1636472D01*
X249895Y1635939D01*
X250095Y1634872D01*
X249895Y1633805D01*
X249295Y1633139D01*
X248595Y1632739D01*
X246095D01*
G01X248595D02*
X250095Y1628872D01*
G01X256095D02*
X255295Y1629005D01*
X254595Y1629539D01*
X253995Y1630339D01*
X253595Y1631272D01*
X253395Y1632339D01*
Y1633405D01*
X253595Y1634472D01*
X253995Y1635405D01*
X254595Y1636205D01*
X255295Y1636739D01*
X256095Y1636872D01*
X256895Y1636739D01*
X257595Y1636205D01*
X258195Y1635405D01*
X258595Y1634472D01*
X258795Y1633405D01*
Y1632339D01*
X258595Y1631272D01*
X258195Y1630339D01*
X257595Y1629539D01*
X256895Y1629005D01*
X256095Y1628872D01*
G01X261895Y1636872D02*
Y1631139D01*
X262295Y1629938D01*
X263095Y1629139D01*
X264095Y1628872D01*
X265095Y1629139D01*
X265895Y1629938D01*
X266295Y1631139D01*
Y1636872D01*
G01X269795Y1628872D02*
Y1636872D01*
X274395Y1628872D01*
Y1636872D01*
G01X277895Y1628872D02*
Y1636872D01*
X279895D01*
X280695Y1636472D01*
X281295Y1635939D01*
X281795Y1635139D01*
X282195Y1634205D01*
X282295Y1632872D01*
X282195Y1631539D01*
X281795Y1630605D01*
X281295Y1629805D01*
X280695Y1629272D01*
X279895Y1628872D01*
X277895D01*
G01X286895Y1636872D02*
X289295D01*
G01X288095D02*
Y1628872D01*
G01X286895D02*
X289295D01*
G01X293795D02*
Y1636872D01*
X298395Y1628872D01*
Y1636872D01*
G01X304695Y1632872D02*
X306695D01*
Y1630472D01*
X306095Y1629672D01*
X305395Y1629139D01*
X304395Y1628872D01*
X303395Y1629139D01*
X302695Y1629672D01*
X302095Y1630472D01*
X301695Y1631405D01*
X301495Y1632472D01*
Y1633405D01*
X301695Y1634205D01*
X302095Y1635139D01*
X302695Y1635939D01*
X303295Y1636472D01*
X304095Y1636872D01*
X304795D01*
X305595Y1636605D01*
X306195Y1636072D01*
G01X317995Y1629938D02*
X318795Y1629272D01*
X319695Y1628872D01*
X320495D01*
X321295Y1629272D01*
X321895Y1629938D01*
X322195Y1630872D01*
X321995Y1631805D01*
X321495Y1632605D01*
X320595Y1633139D01*
X319395Y1633405D01*
X318695Y1633939D01*
X318395Y1634872D01*
X318595Y1635805D01*
X319095Y1636472D01*
X319795Y1636872D01*
X320495D01*
X321195Y1636605D01*
X321795Y1635939D01*
G01X330295Y1636205D02*
X329695Y1636605D01*
X328995Y1636872D01*
X328195D01*
X327295Y1636472D01*
X326595Y1635805D01*
X326095Y1635005D01*
X325695Y1633672D01*
X325595Y1632472D01*
X325795Y1631272D01*
X326095Y1630472D01*
X326695Y1629672D01*
X327395Y1629139D01*
X328095Y1628872D01*
X328795D01*
X329495Y1629139D01*
X330095Y1629539D01*
X330595Y1630072D01*
G01X334095Y1628872D02*
Y1636872D01*
X336595D01*
X337395Y1636472D01*
X337895Y1635939D01*
X338095Y1634872D01*
X337895Y1633805D01*
X337295Y1633139D01*
X336595Y1632739D01*
X334095D01*
G01X336595D02*
X338095Y1628872D01*
G01X346095D02*
X342095D01*
Y1636872D01*
X346095D01*
G01X344495Y1633005D02*
X342095D01*
G01X349095Y1636872D02*
X350495Y1628872D01*
X352095Y1636872D01*
X353695Y1628872D01*
X355095Y1636872D01*
G01X360095Y1628605D02*
X359895Y1628739D01*
Y1629005D01*
X360095Y1629139D01*
X360295Y1629005D01*
Y1628739D01*
X360095Y1628605D01*
G01X367595Y1626205D02*
X366595Y1627539D01*
X366095Y1628872D01*
Y1634205D01*
X366595Y1635539D01*
X367595Y1636872D01*
G01X374095Y1628872D02*
Y1636872D01*
X376495D01*
X377295Y1636472D01*
X377895Y1635539D01*
X378095Y1634472D01*
X377895Y1633405D01*
X377395Y1632605D01*
X376495Y1632205D01*
X374095D01*
G01X382095Y1636872D02*
Y1628872D01*
X386095D01*
G01X394095D02*
X390095D01*
Y1636872D01*
X394095D01*
G01X392495Y1633005D02*
X390095D01*
G01X397595Y1628872D02*
X400095Y1636872D01*
X402595Y1628872D01*
G01X401695Y1631672D02*
X398495D01*
G01X405995Y1629938D02*
X406795Y1629272D01*
X407695Y1628872D01*
X408495D01*
X409295Y1629272D01*
X409895Y1629938D01*
X410195Y1630872D01*
X409995Y1631805D01*
X409495Y1632605D01*
X408595Y1633139D01*
X407395Y1633405D01*
X406695Y1633939D01*
X406395Y1634872D01*
X406595Y1635805D01*
X407095Y1636472D01*
X407795Y1636872D01*
X408495D01*
X409195Y1636605D01*
X409795Y1635939D01*
G01X418095Y1628872D02*
X414095D01*
Y1636872D01*
X418095D01*
G01X416495Y1633005D02*
X414095D01*
G01X430895Y1636872D02*
X433295D01*
G01X432095D02*
Y1628872D01*
G01X430895D02*
X433295D01*
G01X440695Y1632872D02*
X442695D01*
Y1630472D01*
X442095Y1629672D01*
X441395Y1629139D01*
X440395Y1628872D01*
X439395Y1629139D01*
X438695Y1629672D01*
X438095Y1630472D01*
X437695Y1631405D01*
X437495Y1632472D01*
Y1633405D01*
X437695Y1634205D01*
X438095Y1635139D01*
X438695Y1635939D01*
X439295Y1636472D01*
X440095Y1636872D01*
X440795D01*
X441595Y1636605D01*
X442195Y1636072D01*
G01X445795Y1628872D02*
Y1636872D01*
X450395Y1628872D01*
Y1636872D01*
G01X456095Y1628872D02*
X455295Y1629005D01*
X454595Y1629539D01*
X453995Y1630339D01*
X453595Y1631272D01*
X453395Y1632339D01*
Y1633405D01*
X453595Y1634472D01*
X453995Y1635405D01*
X454595Y1636205D01*
X455295Y1636739D01*
X456095Y1636872D01*
X456895Y1636739D01*
X457595Y1636205D01*
X458195Y1635405D01*
X458595Y1634472D01*
X458795Y1633405D01*
Y1632339D01*
X458595Y1631272D01*
X458195Y1630339D01*
X457595Y1629539D01*
X456895Y1629005D01*
X456095Y1628872D01*
G01X462095D02*
Y1636872D01*
X464595D01*
X465395Y1636472D01*
X465895Y1635939D01*
X466095Y1634872D01*
X465895Y1633805D01*
X465295Y1633139D01*
X464595Y1632739D01*
X462095D01*
G01X464595D02*
X466095Y1628872D01*
G01X474095D02*
X470095D01*
Y1636872D01*
X474095D01*
G01X472495Y1633005D02*
X470095D01*
G01X488095Y1636872D02*
Y1628872D01*
G01X485795Y1636872D02*
X490395D01*
G01X493995Y1628872D02*
Y1636872D01*
G01X498195D02*
Y1628872D01*
G01Y1632872D02*
X493995D01*
G01X502895Y1636872D02*
X505295D01*
G01X504095D02*
Y1628872D01*
G01X502895D02*
X505295D01*
G01X509995Y1629938D02*
X510795Y1629272D01*
X511695Y1628872D01*
X512495D01*
X513295Y1629272D01*
X513895Y1629938D01*
X514195Y1630872D01*
X513995Y1631805D01*
X513495Y1632605D01*
X512595Y1633139D01*
X511395Y1633405D01*
X510695Y1633939D01*
X510395Y1634872D01*
X510595Y1635805D01*
X511095Y1636472D01*
X511795Y1636872D01*
X512495D01*
X513195Y1636605D01*
X513795Y1635939D01*
G01X526895Y1636872D02*
X529295D01*
G01X528095D02*
Y1628872D01*
G01X526895D02*
X529295D01*
G01X534195D02*
Y1636872D01*
X537995D01*
G01X536595Y1633005D02*
X534195D01*
G01X549795Y1628872D02*
Y1636872D01*
X554395Y1628872D01*
Y1636872D01*
G01X560095Y1628872D02*
X559295Y1629005D01*
X558595Y1629539D01*
X557995Y1630339D01*
X557595Y1631272D01*
X557395Y1632339D01*
Y1633405D01*
X557595Y1634472D01*
X557995Y1635405D01*
X558595Y1636205D01*
X559295Y1636739D01*
X560095Y1636872D01*
X560895Y1636739D01*
X561595Y1636205D01*
X562195Y1635405D01*
X562595Y1634472D01*
X562795Y1633405D01*
Y1632339D01*
X562595Y1631272D01*
X562195Y1630339D01*
X561595Y1629539D01*
X560895Y1629005D01*
X560095Y1628872D01*
G01X576095Y1636872D02*
Y1628872D01*
G01X573795Y1636872D02*
X578395D01*
G01X581995Y1628872D02*
Y1636872D01*
G01X586195D02*
Y1628872D01*
G01Y1632872D02*
X581995D01*
G01X590895Y1636872D02*
X593295D01*
G01X592095D02*
Y1628872D01*
G01X590895D02*
X593295D01*
G01X597995Y1629938D02*
X598795Y1629272D01*
X599695Y1628872D01*
X600495D01*
X601295Y1629272D01*
X601895Y1629938D01*
X602195Y1630872D01*
X601995Y1631805D01*
X601495Y1632605D01*
X600595Y1633139D01*
X599395Y1633405D01*
X598695Y1633939D01*
X598395Y1634872D01*
X598595Y1635805D01*
X599095Y1636472D01*
X599795Y1636872D01*
X600495D01*
X601195Y1636605D01*
X601795Y1635939D01*
G01X614895Y1636872D02*
X617295D01*
G01X616095D02*
Y1628872D01*
G01X614895D02*
X617295D01*
G01X624095Y1636872D02*
Y1628872D01*
G01X621795Y1636872D02*
X626395D01*
G01X634095Y1628872D02*
X630095D01*
Y1636872D01*
X634095D01*
G01X632495Y1633005D02*
X630095D01*
G01X637495Y1628872D02*
Y1636872D01*
X640095Y1630205D01*
X642695Y1636872D01*
Y1628872D01*
G01X654895Y1636872D02*
X657295D01*
G01X656095D02*
Y1628872D01*
G01X654895D02*
X657295D01*
G01X661795D02*
Y1636872D01*
X666395Y1628872D01*
Y1636872D01*
G01X680895Y1633139D02*
X681295Y1633539D01*
X681595Y1634205D01*
X681795Y1635139D01*
X681595Y1635939D01*
X681195Y1636472D01*
X680495Y1636872D01*
X677795D01*
Y1628872D01*
X681095D01*
X681795Y1629405D01*
X682195Y1630205D01*
X682395Y1631139D01*
X682195Y1632072D01*
X681595Y1632872D01*
X680895Y1633139D01*
X677795D01*
G01X688095Y1628872D02*
X687295Y1629005D01*
X686595Y1629539D01*
X685995Y1630339D01*
X685595Y1631272D01*
X685395Y1632339D01*
Y1633405D01*
X685595Y1634472D01*
X685995Y1635405D01*
X686595Y1636205D01*
X687295Y1636739D01*
X688095Y1636872D01*
X688895Y1636739D01*
X689595Y1636205D01*
X690195Y1635405D01*
X690595Y1634472D01*
X690795Y1633405D01*
Y1632339D01*
X690595Y1631272D01*
X690195Y1630339D01*
X689595Y1629539D01*
X688895Y1629005D01*
X688095Y1628872D01*
G01X693595D02*
X696095Y1636872D01*
X698595Y1628872D01*
G01X697695Y1631672D02*
X694495D01*
G01X702095Y1628872D02*
Y1636872D01*
X704595D01*
X705395Y1636472D01*
X705895Y1635939D01*
X706095Y1634872D01*
X705895Y1633805D01*
X705295Y1633139D01*
X704595Y1632739D01*
X702095D01*
G01X704595D02*
X706095Y1628872D01*
G01X709895D02*
Y1636872D01*
X711895D01*
X712695Y1636472D01*
X713295Y1635939D01*
X713795Y1635139D01*
X714195Y1634205D01*
X714295Y1632872D01*
X714195Y1631539D01*
X713795Y1630605D01*
X713295Y1629805D01*
X712695Y1629272D01*
X711895Y1628872D01*
X709895D01*
G01X726195D02*
Y1636872D01*
X729995D01*
G01X728595Y1633005D02*
X726195D01*
G01X734895Y1636872D02*
X737295D01*
G01X736095D02*
Y1628872D01*
G01X734895D02*
X737295D01*
G01X742095Y1636872D02*
Y1628872D01*
X746095D01*
G01X754095D02*
X750095D01*
Y1636872D01*
X754095D01*
G01X752495Y1633005D02*
X750095D01*
G01X760595Y1626205D02*
X761595Y1627539D01*
X762095Y1628872D01*
Y1634205D01*
X761595Y1635539D01*
X760595Y1636872D01*
G01X13895Y1613872D02*
Y1621872D01*
X15895D01*
X16695Y1621472D01*
X17295Y1620939D01*
X17795Y1620139D01*
X18195Y1619205D01*
X18295Y1617872D01*
X18195Y1616539D01*
X17795Y1615605D01*
X17295Y1614805D01*
X16695Y1614272D01*
X15895Y1613872D01*
X13895D01*
G01X24095Y1613605D02*
X23895Y1613739D01*
Y1614005D01*
X24095Y1614139D01*
X24295Y1614005D01*
Y1613739D01*
X24095Y1613605D01*
G01X30095Y1613872D02*
Y1621872D01*
X32495D01*
X33295Y1621472D01*
X33895Y1620539D01*
X34095Y1619472D01*
X33895Y1618405D01*
X33395Y1617605D01*
X32495Y1617205D01*
X30095D01*
G01X38095Y1613872D02*
Y1621872D01*
X40595D01*
X41395Y1621472D01*
X41895Y1620939D01*
X42095Y1619872D01*
X41895Y1618805D01*
X41295Y1618139D01*
X40595Y1617739D01*
X38095D01*
G01X40595D02*
X42095Y1613872D01*
G01X48095D02*
X47295Y1614005D01*
X46595Y1614539D01*
X45995Y1615339D01*
X45595Y1616272D01*
X45395Y1617339D01*
Y1618405D01*
X45595Y1619472D01*
X45995Y1620405D01*
X46595Y1621205D01*
X47295Y1621739D01*
X48095Y1621872D01*
X48895Y1621739D01*
X49595Y1621205D01*
X50195Y1620405D01*
X50595Y1619472D01*
X50795Y1618405D01*
Y1617339D01*
X50595Y1616272D01*
X50195Y1615339D01*
X49595Y1614539D01*
X48895Y1614005D01*
X48095Y1613872D01*
G01X53595Y1621872D02*
X56095Y1613872D01*
X58595Y1621872D01*
G01X62895D02*
X65295D01*
G01X64095D02*
Y1613872D01*
G01X62895D02*
X65295D01*
G01X69895D02*
Y1621872D01*
X71895D01*
X72695Y1621472D01*
X73295Y1620939D01*
X73795Y1620139D01*
X74195Y1619205D01*
X74295Y1617872D01*
X74195Y1616539D01*
X73795Y1615605D01*
X73295Y1614805D01*
X72695Y1614272D01*
X71895Y1613872D01*
X69895D01*
G01X82095D02*
X78095D01*
Y1621872D01*
X82095D01*
G01X80495Y1618005D02*
X78095D01*
G01X94895Y1621872D02*
X97295D01*
G01X96095D02*
Y1613872D01*
G01X94895D02*
X97295D01*
G01X101495D02*
Y1621872D01*
X104095Y1615205D01*
X106695Y1621872D01*
Y1613872D01*
G01X110095D02*
Y1621872D01*
X112495D01*
X113295Y1621472D01*
X113895Y1620539D01*
X114095Y1619472D01*
X113895Y1618405D01*
X113395Y1617605D01*
X112495Y1617205D01*
X110095D01*
G01X122095Y1613872D02*
X118095D01*
Y1621872D01*
X122095D01*
G01X120495Y1618005D02*
X118095D01*
G01X125895Y1613872D02*
Y1621872D01*
X127895D01*
X128695Y1621472D01*
X129295Y1620939D01*
X129795Y1620139D01*
X130195Y1619205D01*
X130295Y1617872D01*
X130195Y1616539D01*
X129795Y1615605D01*
X129295Y1614805D01*
X128695Y1614272D01*
X127895Y1613872D01*
X125895D01*
G01X133595D02*
X136095Y1621872D01*
X138595Y1613872D01*
G01X137695Y1616672D02*
X134495D01*
G01X141795Y1613872D02*
Y1621872D01*
X146395Y1613872D01*
Y1621872D01*
G01X154295Y1621205D02*
X153695Y1621605D01*
X152995Y1621872D01*
X152195D01*
X151295Y1621472D01*
X150595Y1620805D01*
X150095Y1620005D01*
X149695Y1618672D01*
X149595Y1617472D01*
X149795Y1616272D01*
X150095Y1615472D01*
X150695Y1614672D01*
X151395Y1614139D01*
X152095Y1613872D01*
X152795D01*
X153495Y1614139D01*
X154095Y1614539D01*
X154595Y1615072D01*
G01X162095Y1613872D02*
X158095D01*
Y1621872D01*
X162095D01*
G01X160495Y1618005D02*
X158095D01*
G01X178295Y1621205D02*
X177695Y1621605D01*
X176995Y1621872D01*
X176195D01*
X175295Y1621472D01*
X174595Y1620805D01*
X174095Y1620005D01*
X173695Y1618672D01*
X173595Y1617472D01*
X173795Y1616272D01*
X174095Y1615472D01*
X174695Y1614672D01*
X175395Y1614139D01*
X176095Y1613872D01*
X176795D01*
X177495Y1614139D01*
X178095Y1614539D01*
X178595Y1615072D01*
G01X184095Y1613872D02*
X183295Y1614005D01*
X182595Y1614539D01*
X181995Y1615339D01*
X181595Y1616272D01*
X181395Y1617339D01*
Y1618405D01*
X181595Y1619472D01*
X181995Y1620405D01*
X182595Y1621205D01*
X183295Y1621739D01*
X184095Y1621872D01*
X184895Y1621739D01*
X185595Y1621205D01*
X186195Y1620405D01*
X186595Y1619472D01*
X186795Y1618405D01*
Y1617339D01*
X186595Y1616272D01*
X186195Y1615339D01*
X185595Y1614539D01*
X184895Y1614005D01*
X184095Y1613872D01*
G01X189895Y1621872D02*
Y1616139D01*
X190295Y1614938D01*
X191095Y1614139D01*
X192095Y1613872D01*
X193095Y1614139D01*
X193895Y1614938D01*
X194295Y1616139D01*
Y1621872D01*
G01X198095Y1613872D02*
Y1621872D01*
X200495D01*
X201295Y1621472D01*
X201895Y1620539D01*
X202095Y1619472D01*
X201895Y1618405D01*
X201395Y1617605D01*
X200495Y1617205D01*
X198095D01*
G01X208095Y1613872D02*
X207295Y1614005D01*
X206595Y1614539D01*
X205995Y1615339D01*
X205595Y1616272D01*
X205395Y1617339D01*
Y1618405D01*
X205595Y1619472D01*
X205995Y1620405D01*
X206595Y1621205D01*
X207295Y1621739D01*
X208095Y1621872D01*
X208895Y1621739D01*
X209595Y1621205D01*
X210195Y1620405D01*
X210595Y1619472D01*
X210795Y1618405D01*
Y1617339D01*
X210595Y1616272D01*
X210195Y1615339D01*
X209595Y1614539D01*
X208895Y1614005D01*
X208095Y1613872D01*
G01X213795D02*
Y1621872D01*
X218395Y1613872D01*
Y1621872D01*
G01X229595Y1613872D02*
X232095Y1621872D01*
X234595Y1613872D01*
G01X233695Y1616672D02*
X230495D01*
G01X237795Y1613872D02*
Y1621872D01*
X242395Y1613872D01*
Y1621872D01*
G01X245895Y1613872D02*
Y1621872D01*
X247895D01*
X248695Y1621472D01*
X249295Y1620939D01*
X249795Y1620139D01*
X250195Y1619205D01*
X250295Y1617872D01*
X250195Y1616539D01*
X249795Y1615605D01*
X249295Y1614805D01*
X248695Y1614272D01*
X247895Y1613872D01*
X245895D01*
G01X261495D02*
Y1621872D01*
X264095Y1615205D01*
X266695Y1621872D01*
Y1613872D01*
G01X274095D02*
X270095D01*
Y1621872D01*
X274095D01*
G01X272495Y1618005D02*
X270095D01*
G01X277595Y1613872D02*
X280095Y1621872D01*
X282595Y1613872D01*
G01X281695Y1616672D02*
X278495D01*
G01X285995Y1614938D02*
X286795Y1614272D01*
X287695Y1613872D01*
X288495D01*
X289295Y1614272D01*
X289895Y1614938D01*
X290195Y1615872D01*
X289995Y1616805D01*
X289495Y1617605D01*
X288595Y1618139D01*
X287395Y1618405D01*
X286695Y1618939D01*
X286395Y1619872D01*
X286595Y1620805D01*
X287095Y1621472D01*
X287795Y1621872D01*
X288495D01*
X289195Y1621605D01*
X289795Y1620939D01*
G01X293895Y1621872D02*
Y1616139D01*
X294295Y1614938D01*
X295095Y1614139D01*
X296095Y1613872D01*
X297095Y1614139D01*
X297895Y1614938D01*
X298295Y1616139D01*
Y1621872D01*
G01X302095Y1613872D02*
Y1621872D01*
X304595D01*
X305395Y1621472D01*
X305895Y1620939D01*
X306095Y1619872D01*
X305895Y1618805D01*
X305295Y1618139D01*
X304595Y1617739D01*
X302095D01*
G01X304595D02*
X306095Y1613872D01*
G01X314095D02*
X310095D01*
Y1621872D01*
X314095D01*
G01X312495Y1618005D02*
X310095D01*
G01X317495Y1613872D02*
Y1621872D01*
X320095Y1615205D01*
X322695Y1621872D01*
Y1613872D01*
G01X330095D02*
X326095D01*
Y1621872D01*
X330095D01*
G01X328495Y1618005D02*
X326095D01*
G01X333795Y1613872D02*
Y1621872D01*
X338395Y1613872D01*
Y1621872D01*
G01X344095D02*
Y1613872D01*
G01X341795Y1621872D02*
X346395D01*
G01X358095Y1613872D02*
Y1621872D01*
X360595D01*
X361395Y1621472D01*
X361895Y1620939D01*
X362095Y1619872D01*
X361895Y1618805D01*
X361295Y1618139D01*
X360595Y1617739D01*
X358095D01*
G01X360595D02*
X362095Y1613872D01*
G01X370095D02*
X366095D01*
Y1621872D01*
X370095D01*
G01X368495Y1618005D02*
X366095D01*
G01X374095Y1613872D02*
Y1621872D01*
X376495D01*
X377295Y1621472D01*
X377895Y1620539D01*
X378095Y1619472D01*
X377895Y1618405D01*
X377395Y1617605D01*
X376495Y1617205D01*
X374095D01*
G01X384095Y1613872D02*
X383295Y1614005D01*
X382595Y1614539D01*
X381995Y1615339D01*
X381595Y1616272D01*
X381395Y1617339D01*
Y1618405D01*
X381595Y1619472D01*
X381995Y1620405D01*
X382595Y1621205D01*
X383295Y1621739D01*
X384095Y1621872D01*
X384895Y1621739D01*
X385595Y1621205D01*
X386195Y1620405D01*
X386595Y1619472D01*
X386795Y1618405D01*
Y1617339D01*
X386595Y1616272D01*
X386195Y1615339D01*
X385595Y1614539D01*
X384895Y1614005D01*
X384095Y1613872D01*
G01X390095D02*
Y1621872D01*
X392595D01*
X393395Y1621472D01*
X393895Y1620939D01*
X394095Y1619872D01*
X393895Y1618805D01*
X393295Y1618139D01*
X392595Y1617739D01*
X390095D01*
G01X392595D02*
X394095Y1613872D01*
G01X400095Y1621872D02*
Y1613872D01*
G01X397795Y1621872D02*
X402395D01*
G01X16895Y1648139D02*
X17295Y1648539D01*
X17595Y1649205D01*
X17795Y1650139D01*
X17595Y1650939D01*
X17195Y1651472D01*
X16495Y1651872D01*
X13795D01*
Y1643872D01*
X17095D01*
X17795Y1644405D01*
X18195Y1645205D01*
X18395Y1646139D01*
X18195Y1647072D01*
X17595Y1647872D01*
X16895Y1648139D01*
X13795D01*
G01X24095Y1643605D02*
X23895Y1643739D01*
Y1644005D01*
X24095Y1644139D01*
X24295Y1644005D01*
Y1643739D01*
X24095Y1643605D01*
G01X29595Y1643872D02*
X32095Y1651872D01*
X34595Y1643872D01*
G01X33695Y1646672D02*
X30495D01*
G01X38095Y1651872D02*
Y1643872D01*
X42095D01*
G01X46095Y1651872D02*
Y1643872D01*
X50095D01*
G01X61595Y1651872D02*
X64095Y1643872D01*
X66595Y1651872D01*
G01X70895D02*
X73295D01*
G01X72095D02*
Y1643872D01*
G01X70895D02*
X73295D01*
G01X77595D02*
X80095Y1651872D01*
X82595Y1643872D01*
G01X81695Y1646672D02*
X78495D01*
G01X85995Y1644938D02*
X86795Y1644272D01*
X87695Y1643872D01*
X88495D01*
X89295Y1644272D01*
X89895Y1644938D01*
X90195Y1645872D01*
X89995Y1646805D01*
X89495Y1647605D01*
X88595Y1648139D01*
X87395Y1648405D01*
X86695Y1648939D01*
X86395Y1649872D01*
X86595Y1650805D01*
X87095Y1651472D01*
X87795Y1651872D01*
X88495D01*
X89195Y1651605D01*
X89795Y1650939D01*
G01X102095Y1643872D02*
Y1651872D01*
X104495D01*
X105295Y1651472D01*
X105895Y1650539D01*
X106095Y1649472D01*
X105895Y1648405D01*
X105395Y1647605D01*
X104495Y1647205D01*
X102095D01*
G01X110095Y1651872D02*
Y1643872D01*
X114095D01*
G01X117895Y1651872D02*
Y1646139D01*
X118295Y1644938D01*
X119095Y1644139D01*
X120095Y1643872D01*
X121095Y1644139D01*
X121895Y1644938D01*
X122295Y1646139D01*
Y1651872D01*
G01X128695Y1647872D02*
X130695D01*
Y1645472D01*
X130095Y1644672D01*
X129395Y1644139D01*
X128395Y1643872D01*
X127395Y1644139D01*
X126695Y1644672D01*
X126095Y1645472D01*
X125695Y1646405D01*
X125495Y1647472D01*
Y1648405D01*
X125695Y1649205D01*
X126095Y1650139D01*
X126695Y1650939D01*
X127295Y1651472D01*
X128095Y1651872D01*
X128795D01*
X129595Y1651605D01*
X130195Y1651072D01*
G01X136695Y1647872D02*
X138695D01*
Y1645472D01*
X138095Y1644672D01*
X137395Y1644139D01*
X136395Y1643872D01*
X135395Y1644139D01*
X134695Y1644672D01*
X134095Y1645472D01*
X133695Y1646405D01*
X133495Y1647472D01*
Y1648405D01*
X133695Y1649205D01*
X134095Y1650139D01*
X134695Y1650939D01*
X135295Y1651472D01*
X136095Y1651872D01*
X136795D01*
X137595Y1651605D01*
X138195Y1651072D01*
G01X146095Y1643872D02*
X142095D01*
Y1651872D01*
X146095D01*
G01X144495Y1648005D02*
X142095D01*
G01X149895Y1643872D02*
Y1651872D01*
X151895D01*
X152695Y1651472D01*
X153295Y1650939D01*
X153795Y1650139D01*
X154195Y1649205D01*
X154295Y1647872D01*
X154195Y1646539D01*
X153795Y1645605D01*
X153295Y1644805D01*
X152695Y1644272D01*
X151895Y1643872D01*
X149895D01*
G01X170095D02*
X166095D01*
Y1651872D01*
X170095D01*
G01X168495Y1648005D02*
X166095D01*
G01X173995Y1643872D02*
X178195Y1651872D01*
G01X173995D02*
X178195Y1643872D01*
G01X186295Y1651205D02*
X185695Y1651605D01*
X184995Y1651872D01*
X184195D01*
X183295Y1651472D01*
X182595Y1650805D01*
X182095Y1650005D01*
X181695Y1648672D01*
X181595Y1647472D01*
X181795Y1646272D01*
X182095Y1645472D01*
X182695Y1644672D01*
X183395Y1644139D01*
X184095Y1643872D01*
X184795D01*
X185495Y1644139D01*
X186095Y1644539D01*
X186595Y1645072D01*
G01X194095Y1643872D02*
X190095D01*
Y1651872D01*
X194095D01*
G01X192495Y1648005D02*
X190095D01*
G01X198095Y1643872D02*
Y1651872D01*
X200495D01*
X201295Y1651472D01*
X201895Y1650539D01*
X202095Y1649472D01*
X201895Y1648405D01*
X201395Y1647605D01*
X200495Y1647205D01*
X198095D01*
G01X208095Y1651872D02*
Y1643872D01*
G01X205795Y1651872D02*
X210395D01*
G01X222195Y1643872D02*
Y1651872D01*
X225995D01*
G01X224595Y1648005D02*
X222195D01*
G01X232095Y1643872D02*
X231295Y1644005D01*
X230595Y1644539D01*
X229995Y1645339D01*
X229595Y1646272D01*
X229395Y1647339D01*
Y1648405D01*
X229595Y1649472D01*
X229995Y1650405D01*
X230595Y1651205D01*
X231295Y1651739D01*
X232095Y1651872D01*
X232895Y1651739D01*
X233595Y1651205D01*
X234195Y1650405D01*
X234595Y1649472D01*
X234795Y1648405D01*
Y1647339D01*
X234595Y1646272D01*
X234195Y1645339D01*
X233595Y1644539D01*
X232895Y1644005D01*
X232095Y1643872D01*
G01X238095D02*
Y1651872D01*
X240595D01*
X241395Y1651472D01*
X241895Y1650939D01*
X242095Y1649872D01*
X241895Y1648805D01*
X241295Y1648139D01*
X240595Y1647739D01*
X238095D01*
G01X240595D02*
X242095Y1643872D01*
G01X13595Y1658872D02*
X16095Y1666872D01*
X18595Y1658872D01*
G01X17695Y1661672D02*
X14495D01*
G01X24095Y1658605D02*
X23895Y1658739D01*
Y1659005D01*
X24095Y1659139D01*
X24295Y1659005D01*
Y1658739D01*
X24095Y1658605D01*
G01X29595Y1666872D02*
X32095Y1658872D01*
X34595Y1666872D01*
G01X38895D02*
X41295D01*
G01X40095D02*
Y1658872D01*
G01X38895D02*
X41295D01*
G01X45595D02*
X48095Y1666872D01*
X50595Y1658872D01*
G01X49695Y1661672D02*
X46495D01*
G01X64095Y1666872D02*
Y1658872D01*
G01X61795Y1666872D02*
X66395D01*
G01X74095Y1658872D02*
X70095D01*
Y1666872D01*
X74095D01*
G01X72495Y1663005D02*
X70095D01*
G01X77595Y1658872D02*
X80095Y1666872D01*
X82595Y1658872D01*
G01X81695Y1661672D02*
X78495D01*
G01X86095Y1658872D02*
Y1666872D01*
X88595D01*
X89395Y1666472D01*
X89895Y1665939D01*
X90095Y1664872D01*
X89895Y1663805D01*
X89295Y1663139D01*
X88595Y1662739D01*
X86095D01*
G01X88595D02*
X90095Y1658872D01*
G01X101895D02*
Y1666872D01*
X103895D01*
X104695Y1666472D01*
X105295Y1665939D01*
X105795Y1665139D01*
X106195Y1664205D01*
X106295Y1662872D01*
X106195Y1661539D01*
X105795Y1660605D01*
X105295Y1659805D01*
X104695Y1659272D01*
X103895Y1658872D01*
X101895D01*
G01X110095D02*
Y1666872D01*
X112595D01*
X113395Y1666472D01*
X113895Y1665939D01*
X114095Y1664872D01*
X113895Y1663805D01*
X113295Y1663139D01*
X112595Y1662739D01*
X110095D01*
G01X112595D02*
X114095Y1658872D01*
G01X120095D02*
X119295Y1659005D01*
X118595Y1659539D01*
X117995Y1660339D01*
X117595Y1661272D01*
X117395Y1662339D01*
Y1663405D01*
X117595Y1664472D01*
X117995Y1665405D01*
X118595Y1666205D01*
X119295Y1666739D01*
X120095Y1666872D01*
X120895Y1666739D01*
X121595Y1666205D01*
X122195Y1665405D01*
X122595Y1664472D01*
X122795Y1663405D01*
Y1662339D01*
X122595Y1661272D01*
X122195Y1660339D01*
X121595Y1659539D01*
X120895Y1659005D01*
X120095Y1658872D01*
G01X126095D02*
Y1666872D01*
X128495D01*
X129295Y1666472D01*
X129895Y1665539D01*
X130095Y1664472D01*
X129895Y1663405D01*
X129395Y1662605D01*
X128495Y1662205D01*
X126095D01*
G01X143595Y1656205D02*
X142595Y1657539D01*
X142095Y1658872D01*
Y1664205D01*
X142595Y1665539D01*
X143595Y1666872D01*
G01X150195Y1658872D02*
Y1666872D01*
X153995D01*
G01X152595Y1663005D02*
X150195D01*
G01X160095Y1658872D02*
X159295Y1659005D01*
X158595Y1659539D01*
X157995Y1660339D01*
X157595Y1661272D01*
X157395Y1662339D01*
Y1663405D01*
X157595Y1664472D01*
X157995Y1665405D01*
X158595Y1666205D01*
X159295Y1666739D01*
X160095Y1666872D01*
X160895Y1666739D01*
X161595Y1666205D01*
X162195Y1665405D01*
X162595Y1664472D01*
X162795Y1663405D01*
Y1662339D01*
X162595Y1661272D01*
X162195Y1660339D01*
X161595Y1659539D01*
X160895Y1659005D01*
X160095Y1658872D01*
G01X166095D02*
Y1666872D01*
X168595D01*
X169395Y1666472D01*
X169895Y1665939D01*
X170095Y1664872D01*
X169895Y1663805D01*
X169295Y1663139D01*
X168595Y1662739D01*
X166095D01*
G01X168595D02*
X170095Y1658872D01*
G01X181595D02*
X184095Y1666872D01*
X186595Y1658872D01*
G01X185695Y1661672D02*
X182495D01*
G01X190095Y1666872D02*
Y1658872D01*
X194095D01*
G01X198095Y1666872D02*
Y1658872D01*
X202095D01*
G01X213595Y1666872D02*
X216095Y1658872D01*
X218595Y1666872D01*
G01X222895D02*
X225295D01*
G01X224095D02*
Y1658872D01*
G01X222895D02*
X225295D01*
G01X229595D02*
X232095Y1666872D01*
X234595Y1658872D01*
G01X233695Y1661672D02*
X230495D01*
G01X237995Y1659938D02*
X238795Y1659272D01*
X239695Y1658872D01*
X240495D01*
X241295Y1659272D01*
X241895Y1659938D01*
X242195Y1660872D01*
X241995Y1661805D01*
X241495Y1662605D01*
X240595Y1663139D01*
X239395Y1663405D01*
X238695Y1663939D01*
X238395Y1664872D01*
X238595Y1665805D01*
X239095Y1666472D01*
X239795Y1666872D01*
X240495D01*
X241195Y1666605D01*
X241795Y1665939D01*
G01X253595Y1658872D02*
X256095Y1666872D01*
X258595Y1658872D01*
G01X257695Y1661672D02*
X254495D01*
G01X261795Y1658872D02*
Y1666872D01*
X266395Y1658872D01*
Y1666872D01*
G01X269895Y1658872D02*
Y1666872D01*
X271895D01*
X272695Y1666472D01*
X273295Y1665939D01*
X273795Y1665139D01*
X274195Y1664205D01*
X274295Y1662872D01*
X274195Y1661539D01*
X273795Y1660605D01*
X273295Y1659805D01*
X272695Y1659272D01*
X271895Y1658872D01*
X269895D01*
G01X286095D02*
Y1666872D01*
X288495D01*
X289295Y1666472D01*
X289895Y1665539D01*
X290095Y1664472D01*
X289895Y1663405D01*
X289395Y1662605D01*
X288495Y1662205D01*
X286095D01*
G01X294895Y1666872D02*
X297295D01*
G01X296095D02*
Y1658872D01*
G01X294895D02*
X297295D01*
G01X301795D02*
Y1666872D01*
X306395Y1658872D01*
Y1666872D01*
G01X309995Y1659938D02*
X310795Y1659272D01*
X311695Y1658872D01*
X312495D01*
X313295Y1659272D01*
X313895Y1659938D01*
X314195Y1660872D01*
X313995Y1661805D01*
X313495Y1662605D01*
X312595Y1663139D01*
X311395Y1663405D01*
X310695Y1663939D01*
X310395Y1664872D01*
X310595Y1665805D01*
X311095Y1666472D01*
X311795Y1666872D01*
X312495D01*
X313195Y1666605D01*
X313795Y1665939D01*
G01X320595Y1656205D02*
X321595Y1657539D01*
X322095Y1658872D01*
Y1664205D01*
X321595Y1665539D01*
X320595Y1666872D01*
G01X328095Y1658605D02*
X327895Y1658739D01*
Y1659005D01*
X328095Y1659139D01*
X328295Y1659005D01*
Y1658739D01*
X328095Y1658605D01*
G01X-3805Y1695539D02*
X-3205Y1696339D01*
X-2505Y1696739D01*
X-1705Y1696872D01*
X-705Y1696605D01*
X-5Y1695939D01*
X195Y1695139D01*
X95Y1694338D01*
X-305Y1693672D01*
X-2305Y1692339D01*
X-3205Y1691405D01*
X-3805Y1690072D01*
X-4005Y1688872D01*
X195D01*
G01X6095Y1688605D02*
X5895Y1688739D01*
Y1689005D01*
X6095Y1689139D01*
X6295Y1689005D01*
Y1688739D01*
X6095Y1688605D01*
G01X12195Y1688872D02*
Y1696872D01*
X15995D01*
G01X14595Y1693005D02*
X12195D01*
G01X19595Y1688872D02*
X22095Y1696872D01*
X24595Y1688872D01*
G01X23695Y1691672D02*
X20495D01*
G01X30895Y1693139D02*
X31295Y1693539D01*
X31595Y1694205D01*
X31795Y1695139D01*
X31595Y1695939D01*
X31195Y1696472D01*
X30495Y1696872D01*
X27795D01*
Y1688872D01*
X31095D01*
X31795Y1689405D01*
X32195Y1690205D01*
X32395Y1691139D01*
X32195Y1692072D01*
X31595Y1692872D01*
X30895Y1693139D01*
X27795D01*
G01X36095Y1688872D02*
Y1696872D01*
X38595D01*
X39395Y1696472D01*
X39895Y1695939D01*
X40095Y1694872D01*
X39895Y1693805D01*
X39295Y1693139D01*
X38595Y1692739D01*
X36095D01*
G01X38595D02*
X40095Y1688872D01*
G01X44895Y1696872D02*
X47295D01*
G01X46095D02*
Y1688872D01*
G01X44895D02*
X47295D01*
G01X56295Y1696205D02*
X55695Y1696605D01*
X54995Y1696872D01*
X54195D01*
X53295Y1696472D01*
X52595Y1695805D01*
X52095Y1695005D01*
X51695Y1693672D01*
X51595Y1692472D01*
X51795Y1691272D01*
X52095Y1690472D01*
X52695Y1689672D01*
X53395Y1689139D01*
X54095Y1688872D01*
X54795D01*
X55495Y1689139D01*
X56095Y1689539D01*
X56595Y1690072D01*
G01X59595Y1688872D02*
X62095Y1696872D01*
X64595Y1688872D01*
G01X63695Y1691672D02*
X60495D01*
G01X70095Y1696872D02*
Y1688872D01*
G01X67795Y1696872D02*
X72395D01*
G01X80095Y1688872D02*
X76095D01*
Y1696872D01*
X80095D01*
G01X78495Y1693005D02*
X76095D01*
G01X92095Y1688872D02*
Y1696872D01*
X94495D01*
X95295Y1696472D01*
X95895Y1695539D01*
X96095Y1694472D01*
X95895Y1693405D01*
X95395Y1692605D01*
X94495Y1692205D01*
X92095D01*
G01X104095Y1688872D02*
X100095D01*
Y1696872D01*
X104095D01*
G01X102495Y1693005D02*
X100095D01*
G01X108095Y1688872D02*
Y1696872D01*
X110595D01*
X111395Y1696472D01*
X111895Y1695939D01*
X112095Y1694872D01*
X111895Y1693805D01*
X111295Y1693139D01*
X110595Y1692739D01*
X108095D01*
G01X110595D02*
X112095Y1688872D01*
G01X126095D02*
X125295Y1689005D01*
X124595Y1689539D01*
X123995Y1690339D01*
X123595Y1691272D01*
X123395Y1692339D01*
Y1693405D01*
X123595Y1694472D01*
X123995Y1695405D01*
X124595Y1696205D01*
X125295Y1696739D01*
X126095Y1696872D01*
X126895Y1696739D01*
X127595Y1696205D01*
X128195Y1695405D01*
X128595Y1694472D01*
X128795Y1693405D01*
Y1692339D01*
X128595Y1691272D01*
X128195Y1690339D01*
X127595Y1689539D01*
X126895Y1689005D01*
X126095Y1688872D01*
G01X126895Y1691005D02*
X128095Y1688872D01*
G01X131895Y1696872D02*
Y1691139D01*
X132295Y1689938D01*
X133095Y1689139D01*
X134095Y1688872D01*
X135095Y1689139D01*
X135895Y1689938D01*
X136295Y1691139D01*
Y1696872D01*
G01X139595Y1688872D02*
X142095Y1696872D01*
X144595Y1688872D01*
G01X143695Y1691672D02*
X140495D01*
G01X147795Y1688872D02*
Y1696872D01*
X152395Y1688872D01*
Y1696872D01*
G01X158095D02*
Y1688872D01*
G01X155795Y1696872D02*
X160395D01*
G01X163595Y1688872D02*
X166095Y1696872D01*
X168595Y1688872D01*
G01X167695Y1691672D02*
X164495D01*
G01X180095Y1688872D02*
Y1696872D01*
X182495D01*
X183295Y1696472D01*
X183895Y1695539D01*
X184095Y1694472D01*
X183895Y1693405D01*
X183395Y1692605D01*
X182495Y1692205D01*
X180095D01*
G01X192295Y1696205D02*
X191695Y1696605D01*
X190995Y1696872D01*
X190195D01*
X189295Y1696472D01*
X188595Y1695805D01*
X188095Y1695005D01*
X187695Y1693672D01*
X187595Y1692472D01*
X187795Y1691272D01*
X188095Y1690472D01*
X188695Y1689672D01*
X189395Y1689139D01*
X190095Y1688872D01*
X190795D01*
X191495Y1689139D01*
X192095Y1689539D01*
X192595Y1690072D01*
G01X198895Y1693139D02*
X199295Y1693539D01*
X199595Y1694205D01*
X199795Y1695139D01*
X199595Y1695939D01*
X199195Y1696472D01*
X198495Y1696872D01*
X195795D01*
Y1688872D01*
X199095D01*
X199795Y1689405D01*
X200195Y1690205D01*
X200395Y1691139D01*
X200195Y1692072D01*
X199595Y1692872D01*
X198895Y1693139D01*
X195795D01*
G01X211995Y1689938D02*
X212795Y1689272D01*
X213695Y1688872D01*
X214495D01*
X215295Y1689272D01*
X215895Y1689938D01*
X216195Y1690872D01*
X215995Y1691805D01*
X215495Y1692605D01*
X214595Y1693139D01*
X213395Y1693405D01*
X212695Y1693939D01*
X212395Y1694872D01*
X212595Y1695805D01*
X213095Y1696472D01*
X213795Y1696872D01*
X214495D01*
X215195Y1696605D01*
X215795Y1695939D01*
G01X220095Y1688872D02*
Y1696872D01*
X222495D01*
X223295Y1696472D01*
X223895Y1695539D01*
X224095Y1694472D01*
X223895Y1693405D01*
X223395Y1692605D01*
X222495Y1692205D01*
X220095D01*
G01X232095Y1688872D02*
X228095D01*
Y1696872D01*
X232095D01*
G01X230495Y1693005D02*
X228095D01*
G01X240295Y1696205D02*
X239695Y1696605D01*
X238995Y1696872D01*
X238195D01*
X237295Y1696472D01*
X236595Y1695805D01*
X236095Y1695005D01*
X235695Y1693672D01*
X235595Y1692472D01*
X235795Y1691272D01*
X236095Y1690472D01*
X236695Y1689672D01*
X237395Y1689139D01*
X238095Y1688872D01*
X238795D01*
X239495Y1689139D01*
X240095Y1689539D01*
X240595Y1690072D01*
G01X244895Y1696872D02*
X247295D01*
G01X246095D02*
Y1688872D01*
G01X244895D02*
X247295D01*
G01X252195D02*
Y1696872D01*
X255995D01*
G01X254595Y1693005D02*
X252195D01*
G01X260895Y1696872D02*
X263295D01*
G01X262095D02*
Y1688872D01*
G01X260895D02*
X263295D01*
G01X272295Y1696205D02*
X271695Y1696605D01*
X270995Y1696872D01*
X270195D01*
X269295Y1696472D01*
X268595Y1695805D01*
X268095Y1695005D01*
X267695Y1693672D01*
X267595Y1692472D01*
X267795Y1691272D01*
X268095Y1690472D01*
X268695Y1689672D01*
X269395Y1689139D01*
X270095Y1688872D01*
X270795D01*
X271495Y1689139D01*
X272095Y1689539D01*
X272595Y1690072D01*
G01X275595Y1688872D02*
X278095Y1696872D01*
X280595Y1688872D01*
G01X279695Y1691672D02*
X276495D01*
G01X286095Y1696872D02*
Y1688872D01*
G01X283795Y1696872D02*
X288395D01*
G01X292895D02*
X295295D01*
G01X294095D02*
Y1688872D01*
G01X292895D02*
X295295D01*
G01X302095D02*
X301295Y1689005D01*
X300595Y1689539D01*
X299995Y1690339D01*
X299595Y1691272D01*
X299395Y1692339D01*
Y1693405D01*
X299595Y1694472D01*
X299995Y1695405D01*
X300595Y1696205D01*
X301295Y1696739D01*
X302095Y1696872D01*
X302895Y1696739D01*
X303595Y1696205D01*
X304195Y1695405D01*
X304595Y1694472D01*
X304795Y1693405D01*
Y1692339D01*
X304595Y1691272D01*
X304195Y1690339D01*
X303595Y1689539D01*
X302895Y1689005D01*
X302095Y1688872D01*
G01X307795D02*
Y1696872D01*
X312395Y1688872D01*
Y1696872D01*
G01X329095Y1686205D02*
X324095Y1694205D01*
Y1695539D01*
X325095Y1696872D01*
X326095D01*
X327095Y1695539D01*
Y1694205D01*
X326095Y1692872D01*
X324095Y1691539D01*
X323095Y1690205D01*
Y1687539D01*
X324095Y1686205D01*
X327095D01*
X329095Y1688872D01*
G01X342095D02*
X341295Y1689005D01*
X340595Y1689539D01*
X339995Y1690339D01*
X339595Y1691272D01*
X339395Y1692339D01*
Y1693405D01*
X339595Y1694472D01*
X339995Y1695405D01*
X340595Y1696205D01*
X341295Y1696739D01*
X342095Y1696872D01*
X342895Y1696739D01*
X343595Y1696205D01*
X344195Y1695405D01*
X344595Y1694472D01*
X344795Y1693405D01*
Y1692339D01*
X344595Y1691272D01*
X344195Y1690339D01*
X343595Y1689539D01*
X342895Y1689005D01*
X342095Y1688872D01*
G01X342895Y1691005D02*
X344095Y1688872D01*
G01X352295Y1696205D02*
X351695Y1696605D01*
X350995Y1696872D01*
X350195D01*
X349295Y1696472D01*
X348595Y1695805D01*
X348095Y1695005D01*
X347695Y1693672D01*
X347595Y1692472D01*
X347795Y1691272D01*
X348095Y1690472D01*
X348695Y1689672D01*
X349395Y1689139D01*
X350095Y1688872D01*
X350795D01*
X351495Y1689139D01*
X352095Y1689539D01*
X352595Y1690072D01*
G01X358095Y1696872D02*
Y1688872D01*
G01X355795Y1696872D02*
X360395D01*
G01X376095Y1688872D02*
X372095D01*
Y1696872D01*
X376095D01*
G01X374495Y1693005D02*
X372095D01*
G01X382095Y1688872D02*
X381295Y1689005D01*
X380595Y1689539D01*
X379995Y1690339D01*
X379595Y1691272D01*
X379395Y1692339D01*
Y1693405D01*
X379595Y1694472D01*
X379995Y1695405D01*
X380595Y1696205D01*
X381295Y1696739D01*
X382095Y1696872D01*
X382895Y1696739D01*
X383595Y1696205D01*
X384195Y1695405D01*
X384595Y1694472D01*
X384795Y1693405D01*
Y1692339D01*
X384595Y1691272D01*
X384195Y1690339D01*
X383595Y1689539D01*
X382895Y1689005D01*
X382095Y1688872D01*
G01X382895Y1691005D02*
X384095Y1688872D01*
G01X396195D02*
Y1696872D01*
X399995D01*
G01X398595Y1693005D02*
X396195D01*
G01X403595Y1688872D02*
X406095Y1696872D01*
X408595Y1688872D01*
G01X407695Y1691672D02*
X404495D01*
G01X414095Y1688872D02*
X413295Y1689005D01*
X412595Y1689539D01*
X411995Y1690339D01*
X411595Y1691272D01*
X411395Y1692339D01*
Y1693405D01*
X411595Y1694472D01*
X411995Y1695405D01*
X412595Y1696205D01*
X413295Y1696739D01*
X414095Y1696872D01*
X414895Y1696739D01*
X415595Y1696205D01*
X416195Y1695405D01*
X416595Y1694472D01*
X416795Y1693405D01*
Y1692339D01*
X416595Y1691272D01*
X416195Y1690339D01*
X415595Y1689539D01*
X414895Y1689005D01*
X414095Y1688872D01*
G01X414895Y1691005D02*
X416095Y1688872D01*
G01X422095Y1688605D02*
X421895Y1688739D01*
Y1689005D01*
X422095Y1689139D01*
X422295Y1689005D01*
Y1688739D01*
X422095Y1688605D01*
G01X-4105Y1675472D02*
X-3505Y1674539D01*
X-2705Y1674005D01*
X-1805Y1673872D01*
X-1005Y1674005D01*
X-205Y1674672D01*
X295Y1675472D01*
X395Y1676272D01*
X195Y1677205D01*
X-505Y1677872D01*
X-1205Y1678139D01*
X-2105D01*
G01X-1205D02*
X-605Y1678539D01*
X-105Y1679205D01*
X95Y1680005D01*
X-105Y1680805D01*
X-605Y1681472D01*
X-1505Y1681872D01*
X-2405Y1681739D01*
X-3305Y1681205D01*
G01X6095Y1673605D02*
X5895Y1673739D01*
Y1674005D01*
X6095Y1674139D01*
X6295Y1674005D01*
Y1673739D01*
X6095Y1673605D01*
G01X12095Y1673872D02*
Y1681872D01*
X14495D01*
X15295Y1681472D01*
X15895Y1680539D01*
X16095Y1679472D01*
X15895Y1678405D01*
X15395Y1677605D01*
X14495Y1677205D01*
X12095D01*
G01X24295Y1681205D02*
X23695Y1681605D01*
X22995Y1681872D01*
X22195D01*
X21295Y1681472D01*
X20595Y1680805D01*
X20095Y1680005D01*
X19695Y1678672D01*
X19595Y1677472D01*
X19795Y1676272D01*
X20095Y1675472D01*
X20695Y1674672D01*
X21395Y1674139D01*
X22095Y1673872D01*
X22795D01*
X23495Y1674139D01*
X24095Y1674539D01*
X24595Y1675072D01*
G01X30895Y1678139D02*
X31295Y1678539D01*
X31595Y1679205D01*
X31795Y1680139D01*
X31595Y1680939D01*
X31195Y1681472D01*
X30495Y1681872D01*
X27795D01*
Y1673872D01*
X31095D01*
X31795Y1674405D01*
X32195Y1675205D01*
X32395Y1676139D01*
X32195Y1677072D01*
X31595Y1677872D01*
X30895Y1678139D01*
X27795D01*
G01X44095Y1673872D02*
Y1681872D01*
X46495D01*
X47295Y1681472D01*
X47895Y1680539D01*
X48095Y1679472D01*
X47895Y1678405D01*
X47395Y1677605D01*
X46495Y1677205D01*
X44095D01*
G01X52095Y1673872D02*
Y1681872D01*
X54595D01*
X55395Y1681472D01*
X55895Y1680939D01*
X56095Y1679872D01*
X55895Y1678805D01*
X55295Y1678139D01*
X54595Y1677739D01*
X52095D01*
G01X54595D02*
X56095Y1673872D01*
G01X62095D02*
X61295Y1674005D01*
X60595Y1674539D01*
X59995Y1675339D01*
X59595Y1676272D01*
X59395Y1677339D01*
Y1678405D01*
X59595Y1679472D01*
X59995Y1680405D01*
X60595Y1681205D01*
X61295Y1681739D01*
X62095Y1681872D01*
X62895Y1681739D01*
X63595Y1681205D01*
X64195Y1680405D01*
X64595Y1679472D01*
X64795Y1678405D01*
Y1677339D01*
X64595Y1676272D01*
X64195Y1675339D01*
X63595Y1674539D01*
X62895Y1674005D01*
X62095Y1673872D01*
G01X72295Y1681205D02*
X71695Y1681605D01*
X70995Y1681872D01*
X70195D01*
X69295Y1681472D01*
X68595Y1680805D01*
X68095Y1680005D01*
X67695Y1678672D01*
X67595Y1677472D01*
X67795Y1676272D01*
X68095Y1675472D01*
X68695Y1674672D01*
X69395Y1674139D01*
X70095Y1673872D01*
X70795D01*
X71495Y1674139D01*
X72095Y1674539D01*
X72595Y1675072D01*
G01X80095Y1673872D02*
X76095D01*
Y1681872D01*
X80095D01*
G01X78495Y1678005D02*
X76095D01*
G01X83995Y1674938D02*
X84795Y1674272D01*
X85695Y1673872D01*
X86495D01*
X87295Y1674272D01*
X87895Y1674938D01*
X88195Y1675872D01*
X87995Y1676805D01*
X87495Y1677605D01*
X86595Y1678139D01*
X85395Y1678405D01*
X84695Y1678939D01*
X84395Y1679872D01*
X84595Y1680805D01*
X85095Y1681472D01*
X85795Y1681872D01*
X86495D01*
X87195Y1681605D01*
X87795Y1680939D01*
G01X91995Y1674938D02*
X92795Y1674272D01*
X93695Y1673872D01*
X94495D01*
X95295Y1674272D01*
X95895Y1674938D01*
X96195Y1675872D01*
X95995Y1676805D01*
X95495Y1677605D01*
X94595Y1678139D01*
X93395Y1678405D01*
X92695Y1678939D01*
X92395Y1679872D01*
X92595Y1680805D01*
X93095Y1681472D01*
X93795Y1681872D01*
X94495D01*
X95195Y1681605D01*
X95795Y1680939D01*
G01X102095Y1673605D02*
X101895Y1673739D01*
Y1674005D01*
X102095Y1674139D01*
X102295Y1674005D01*
Y1673739D01*
X102095Y1673605D01*
G01Y1677205D02*
X101895Y1677339D01*
Y1677605D01*
X102095Y1677739D01*
X102295Y1677605D01*
Y1677339D01*
X102095Y1677205D01*
G01X-4205Y1718872D02*
Y1726872D01*
X395Y1718872D01*
Y1726872D01*
G01X6095Y1718872D02*
X5295Y1719005D01*
X4595Y1719539D01*
X3995Y1720339D01*
X3595Y1721272D01*
X3395Y1722339D01*
Y1723405D01*
X3595Y1724472D01*
X3995Y1725405D01*
X4595Y1726205D01*
X5295Y1726739D01*
X6095Y1726872D01*
X6895Y1726739D01*
X7595Y1726205D01*
X8195Y1725405D01*
X8595Y1724472D01*
X8795Y1723405D01*
Y1722339D01*
X8595Y1721272D01*
X8195Y1720339D01*
X7595Y1719539D01*
X6895Y1719005D01*
X6095Y1718872D01*
G01X14095Y1726872D02*
Y1718872D01*
G01X11795Y1726872D02*
X16395D01*
G01X24095Y1718872D02*
X20095D01*
Y1726872D01*
X24095D01*
G01X22495Y1723005D02*
X20095D01*
G01X27995Y1719938D02*
X28795Y1719272D01*
X29695Y1718872D01*
X30495D01*
X31295Y1719272D01*
X31895Y1719938D01*
X32195Y1720872D01*
X31995Y1721805D01*
X31495Y1722605D01*
X30595Y1723139D01*
X29395Y1723405D01*
X28695Y1723939D01*
X28395Y1724872D01*
X28595Y1725805D01*
X29095Y1726472D01*
X29795Y1726872D01*
X30495D01*
X31195Y1726605D01*
X31795Y1725939D01*
G01X38095Y1718605D02*
X37895Y1718739D01*
Y1719005D01*
X38095Y1719139D01*
X38295Y1719005D01*
Y1718739D01*
X38095Y1718605D01*
G01Y1722205D02*
X37895Y1722339D01*
Y1722605D01*
X38095Y1722739D01*
X38295Y1722605D01*
Y1722339D01*
X38095Y1722205D01*
G01X53595Y1716205D02*
X52595Y1717539D01*
X52095Y1718872D01*
Y1724205D01*
X52595Y1725539D01*
X53595Y1726872D01*
G01X59895D02*
Y1721139D01*
X60295Y1719938D01*
X61095Y1719139D01*
X62095Y1718872D01*
X63095Y1719139D01*
X63895Y1719938D01*
X64295Y1721139D01*
Y1726872D01*
G01X67795Y1718872D02*
Y1726872D01*
X72395Y1718872D01*
Y1726872D01*
G01X76095D02*
Y1718872D01*
X80095D01*
G01X88095D02*
X84095D01*
Y1726872D01*
X88095D01*
G01X86495Y1723005D02*
X84095D01*
G01X91995Y1719938D02*
X92795Y1719272D01*
X93695Y1718872D01*
X94495D01*
X95295Y1719272D01*
X95895Y1719938D01*
X96195Y1720872D01*
X95995Y1721805D01*
X95495Y1722605D01*
X94595Y1723139D01*
X93395Y1723405D01*
X92695Y1723939D01*
X92395Y1724872D01*
X92595Y1725805D01*
X93095Y1726472D01*
X93795Y1726872D01*
X94495D01*
X95195Y1726605D01*
X95795Y1725939D01*
G01X99995Y1719938D02*
X100795Y1719272D01*
X101695Y1718872D01*
X102495D01*
X103295Y1719272D01*
X103895Y1719938D01*
X104195Y1720872D01*
X103995Y1721805D01*
X103495Y1722605D01*
X102595Y1723139D01*
X101395Y1723405D01*
X100695Y1723939D01*
X100395Y1724872D01*
X100595Y1725805D01*
X101095Y1726472D01*
X101795Y1726872D01*
X102495D01*
X103195Y1726605D01*
X103795Y1725939D01*
G01X118095Y1718872D02*
X117295Y1719005D01*
X116595Y1719539D01*
X115995Y1720339D01*
X115595Y1721272D01*
X115395Y1722339D01*
Y1723405D01*
X115595Y1724472D01*
X115995Y1725405D01*
X116595Y1726205D01*
X117295Y1726739D01*
X118095Y1726872D01*
X118895Y1726739D01*
X119595Y1726205D01*
X120195Y1725405D01*
X120595Y1724472D01*
X120795Y1723405D01*
Y1722339D01*
X120595Y1721272D01*
X120195Y1720339D01*
X119595Y1719539D01*
X118895Y1719005D01*
X118095Y1718872D01*
G01X126095Y1726872D02*
Y1718872D01*
G01X123795Y1726872D02*
X128395D01*
G01X131995Y1718872D02*
Y1726872D01*
G01X136195D02*
Y1718872D01*
G01Y1722872D02*
X131995D01*
G01X144095Y1718872D02*
X140095D01*
Y1726872D01*
X144095D01*
G01X142495Y1723005D02*
X140095D01*
G01X148095Y1718872D02*
Y1726872D01*
X150595D01*
X151395Y1726472D01*
X151895Y1725939D01*
X152095Y1724872D01*
X151895Y1723805D01*
X151295Y1723139D01*
X150595Y1722739D01*
X148095D01*
G01X150595D02*
X152095Y1718872D01*
G01X155095Y1726872D02*
X156495Y1718872D01*
X158095Y1726872D01*
X159695Y1718872D01*
X161095Y1726872D01*
G01X164895D02*
X167295D01*
G01X166095D02*
Y1718872D01*
G01X164895D02*
X167295D01*
G01X171995Y1719938D02*
X172795Y1719272D01*
X173695Y1718872D01*
X174495D01*
X175295Y1719272D01*
X175895Y1719938D01*
X176195Y1720872D01*
X175995Y1721805D01*
X175495Y1722605D01*
X174595Y1723139D01*
X173395Y1723405D01*
X172695Y1723939D01*
X172395Y1724872D01*
X172595Y1725805D01*
X173095Y1726472D01*
X173795Y1726872D01*
X174495D01*
X175195Y1726605D01*
X175795Y1725939D01*
G01X184095Y1718872D02*
X180095D01*
Y1726872D01*
X184095D01*
G01X182495Y1723005D02*
X180095D01*
G01X195995Y1719938D02*
X196795Y1719272D01*
X197695Y1718872D01*
X198495D01*
X199295Y1719272D01*
X199895Y1719938D01*
X200195Y1720872D01*
X199995Y1721805D01*
X199495Y1722605D01*
X198595Y1723139D01*
X197395Y1723405D01*
X196695Y1723939D01*
X196395Y1724872D01*
X196595Y1725805D01*
X197095Y1726472D01*
X197795Y1726872D01*
X198495D01*
X199195Y1726605D01*
X199795Y1725939D01*
G01X204095Y1718872D02*
Y1726872D01*
X206495D01*
X207295Y1726472D01*
X207895Y1725539D01*
X208095Y1724472D01*
X207895Y1723405D01*
X207395Y1722605D01*
X206495Y1722205D01*
X204095D01*
G01X216095Y1718872D02*
X212095D01*
Y1726872D01*
X216095D01*
G01X214495Y1723005D02*
X212095D01*
G01X224295Y1726205D02*
X223695Y1726605D01*
X222995Y1726872D01*
X222195D01*
X221295Y1726472D01*
X220595Y1725805D01*
X220095Y1725005D01*
X219695Y1723672D01*
X219595Y1722472D01*
X219795Y1721272D01*
X220095Y1720472D01*
X220695Y1719672D01*
X221395Y1719139D01*
X222095Y1718872D01*
X222795D01*
X223495Y1719139D01*
X224095Y1719539D01*
X224595Y1720072D01*
G01X228895Y1726872D02*
X231295D01*
G01X230095D02*
Y1718872D01*
G01X228895D02*
X231295D01*
G01X236195D02*
Y1726872D01*
X239995D01*
G01X238595Y1723005D02*
X236195D01*
G01X244895Y1726872D02*
X247295D01*
G01X246095D02*
Y1718872D01*
G01X244895D02*
X247295D01*
G01X256095D02*
X252095D01*
Y1726872D01*
X256095D01*
G01X254495Y1723005D02*
X252095D01*
G01X259895Y1718872D02*
Y1726872D01*
X261895D01*
X262695Y1726472D01*
X263295Y1725939D01*
X263795Y1725139D01*
X264195Y1724205D01*
X264295Y1722872D01*
X264195Y1721539D01*
X263795Y1720605D01*
X263295Y1719805D01*
X262695Y1719272D01*
X261895Y1718872D01*
X259895D01*
G01X276895Y1726872D02*
X279295D01*
G01X278095D02*
Y1718872D01*
G01X276895D02*
X279295D01*
G01X283795D02*
Y1726872D01*
X288395Y1718872D01*
Y1726872D01*
G01X300095Y1718872D02*
Y1726872D01*
X302495D01*
X303295Y1726472D01*
X303895Y1725539D01*
X304095Y1724472D01*
X303895Y1723405D01*
X303395Y1722605D01*
X302495Y1722205D01*
X300095D01*
G01X312295Y1726205D02*
X311695Y1726605D01*
X310995Y1726872D01*
X310195D01*
X309295Y1726472D01*
X308595Y1725805D01*
X308095Y1725005D01*
X307695Y1723672D01*
X307595Y1722472D01*
X307795Y1721272D01*
X308095Y1720472D01*
X308695Y1719672D01*
X309395Y1719139D01*
X310095Y1718872D01*
X310795D01*
X311495Y1719139D01*
X312095Y1719539D01*
X312595Y1720072D01*
G01X318895Y1723139D02*
X319295Y1723539D01*
X319595Y1724205D01*
X319795Y1725139D01*
X319595Y1725939D01*
X319195Y1726472D01*
X318495Y1726872D01*
X315795D01*
Y1718872D01*
X319095D01*
X319795Y1719405D01*
X320195Y1720205D01*
X320395Y1721139D01*
X320195Y1722072D01*
X319595Y1722872D01*
X318895Y1723139D01*
X315795D01*
G01X331995Y1719938D02*
X332795Y1719272D01*
X333695Y1718872D01*
X334495D01*
X335295Y1719272D01*
X335895Y1719938D01*
X336195Y1720872D01*
X335995Y1721805D01*
X335495Y1722605D01*
X334595Y1723139D01*
X333395Y1723405D01*
X332695Y1723939D01*
X332395Y1724872D01*
X332595Y1725805D01*
X333095Y1726472D01*
X333795Y1726872D01*
X334495D01*
X335195Y1726605D01*
X335795Y1725939D01*
G01X340095Y1718872D02*
Y1726872D01*
X342495D01*
X343295Y1726472D01*
X343895Y1725539D01*
X344095Y1724472D01*
X343895Y1723405D01*
X343395Y1722605D01*
X342495Y1722205D01*
X340095D01*
G01X352095Y1718872D02*
X348095D01*
Y1726872D01*
X352095D01*
G01X350495Y1723005D02*
X348095D01*
G01X360295Y1726205D02*
X359695Y1726605D01*
X358995Y1726872D01*
X358195D01*
X357295Y1726472D01*
X356595Y1725805D01*
X356095Y1725005D01*
X355695Y1723672D01*
X355595Y1722472D01*
X355795Y1721272D01*
X356095Y1720472D01*
X356695Y1719672D01*
X357395Y1719139D01*
X358095Y1718872D01*
X358795D01*
X359495Y1719139D01*
X360095Y1719539D01*
X360595Y1720072D01*
G01X366595Y1716205D02*
X367595Y1717539D01*
X368095Y1718872D01*
Y1724205D01*
X367595Y1725539D01*
X366595Y1726872D01*
G01X-1905Y1703872D02*
Y1711872D01*
X-3105Y1710272D01*
G01Y1703872D02*
X-705D01*
G01X6095Y1703605D02*
X5895Y1703739D01*
Y1704005D01*
X6095Y1704139D01*
X6295Y1704005D01*
Y1703739D01*
X6095Y1703605D01*
G01X12095Y1703872D02*
Y1711872D01*
X14495D01*
X15295Y1711472D01*
X15895Y1710539D01*
X16095Y1709472D01*
X15895Y1708405D01*
X15395Y1707605D01*
X14495Y1707205D01*
X12095D01*
G01X24295Y1711205D02*
X23695Y1711605D01*
X22995Y1711872D01*
X22195D01*
X21295Y1711472D01*
X20595Y1710805D01*
X20095Y1710005D01*
X19695Y1708672D01*
X19595Y1707472D01*
X19795Y1706272D01*
X20095Y1705472D01*
X20695Y1704672D01*
X21395Y1704139D01*
X22095Y1703872D01*
X22795D01*
X23495Y1704139D01*
X24095Y1704539D01*
X24595Y1705072D01*
G01X30895Y1708139D02*
X31295Y1708539D01*
X31595Y1709205D01*
X31795Y1710139D01*
X31595Y1710939D01*
X31195Y1711472D01*
X30495Y1711872D01*
X27795D01*
Y1703872D01*
X31095D01*
X31795Y1704405D01*
X32195Y1705205D01*
X32395Y1706139D01*
X32195Y1707072D01*
X31595Y1707872D01*
X30895Y1708139D01*
X27795D01*
G01X43995Y1704938D02*
X44795Y1704272D01*
X45695Y1703872D01*
X46495D01*
X47295Y1704272D01*
X47895Y1704938D01*
X48195Y1705872D01*
X47995Y1706805D01*
X47495Y1707605D01*
X46595Y1708139D01*
X45395Y1708405D01*
X44695Y1708939D01*
X44395Y1709872D01*
X44595Y1710805D01*
X45095Y1711472D01*
X45795Y1711872D01*
X46495D01*
X47195Y1711605D01*
X47795Y1710939D01*
G01X52895Y1711872D02*
X55295D01*
G01X54095D02*
Y1703872D01*
G01X52895D02*
X55295D01*
G01X60195Y1711872D02*
X63995D01*
X60195Y1703872D01*
X63995D01*
G01X72095D02*
X68095D01*
Y1711872D01*
X72095D01*
G01X70495Y1708005D02*
X68095D01*
G01X102095Y1703605D02*
X101895Y1703739D01*
Y1704005D01*
X102095Y1704139D01*
X102295Y1704005D01*
Y1703739D01*
X102095Y1703605D01*
G01Y1707205D02*
X101895Y1707339D01*
Y1707605D01*
X102095Y1707739D01*
X102295Y1707605D01*
Y1707339D01*
X102095Y1707205D01*
G01X116195Y1703872D02*
Y1711872D01*
X119995D01*
G01X118595Y1708005D02*
X116195D01*
G01X126095Y1703872D02*
X125295Y1704005D01*
X124595Y1704539D01*
X123995Y1705339D01*
X123595Y1706272D01*
X123395Y1707339D01*
Y1708405D01*
X123595Y1709472D01*
X123995Y1710405D01*
X124595Y1711205D01*
X125295Y1711739D01*
X126095Y1711872D01*
X126895Y1711739D01*
X127595Y1711205D01*
X128195Y1710405D01*
X128595Y1709472D01*
X128795Y1708405D01*
Y1707339D01*
X128595Y1706272D01*
X128195Y1705339D01*
X127595Y1704539D01*
X126895Y1704005D01*
X126095Y1703872D01*
G01X132095Y1711872D02*
Y1703872D01*
X136095D01*
G01X140095Y1711872D02*
Y1703872D01*
X144095D01*
G01X150095D02*
X149295Y1704005D01*
X148595Y1704539D01*
X147995Y1705339D01*
X147595Y1706272D01*
X147395Y1707339D01*
Y1708405D01*
X147595Y1709472D01*
X147995Y1710405D01*
X148595Y1711205D01*
X149295Y1711739D01*
X150095Y1711872D01*
X150895Y1711739D01*
X151595Y1711205D01*
X152195Y1710405D01*
X152595Y1709472D01*
X152795Y1708405D01*
Y1707339D01*
X152595Y1706272D01*
X152195Y1705339D01*
X151595Y1704539D01*
X150895Y1704005D01*
X150095Y1703872D01*
G01X155095Y1711872D02*
X156495Y1703872D01*
X158095Y1711872D01*
X159695Y1703872D01*
X161095Y1711872D01*
G01X174695Y1707872D02*
X176695D01*
Y1705472D01*
X176095Y1704672D01*
X175395Y1704139D01*
X174395Y1703872D01*
X173395Y1704139D01*
X172695Y1704672D01*
X172095Y1705472D01*
X171695Y1706405D01*
X171495Y1707472D01*
Y1708405D01*
X171695Y1709205D01*
X172095Y1710139D01*
X172695Y1710939D01*
X173295Y1711472D01*
X174095Y1711872D01*
X174795D01*
X175595Y1711605D01*
X176195Y1711072D01*
G01X184095Y1703872D02*
X180095D01*
Y1711872D01*
X184095D01*
G01X182495Y1708005D02*
X180095D01*
G01X188095Y1703872D02*
Y1711872D01*
X190595D01*
X191395Y1711472D01*
X191895Y1710939D01*
X192095Y1709872D01*
X191895Y1708805D01*
X191295Y1708139D01*
X190595Y1707739D01*
X188095D01*
G01X190595D02*
X192095Y1703872D01*
G01X198895Y1708139D02*
X199295Y1708539D01*
X199595Y1709205D01*
X199795Y1710139D01*
X199595Y1710939D01*
X199195Y1711472D01*
X198495Y1711872D01*
X195795D01*
Y1703872D01*
X199095D01*
X199795Y1704405D01*
X200195Y1705205D01*
X200395Y1706139D01*
X200195Y1707072D01*
X199595Y1707872D01*
X198895Y1708139D01*
X195795D01*
G01X208095Y1703872D02*
X204095D01*
Y1711872D01*
X208095D01*
G01X206495Y1708005D02*
X204095D01*
G01X212095Y1703872D02*
Y1711872D01*
X214595D01*
X215395Y1711472D01*
X215895Y1710939D01*
X216095Y1709872D01*
X215895Y1708805D01*
X215295Y1708139D01*
X214595Y1707739D01*
X212095D01*
G01X214595D02*
X216095Y1703872D01*
G01X228195D02*
Y1711872D01*
X231995D01*
G01X230595Y1708005D02*
X228195D01*
G01X236895Y1711872D02*
X239295D01*
G01X238095D02*
Y1703872D01*
G01X236895D02*
X239295D01*
G01X244095Y1711872D02*
Y1703872D01*
X248095D01*
G01X256095D02*
X252095D01*
Y1711872D01*
X256095D01*
G01X254495Y1708005D02*
X252095D01*
G01X261395Y1701472D02*
X262795Y1703339D01*
Y1705205D01*
X261395D01*
Y1703339D01*
X262795D01*
G01Y1706539D02*
Y1708405D01*
X261395D01*
Y1706539D01*
X262795D01*
G01X275095Y1711872D02*
X276495Y1703872D01*
X278095Y1711872D01*
X279695Y1703872D01*
X281095Y1711872D01*
G01X284895D02*
X287295D01*
G01X286095D02*
Y1703872D01*
G01X284895D02*
X287295D01*
G01X294095Y1711872D02*
Y1703872D01*
G01X291795Y1711872D02*
X296395D01*
G01X299995Y1703872D02*
Y1711872D01*
G01X304195D02*
Y1703872D01*
G01Y1707872D02*
X299995D01*
G01X318095Y1711872D02*
Y1703872D01*
G01X315795Y1711872D02*
X320395D01*
G01X326095Y1703872D02*
X325295Y1704005D01*
X324595Y1704539D01*
X323995Y1705339D01*
X323595Y1706272D01*
X323395Y1707339D01*
Y1708405D01*
X323595Y1709472D01*
X323995Y1710405D01*
X324595Y1711205D01*
X325295Y1711739D01*
X326095Y1711872D01*
X326895Y1711739D01*
X327595Y1711205D01*
X328195Y1710405D01*
X328595Y1709472D01*
X328795Y1708405D01*
Y1707339D01*
X328595Y1706272D01*
X328195Y1705339D01*
X327595Y1704539D01*
X326895Y1704005D01*
X326095Y1703872D01*
G01X332095Y1711872D02*
Y1703872D01*
X336095D01*
G01X344095D02*
X340095D01*
Y1711872D01*
X344095D01*
G01X342495Y1708005D02*
X340095D01*
G01X348095Y1703872D02*
Y1711872D01*
X350595D01*
X351395Y1711472D01*
X351895Y1710939D01*
X352095Y1709872D01*
X351895Y1708805D01*
X351295Y1708139D01*
X350595Y1707739D01*
X348095D01*
G01X350595D02*
X352095Y1703872D01*
G01X355595D02*
X358095Y1711872D01*
X360595Y1703872D01*
G01X359695Y1706672D02*
X356495D01*
G01X363795Y1703872D02*
Y1711872D01*
X368395Y1703872D01*
Y1711872D01*
G01X376295Y1711205D02*
X375695Y1711605D01*
X374995Y1711872D01*
X374195D01*
X373295Y1711472D01*
X372595Y1710805D01*
X372095Y1710005D01*
X371695Y1708672D01*
X371595Y1707472D01*
X371795Y1706272D01*
X372095Y1705472D01*
X372695Y1704672D01*
X373395Y1704139D01*
X374095Y1703872D01*
X374795D01*
X375495Y1704139D01*
X376095Y1704539D01*
X376595Y1705072D01*
G01X384095Y1703872D02*
X380095D01*
Y1711872D01*
X384095D01*
G01X382495Y1708005D02*
X380095D01*
G01X396795Y1705339D02*
X399395D01*
G01Y1707739D02*
X396795D01*
G01X404995Y1706539D02*
X407395D01*
G01X406095Y1708272D02*
Y1704805D01*
G01X412295Y1703605D02*
X415895Y1711872D01*
G01X420795Y1706539D02*
X423395D01*
G01X430095Y1711872D02*
X429295Y1711605D01*
X428695Y1710939D01*
X428295Y1710139D01*
X427995Y1709072D01*
X427895Y1707872D01*
X427995Y1706672D01*
X428295Y1705605D01*
X428695Y1704805D01*
X429295Y1704139D01*
X430095Y1703872D01*
X430895Y1704139D01*
X431495Y1704805D01*
X431895Y1705605D01*
X432195Y1706672D01*
X432295Y1707872D01*
X432195Y1709072D01*
X431895Y1710139D01*
X431495Y1710939D01*
X430895Y1711605D01*
X430095Y1711872D01*
G01X438095Y1703605D02*
X437895Y1703739D01*
Y1704005D01*
X438095Y1704139D01*
X438295Y1704005D01*
Y1703739D01*
X438095Y1703605D01*
G01X446095Y1703872D02*
Y1711872D01*
X444895Y1710272D01*
G01Y1703872D02*
X447295D01*
G01X451895Y1705072D02*
X452495Y1704405D01*
X453195Y1704005D01*
X454095Y1703872D01*
X454995Y1704139D01*
X455695Y1704672D01*
X456195Y1705605D01*
X456295Y1706672D01*
X456095Y1707739D01*
X455595Y1708405D01*
X454895Y1708939D01*
X454195Y1709072D01*
X453495Y1708939D01*
X452595Y1708405D01*
X452895Y1711872D01*
X455595D01*
G01X459495Y1703872D02*
Y1711872D01*
X462095Y1705205D01*
X464695Y1711872D01*
Y1703872D01*
G01X467495D02*
Y1711872D01*
X470095Y1705205D01*
X472695Y1711872D01*
Y1703872D01*
G01X-1905Y1733872D02*
X-2705Y1734005D01*
X-3405Y1734539D01*
X-4005Y1735339D01*
X-4405Y1736272D01*
X-4605Y1737339D01*
Y1738405D01*
X-4405Y1739472D01*
X-4005Y1740405D01*
X-3405Y1741205D01*
X-2705Y1741739D01*
X-1905Y1741872D01*
X-1105Y1741739D01*
X-405Y1741205D01*
X195Y1740405D01*
X595Y1739472D01*
X795Y1738405D01*
Y1737339D01*
X595Y1736272D01*
X195Y1735339D01*
X-405Y1734539D01*
X-1105Y1734005D01*
X-1905Y1733872D01*
G01X-1105Y1736005D02*
X95Y1733872D01*
G01X4395Y1739205D02*
Y1735472D01*
X4795Y1734539D01*
X5395Y1734005D01*
X6095Y1733872D01*
X6795Y1734005D01*
X7395Y1734539D01*
X7795Y1735472D01*
G01Y1733872D02*
Y1739205D01*
G01X15895Y1733872D02*
Y1739205D01*
G01Y1738272D02*
X15495Y1738805D01*
X14895Y1739072D01*
X14195Y1739205D01*
X13495Y1738939D01*
X12895Y1738405D01*
X12495Y1737605D01*
X12295Y1736539D01*
X12495Y1735472D01*
X12895Y1734672D01*
X13495Y1734139D01*
X14195Y1733872D01*
X14895Y1734005D01*
X15495Y1734405D01*
X15895Y1734938D01*
G01X20395Y1733872D02*
Y1739205D01*
G01Y1737872D02*
X20795Y1738539D01*
X21395Y1739072D01*
X22195Y1739205D01*
X22895Y1739072D01*
X23495Y1738539D01*
X23795Y1737605D01*
Y1733872D01*
G01X30095Y1741872D02*
Y1733872D01*
G01X28695Y1739205D02*
X31495D01*
G01X39895Y1733872D02*
Y1739205D01*
G01Y1738272D02*
X39495Y1738805D01*
X38895Y1739072D01*
X38195Y1739205D01*
X37495Y1738939D01*
X36895Y1738405D01*
X36495Y1737605D01*
X36295Y1736539D01*
X36495Y1735472D01*
X36895Y1734672D01*
X37495Y1734139D01*
X38195Y1733872D01*
X38895Y1734005D01*
X39495Y1734405D01*
X39895Y1734938D01*
G01X52195Y1733872D02*
Y1741872D01*
X55995D01*
G01X54595Y1738005D02*
X52195D01*
G01X59595Y1733872D02*
X62095Y1741872D01*
X64595Y1733872D01*
G01X63695Y1736672D02*
X60495D01*
G01X70895Y1738139D02*
X71295Y1738539D01*
X71595Y1739205D01*
X71795Y1740139D01*
X71595Y1740939D01*
X71195Y1741472D01*
X70495Y1741872D01*
X67795D01*
Y1733872D01*
X71095D01*
X71795Y1734405D01*
X72195Y1735205D01*
X72395Y1736139D01*
X72195Y1737072D01*
X71595Y1737872D01*
X70895Y1738139D01*
X67795D01*
G01X83795Y1733872D02*
Y1741872D01*
X88395Y1733872D01*
Y1741872D01*
G01X94095Y1733872D02*
X93295Y1734005D01*
X92595Y1734539D01*
X91995Y1735339D01*
X91595Y1736272D01*
X91395Y1737339D01*
Y1738405D01*
X91595Y1739472D01*
X91995Y1740405D01*
X92595Y1741205D01*
X93295Y1741739D01*
X94095Y1741872D01*
X94895Y1741739D01*
X95595Y1741205D01*
X96195Y1740405D01*
X96595Y1739472D01*
X96795Y1738405D01*
Y1737339D01*
X96595Y1736272D01*
X96195Y1735339D01*
X95595Y1734539D01*
X94895Y1734005D01*
X94095Y1733872D01*
G01X102095Y1741872D02*
Y1733872D01*
G01X99795Y1741872D02*
X104395D01*
G01X112095Y1733872D02*
X108095D01*
Y1741872D01*
X112095D01*
G01X110495Y1738005D02*
X108095D01*
G01X124095Y1733872D02*
Y1741872D01*
X126595D01*
X127395Y1741472D01*
X127895Y1740939D01*
X128095Y1739872D01*
X127895Y1738805D01*
X127295Y1738139D01*
X126595Y1737739D01*
X124095D01*
G01X126595D02*
X128095Y1733872D01*
G01X136095D02*
X132095D01*
Y1741872D01*
X136095D01*
G01X134495Y1738005D02*
X132095D01*
G01X139595Y1741872D02*
X142095Y1733872D01*
X144595Y1741872D01*
G01X150095Y1733605D02*
X149895Y1733739D01*
Y1734005D01*
X150095Y1734139D01*
X150295Y1734005D01*
Y1733739D01*
X150095Y1733605D01*
G01Y1737205D02*
X149895Y1737339D01*
Y1737605D01*
X150095Y1737739D01*
X150295Y1737605D01*
Y1737339D01*
X150095Y1737205D01*
G01X156195Y1733872D02*
Y1741872D01*
X159995D01*
G01X158595Y1738005D02*
X156195D01*
G01X16093Y-834672D02*
Y-839672D01*
G01X14636Y-834672D02*
X17550D01*
G01X22460Y-839672D02*
X19926D01*
Y-834672D01*
X22460D01*
G01X21446Y-837089D02*
X19926D01*
G01X25026Y-834672D02*
Y-839672D01*
X27560D01*
G01X31393Y-839839D02*
X31266Y-839755D01*
Y-839589D01*
X31393Y-839505D01*
X31520Y-839589D01*
Y-839755D01*
X31393Y-839839D01*
G01Y-837589D02*
X31266Y-837505D01*
Y-837339D01*
X31393Y-837255D01*
X31520Y-837339D01*
Y-837505D01*
X31393Y-837589D01*
G01X36176Y-841339D02*
X35543Y-840505D01*
X35226Y-839672D01*
Y-836339D01*
X35543Y-835505D01*
X36176Y-834672D01*
G01X41593D02*
X41086Y-834839D01*
X40706Y-835255D01*
X40453Y-835755D01*
X40263Y-836422D01*
X40200Y-837172D01*
X40263Y-837922D01*
X40453Y-838589D01*
X40706Y-839089D01*
X41086Y-839505D01*
X41593Y-839672D01*
X42100Y-839505D01*
X42480Y-839089D01*
X42733Y-838589D01*
X42923Y-837922D01*
X42986Y-837172D01*
X42923Y-836422D01*
X42733Y-835755D01*
X42480Y-835255D01*
X42100Y-834839D01*
X41593Y-834672D01*
G01X45300Y-838672D02*
X45680Y-839255D01*
X46186Y-839589D01*
X46756Y-839672D01*
X47263Y-839589D01*
X47770Y-839172D01*
X48086Y-838672D01*
X48150Y-838172D01*
X48023Y-837589D01*
X47580Y-837172D01*
X47136Y-837005D01*
X46566D01*
G01X47136D02*
X47516Y-836755D01*
X47833Y-836339D01*
X47960Y-835839D01*
X47833Y-835339D01*
X47516Y-834922D01*
X46946Y-834672D01*
X46376Y-834755D01*
X45806Y-835089D01*
G01X52110Y-841339D02*
X52743Y-840505D01*
X53060Y-839672D01*
Y-836339D01*
X52743Y-835505D01*
X52110Y-834672D01*
G01X55500Y-838672D02*
X55880Y-839255D01*
X56386Y-839589D01*
X56956Y-839672D01*
X57463Y-839589D01*
X57970Y-839172D01*
X58286Y-838672D01*
X58350Y-838172D01*
X58223Y-837589D01*
X57780Y-837172D01*
X57336Y-837005D01*
X56766D01*
G01X57336D02*
X57716Y-836755D01*
X58033Y-836339D01*
X58160Y-835839D01*
X58033Y-835339D01*
X57716Y-834922D01*
X57146Y-834672D01*
X56576Y-834755D01*
X56006Y-835089D01*
G01X60790Y-835505D02*
X61170Y-835005D01*
X61613Y-834755D01*
X62120Y-834672D01*
X62753Y-834839D01*
X63196Y-835255D01*
X63323Y-835755D01*
X63260Y-836255D01*
X63006Y-836672D01*
X61740Y-837505D01*
X61170Y-838089D01*
X60790Y-838922D01*
X60663Y-839672D01*
X63323D01*
G01X66966D02*
X67093Y-838589D01*
X67283Y-837672D01*
X67536Y-836839D01*
X67853Y-835922D01*
X68360Y-834672D01*
X65826D01*
G01X71370Y-838005D02*
X73016D01*
G01X76090Y-835505D02*
X76470Y-835005D01*
X76913Y-834755D01*
X77420Y-834672D01*
X78053Y-834839D01*
X78496Y-835255D01*
X78623Y-835755D01*
X78560Y-836255D01*
X78306Y-836672D01*
X77040Y-837505D01*
X76470Y-838089D01*
X76090Y-838922D01*
X75963Y-839672D01*
X78623D01*
G01X81000Y-838672D02*
X81380Y-839255D01*
X81886Y-839589D01*
X82456Y-839672D01*
X82963Y-839589D01*
X83470Y-839172D01*
X83786Y-838672D01*
X83850Y-838172D01*
X83723Y-837589D01*
X83280Y-837172D01*
X82836Y-837005D01*
X82266D01*
G01X82836D02*
X83216Y-836755D01*
X83533Y-836339D01*
X83660Y-835839D01*
X83533Y-835339D01*
X83216Y-834922D01*
X82646Y-834672D01*
X82076Y-834755D01*
X81506Y-835089D01*
G01X88253Y-839672D02*
Y-834672D01*
X85910Y-838255D01*
X89076D01*
G01X91200Y-838922D02*
X91580Y-839339D01*
X92023Y-839589D01*
X92593Y-839672D01*
X93163Y-839505D01*
X93606Y-839172D01*
X93923Y-838589D01*
X93986Y-837922D01*
X93860Y-837255D01*
X93543Y-836839D01*
X93100Y-836505D01*
X92656Y-836422D01*
X92213Y-836505D01*
X91643Y-836839D01*
X91833Y-834672D01*
X93543D01*
G01X101590Y-839672D02*
Y-834672D01*
X103996D01*
G01X103110Y-837089D02*
X101590D01*
G01X106310Y-839672D02*
X107893Y-834672D01*
X109476Y-839672D01*
G01X108906Y-837922D02*
X106880D01*
G01X111663Y-839672D02*
X114323Y-834672D01*
G01X111663D02*
X114323Y-839672D01*
G01X118093Y-839839D02*
X117966Y-839755D01*
Y-839589D01*
X118093Y-839505D01*
X118220Y-839589D01*
Y-839755D01*
X118093Y-839839D01*
G01Y-837589D02*
X117966Y-837505D01*
Y-837339D01*
X118093Y-837255D01*
X118220Y-837339D01*
Y-837505D01*
X118093Y-837589D01*
G01X122876Y-841339D02*
X122243Y-840505D01*
X121926Y-839672D01*
Y-836339D01*
X122243Y-835505D01*
X122876Y-834672D01*
G01X128293D02*
X127786Y-834839D01*
X127406Y-835255D01*
X127153Y-835755D01*
X126963Y-836422D01*
X126900Y-837172D01*
X126963Y-837922D01*
X127153Y-838589D01*
X127406Y-839089D01*
X127786Y-839505D01*
X128293Y-839672D01*
X128800Y-839505D01*
X129180Y-839089D01*
X129433Y-838589D01*
X129623Y-837922D01*
X129686Y-837172D01*
X129623Y-836422D01*
X129433Y-835755D01*
X129180Y-835255D01*
X128800Y-834839D01*
X128293Y-834672D01*
G01X132000Y-838672D02*
X132380Y-839255D01*
X132886Y-839589D01*
X133456Y-839672D01*
X133963Y-839589D01*
X134470Y-839172D01*
X134786Y-838672D01*
X134850Y-838172D01*
X134723Y-837589D01*
X134280Y-837172D01*
X133836Y-837005D01*
X133266D01*
G01X133836D02*
X134216Y-836755D01*
X134533Y-836339D01*
X134660Y-835839D01*
X134533Y-835339D01*
X134216Y-834922D01*
X133646Y-834672D01*
X133076Y-834755D01*
X132506Y-835089D01*
G01X138810Y-841339D02*
X139443Y-840505D01*
X139760Y-839672D01*
Y-836339D01*
X139443Y-835505D01*
X138810Y-834672D01*
G01X142200Y-838672D02*
X142580Y-839255D01*
X143086Y-839589D01*
X143656Y-839672D01*
X144163Y-839589D01*
X144670Y-839172D01*
X144986Y-838672D01*
X145050Y-838172D01*
X144923Y-837589D01*
X144480Y-837172D01*
X144036Y-837005D01*
X143466D01*
G01X144036D02*
X144416Y-836755D01*
X144733Y-836339D01*
X144860Y-835839D01*
X144733Y-835339D01*
X144416Y-834922D01*
X143846Y-834672D01*
X143276Y-834755D01*
X142706Y-835089D01*
G01X147616Y-839089D02*
X148060Y-839505D01*
X148566Y-839672D01*
X149073Y-839505D01*
X149516Y-839005D01*
X149833Y-838255D01*
X149960Y-837505D01*
Y-836589D01*
X149833Y-835839D01*
X149516Y-835172D01*
X149136Y-834839D01*
X148693Y-834672D01*
X148186Y-834839D01*
X147806Y-835172D01*
X147553Y-835672D01*
X147426Y-836339D01*
X147553Y-836922D01*
X147870Y-837505D01*
X148250Y-837839D01*
X148693Y-837922D01*
X149200Y-837755D01*
X149580Y-837339D01*
X149960Y-836589D01*
G01X153666Y-839672D02*
X153793Y-838589D01*
X153983Y-837672D01*
X154236Y-836839D01*
X154553Y-835922D01*
X155060Y-834672D01*
X152526D01*
G01X158070Y-838005D02*
X159716D01*
G01X162600Y-838672D02*
X162980Y-839255D01*
X163486Y-839589D01*
X164056Y-839672D01*
X164563Y-839589D01*
X165070Y-839172D01*
X165386Y-838672D01*
X165450Y-838172D01*
X165323Y-837589D01*
X164880Y-837172D01*
X164436Y-837005D01*
X163866D01*
G01X164436D02*
X164816Y-836755D01*
X165133Y-836339D01*
X165260Y-835839D01*
X165133Y-835339D01*
X164816Y-834922D01*
X164246Y-834672D01*
X163676Y-834755D01*
X163106Y-835089D01*
G01X167890Y-837589D02*
X168333Y-837005D01*
X168713Y-836672D01*
X169220Y-836505D01*
X169663Y-836672D01*
X169980Y-837005D01*
X170233Y-837505D01*
X170296Y-838089D01*
X170233Y-838589D01*
X169980Y-839089D01*
X169600Y-839505D01*
X169156Y-839672D01*
X168650Y-839505D01*
X168206Y-839005D01*
X167953Y-838255D01*
X167890Y-837422D01*
X168016Y-836339D01*
X168206Y-835755D01*
X168523Y-835172D01*
X168966Y-834755D01*
X169410Y-834672D01*
X169853Y-834839D01*
X170170Y-835255D01*
G01X174193Y-839672D02*
Y-834672D01*
X173433Y-835672D01*
G01Y-839672D02*
X174953D01*
G01X180053D02*
Y-834672D01*
X177710Y-838255D01*
X180876D01*
G01X18750Y-84300D02*
Y-88950D01*
X6250D01*
Y-84300D01*
G01X18750Y-65700D02*
Y-61050D01*
X6250D01*
Y-65700D01*
G01X19922Y204173D02*
Y-24500D01*
X26675Y-34098D01*
G01X118110Y41339D02*
X106299D01*
X32015Y37415D01*
G02Y57073I-519J9829D01*
G01X106299Y53150D01*
X118110D01*
G02Y41339I0J-5905D01*
G01Y53150D02*
G02Y41339I0J-5905D01*
G01X106299D01*
X32015Y37415D01*
G02Y57073I-519J9829D01*
G01X106299Y53150D01*
X118110D01*
G01X32016Y37415D02*
G02Y57073I-520J9829D01*
G01X106300Y41338D02*
X32016Y37415D01*
G01Y57073D02*
X106300Y53150D01*
G01X19921Y218504D02*
G02Y209843I0J-4330D01*
G02Y218504I0J4331D01*
G01Y209843D02*
G03Y218504I0J4331D01*
G03Y209843I0J-4330D01*
G01Y372047D02*
G02Y363386I0J-4330D01*
G02Y372047I0J4330D01*
G01Y363386D02*
G03Y372047I0J4330D01*
G03Y363386I0J-4330D01*
G01X32015Y545262D02*
X106299Y541339D01*
X118110D01*
G02Y529528I0J-5906D01*
G01X106299D01*
X32015Y525604D01*
G02Y545262I-519J9829D01*
G01D02*
G03Y525604I-519J-9829D01*
G01X106299Y529528D01*
X118110D01*
G03Y541339I0J5905D01*
G01X106299D01*
X32015Y545262D01*
G01X32016Y525604D02*
G02Y545262I-520J9829D01*
G01X106300Y529527D02*
X32016Y525604D01*
G01Y545262D02*
X106300Y541339D01*
G01X38850Y692750D02*
Y688100D01*
X26350D01*
Y692750D01*
G01X38850Y748550D02*
Y753200D01*
X26350D01*
Y748550D01*
G01X8725Y1093324D02*
Y1061828D01*
G01D02*
Y1113009D01*
G01Y1132694D02*
Y1164190D01*
G01D02*
Y1113009D01*
G01X71717Y1152379D02*
X28410D01*
G01X33395Y1179932D02*
X20895D01*
X29853Y1174197D01*
Y1181947D01*
G01X33395Y1186442D02*
X20895D01*
X31312Y1190472D01*
X20895Y1194502D01*
X33395D01*
G01Y1198842D02*
X20895D01*
X31312Y1202872D01*
X20895Y1206902D01*
X33395D01*
G01X71717Y1168128D02*
X28410D01*
G01X23895Y1318139D02*
X24295Y1318539D01*
X24595Y1319205D01*
X24795Y1320139D01*
X24595Y1320939D01*
X24195Y1321472D01*
X23495Y1321872D01*
X20795D01*
Y1313872D01*
X24095D01*
X24795Y1314405D01*
X25195Y1315205D01*
X25395Y1316139D01*
X25195Y1317072D01*
X24595Y1317872D01*
X23895Y1318139D01*
X20795D01*
G01X31095Y1313605D02*
X30895Y1313739D01*
Y1314005D01*
X31095Y1314139D01*
X31295Y1314005D01*
Y1313739D01*
X31095Y1313605D01*
G01X37895Y1321872D02*
X40295D01*
G01X39095D02*
Y1313872D01*
G01X37895D02*
X40295D01*
G01X45195D02*
Y1321872D01*
X48995D01*
G01X47595Y1318005D02*
X45195D01*
G01X63095Y1321872D02*
Y1313872D01*
G01X60795Y1321872D02*
X65395D01*
G01X68995Y1313872D02*
Y1321872D01*
G01X73195D02*
Y1313872D01*
G01Y1317872D02*
X68995D01*
G01X81095Y1313872D02*
X77095D01*
Y1321872D01*
X81095D01*
G01X79495Y1318005D02*
X77095D01*
G01X93095Y1313872D02*
Y1321872D01*
X95495D01*
X96295Y1321472D01*
X96895Y1320539D01*
X97095Y1319472D01*
X96895Y1318405D01*
X96395Y1317605D01*
X95495Y1317205D01*
X93095D01*
G01X103095Y1321872D02*
Y1313872D01*
G01X100795Y1321872D02*
X105395D01*
G01X108995Y1313872D02*
Y1321872D01*
G01X113195D02*
Y1313872D01*
G01Y1317872D02*
X108995D01*
G01X127095Y1321872D02*
Y1313872D01*
G01X124795Y1321872D02*
X129395D01*
G01X135095Y1313872D02*
X134295Y1314005D01*
X133595Y1314539D01*
X132995Y1315339D01*
X132595Y1316272D01*
X132395Y1317339D01*
Y1318405D01*
X132595Y1319472D01*
X132995Y1320405D01*
X133595Y1321205D01*
X134295Y1321739D01*
X135095Y1321872D01*
X135895Y1321739D01*
X136595Y1321205D01*
X137195Y1320405D01*
X137595Y1319472D01*
X137795Y1318405D01*
Y1317339D01*
X137595Y1316272D01*
X137195Y1315339D01*
X136595Y1314539D01*
X135895Y1314005D01*
X135095Y1313872D01*
G01X143095D02*
X142295Y1314005D01*
X141595Y1314539D01*
X140995Y1315339D01*
X140595Y1316272D01*
X140395Y1317339D01*
Y1318405D01*
X140595Y1319472D01*
X140995Y1320405D01*
X141595Y1321205D01*
X142295Y1321739D01*
X143095Y1321872D01*
X143895Y1321739D01*
X144595Y1321205D01*
X145195Y1320405D01*
X145595Y1319472D01*
X145795Y1318405D01*
Y1317339D01*
X145595Y1316272D01*
X145195Y1315339D01*
X144595Y1314539D01*
X143895Y1314005D01*
X143095Y1313872D01*
G01X149095Y1321872D02*
Y1313872D01*
X153095D01*
G01X157895Y1321872D02*
X160295D01*
G01X159095D02*
Y1313872D01*
G01X157895D02*
X160295D01*
G01X164795D02*
Y1321872D01*
X169395Y1313872D01*
Y1321872D01*
G01X175695Y1317872D02*
X177695D01*
Y1315472D01*
X177095Y1314672D01*
X176395Y1314139D01*
X175395Y1313872D01*
X174395Y1314139D01*
X173695Y1314672D01*
X173095Y1315472D01*
X172695Y1316405D01*
X172495Y1317472D01*
Y1318405D01*
X172695Y1319205D01*
X173095Y1320139D01*
X173695Y1320939D01*
X174295Y1321472D01*
X175095Y1321872D01*
X175795D01*
X176595Y1321605D01*
X177195Y1321072D01*
G01X188995Y1313872D02*
Y1321872D01*
G01X193195D02*
Y1313872D01*
G01Y1317872D02*
X188995D01*
G01X199095Y1313872D02*
X198295Y1314005D01*
X197595Y1314539D01*
X196995Y1315339D01*
X196595Y1316272D01*
X196395Y1317339D01*
Y1318405D01*
X196595Y1319472D01*
X196995Y1320405D01*
X197595Y1321205D01*
X198295Y1321739D01*
X199095Y1321872D01*
X199895Y1321739D01*
X200595Y1321205D01*
X201195Y1320405D01*
X201595Y1319472D01*
X201795Y1318405D01*
Y1317339D01*
X201595Y1316272D01*
X201195Y1315339D01*
X200595Y1314539D01*
X199895Y1314005D01*
X199095Y1313872D01*
G01X205095Y1321872D02*
Y1313872D01*
X209095D01*
G01X217095D02*
X213095D01*
Y1321872D01*
X217095D01*
G01X215495Y1318005D02*
X213095D01*
G01X229895Y1321872D02*
X232295D01*
G01X231095D02*
Y1313872D01*
G01X229895D02*
X232295D01*
G01X236995Y1314938D02*
X237795Y1314272D01*
X238695Y1313872D01*
X239495D01*
X240295Y1314272D01*
X240895Y1314938D01*
X241195Y1315872D01*
X240995Y1316805D01*
X240495Y1317605D01*
X239595Y1318139D01*
X238395Y1318405D01*
X237695Y1318939D01*
X237395Y1319872D01*
X237595Y1320805D01*
X238095Y1321472D01*
X238795Y1321872D01*
X239495D01*
X240195Y1321605D01*
X240795Y1320939D01*
G01X252495Y1313872D02*
Y1321872D01*
X255095Y1315205D01*
X257695Y1321872D01*
Y1313872D01*
G01X260595D02*
X263095Y1321872D01*
X265595Y1313872D01*
G01X264695Y1316672D02*
X261495D01*
G01X268895Y1313872D02*
Y1321872D01*
X270895D01*
X271695Y1321472D01*
X272295Y1320939D01*
X272795Y1320139D01*
X273195Y1319205D01*
X273295Y1317872D01*
X273195Y1316539D01*
X272795Y1315605D01*
X272295Y1314805D01*
X271695Y1314272D01*
X270895Y1313872D01*
X268895D01*
G01X281095D02*
X277095D01*
Y1321872D01*
X281095D01*
G01X279495Y1318005D02*
X277095D01*
G01X295895Y1318139D02*
X296295Y1318539D01*
X296595Y1319205D01*
X296795Y1320139D01*
X296595Y1320939D01*
X296195Y1321472D01*
X295495Y1321872D01*
X292795D01*
Y1313872D01*
X296095D01*
X296795Y1314405D01*
X297195Y1315205D01*
X297395Y1316139D01*
X297195Y1317072D01*
X296595Y1317872D01*
X295895Y1318139D01*
X292795D01*
G01X303095Y1313872D02*
Y1317472D01*
X301095Y1321872D01*
G01X305095D02*
X303095Y1317472D01*
G01X317095Y1313872D02*
Y1321872D01*
X319595D01*
X320395Y1321472D01*
X320895Y1320939D01*
X321095Y1319872D01*
X320895Y1318805D01*
X320295Y1318139D01*
X319595Y1317739D01*
X317095D01*
G01X319595D02*
X321095Y1313872D01*
G01X327095D02*
X326295Y1314005D01*
X325595Y1314539D01*
X324995Y1315339D01*
X324595Y1316272D01*
X324395Y1317339D01*
Y1318405D01*
X324595Y1319472D01*
X324995Y1320405D01*
X325595Y1321205D01*
X326295Y1321739D01*
X327095Y1321872D01*
X327895Y1321739D01*
X328595Y1321205D01*
X329195Y1320405D01*
X329595Y1319472D01*
X329795Y1318405D01*
Y1317339D01*
X329595Y1316272D01*
X329195Y1315339D01*
X328595Y1314539D01*
X327895Y1314005D01*
X327095Y1313872D01*
G01X332895Y1321872D02*
Y1316139D01*
X333295Y1314938D01*
X334095Y1314139D01*
X335095Y1313872D01*
X336095Y1314139D01*
X336895Y1314938D01*
X337295Y1316139D01*
Y1321872D01*
G01X343095D02*
Y1313872D01*
G01X340795Y1321872D02*
X345395D01*
G01X349895D02*
X352295D01*
G01X351095D02*
Y1313872D01*
G01X349895D02*
X352295D01*
G01X356795D02*
Y1321872D01*
X361395Y1313872D01*
Y1321872D01*
G01X367695Y1317872D02*
X369695D01*
Y1315472D01*
X369095Y1314672D01*
X368395Y1314139D01*
X367395Y1313872D01*
X366395Y1314139D01*
X365695Y1314672D01*
X365095Y1315472D01*
X364695Y1316405D01*
X364495Y1317472D01*
Y1318405D01*
X364695Y1319205D01*
X365095Y1320139D01*
X365695Y1320939D01*
X366295Y1321472D01*
X367095Y1321872D01*
X367795D01*
X368595Y1321605D01*
X369195Y1321072D01*
G01X374895Y1312405D02*
X375295Y1314139D01*
G01X388795Y1313872D02*
Y1321872D01*
X393395Y1313872D01*
Y1321872D01*
G01X399095Y1313872D02*
X398295Y1314005D01*
X397595Y1314539D01*
X396995Y1315339D01*
X396595Y1316272D01*
X396395Y1317339D01*
Y1318405D01*
X396595Y1319472D01*
X396995Y1320405D01*
X397595Y1321205D01*
X398295Y1321739D01*
X399095Y1321872D01*
X399895Y1321739D01*
X400595Y1321205D01*
X401195Y1320405D01*
X401595Y1319472D01*
X401795Y1318405D01*
Y1317339D01*
X401595Y1316272D01*
X401195Y1315339D01*
X400595Y1314539D01*
X399895Y1314005D01*
X399095Y1313872D01*
G01X404795D02*
Y1321872D01*
X409395Y1313872D01*
Y1321872D01*
G01X413795Y1316539D02*
X416395D01*
G01X421195Y1313872D02*
Y1321872D01*
X424995D01*
G01X423595Y1318005D02*
X421195D01*
G01X428895Y1321872D02*
Y1316139D01*
X429295Y1314938D01*
X430095Y1314139D01*
X431095Y1313872D01*
X432095Y1314139D01*
X432895Y1314938D01*
X433295Y1316139D01*
Y1321872D01*
G01X436795Y1313872D02*
Y1321872D01*
X441395Y1313872D01*
Y1321872D01*
G01X449295Y1321205D02*
X448695Y1321605D01*
X447995Y1321872D01*
X447195D01*
X446295Y1321472D01*
X445595Y1320805D01*
X445095Y1320005D01*
X444695Y1318672D01*
X444595Y1317472D01*
X444795Y1316272D01*
X445095Y1315472D01*
X445695Y1314672D01*
X446395Y1314139D01*
X447095Y1313872D01*
X447795D01*
X448495Y1314139D01*
X449095Y1314539D01*
X449595Y1315072D01*
G01X455095Y1321872D02*
Y1313872D01*
G01X452795Y1321872D02*
X457395D01*
G01X461895D02*
X464295D01*
G01X463095D02*
Y1313872D01*
G01X461895D02*
X464295D01*
G01X471095D02*
X470295Y1314005D01*
X469595Y1314539D01*
X468995Y1315339D01*
X468595Y1316272D01*
X468395Y1317339D01*
Y1318405D01*
X468595Y1319472D01*
X468995Y1320405D01*
X469595Y1321205D01*
X470295Y1321739D01*
X471095Y1321872D01*
X471895Y1321739D01*
X472595Y1321205D01*
X473195Y1320405D01*
X473595Y1319472D01*
X473795Y1318405D01*
Y1317339D01*
X473595Y1316272D01*
X473195Y1315339D01*
X472595Y1314539D01*
X471895Y1314005D01*
X471095Y1313872D01*
G01X476795D02*
Y1321872D01*
X481395Y1313872D01*
Y1321872D01*
G01X484595Y1313872D02*
X487095Y1321872D01*
X489595Y1313872D01*
G01X488695Y1316672D02*
X485495D01*
G01X493095Y1321872D02*
Y1313872D01*
X497095D01*
G01X509095D02*
Y1321872D01*
X511495D01*
X512295Y1321472D01*
X512895Y1320539D01*
X513095Y1319472D01*
X512895Y1318405D01*
X512395Y1317605D01*
X511495Y1317205D01*
X509095D01*
G01X516595Y1313872D02*
X519095Y1321872D01*
X521595Y1313872D01*
G01X520695Y1316672D02*
X517495D01*
G01X524895Y1313872D02*
Y1321872D01*
X526895D01*
X527695Y1321472D01*
X528295Y1320939D01*
X528795Y1320139D01*
X529195Y1319205D01*
X529295Y1317872D01*
X529195Y1316539D01*
X528795Y1315605D01*
X528295Y1314805D01*
X527695Y1314272D01*
X526895Y1313872D01*
X524895D01*
G01X540995Y1314938D02*
X541795Y1314272D01*
X542695Y1313872D01*
X543495D01*
X544295Y1314272D01*
X544895Y1314938D01*
X545195Y1315872D01*
X544995Y1316805D01*
X544495Y1317605D01*
X543595Y1318139D01*
X542395Y1318405D01*
X541695Y1318939D01*
X541395Y1319872D01*
X541595Y1320805D01*
X542095Y1321472D01*
X542795Y1321872D01*
X543495D01*
X544195Y1321605D01*
X544795Y1320939D01*
G01X549895Y1321872D02*
X552295D01*
G01X551095D02*
Y1313872D01*
G01X549895D02*
X552295D01*
G01X557195Y1321872D02*
X560995D01*
X557195Y1313872D01*
X560995D01*
G01X569095D02*
X565095D01*
Y1321872D01*
X569095D01*
G01X567495Y1318005D02*
X565095D01*
G01X581895Y1321872D02*
X584295D01*
G01X583095D02*
Y1313872D01*
G01X581895D02*
X584295D01*
G01X588995Y1314938D02*
X589795Y1314272D01*
X590695Y1313872D01*
X591495D01*
X592295Y1314272D01*
X592895Y1314938D01*
X593195Y1315872D01*
X592995Y1316805D01*
X592495Y1317605D01*
X591595Y1318139D01*
X590395Y1318405D01*
X589695Y1318939D01*
X589395Y1319872D01*
X589595Y1320805D01*
X590095Y1321472D01*
X590795Y1321872D01*
X591495D01*
X592195Y1321605D01*
X592795Y1320939D01*
G01X607095Y1321872D02*
Y1313872D01*
G01X604795Y1321872D02*
X609395D01*
G01X612995Y1313872D02*
Y1321872D01*
G01X617195D02*
Y1313872D01*
G01Y1317872D02*
X612995D01*
G01X625095Y1313872D02*
X621095D01*
Y1321872D01*
X625095D01*
G01X623495Y1318005D02*
X621095D01*
G01X637095Y1313872D02*
Y1321872D01*
X639495D01*
X640295Y1321472D01*
X640895Y1320539D01*
X641095Y1319472D01*
X640895Y1318405D01*
X640395Y1317605D01*
X639495Y1317205D01*
X637095D01*
G01X645095Y1313872D02*
Y1321872D01*
X647595D01*
X648395Y1321472D01*
X648895Y1320939D01*
X649095Y1319872D01*
X648895Y1318805D01*
X648295Y1318139D01*
X647595Y1317739D01*
X645095D01*
G01X647595D02*
X649095Y1313872D01*
G01X655095D02*
X654295Y1314005D01*
X653595Y1314539D01*
X652995Y1315339D01*
X652595Y1316272D01*
X652395Y1317339D01*
Y1318405D01*
X652595Y1319472D01*
X652995Y1320405D01*
X653595Y1321205D01*
X654295Y1321739D01*
X655095Y1321872D01*
X655895Y1321739D01*
X656595Y1321205D01*
X657195Y1320405D01*
X657595Y1319472D01*
X657795Y1318405D01*
Y1317339D01*
X657595Y1316272D01*
X657195Y1315339D01*
X656595Y1314539D01*
X655895Y1314005D01*
X655095Y1313872D01*
G01X661195D02*
Y1321872D01*
X664995D01*
G01X663595Y1318005D02*
X661195D01*
G01X669895Y1321872D02*
X672295D01*
G01X671095D02*
Y1313872D01*
G01X669895D02*
X672295D01*
G01X677095Y1321872D02*
Y1313872D01*
X681095D01*
G01X689095D02*
X685095D01*
Y1321872D01*
X689095D01*
G01X687495Y1318005D02*
X685095D01*
G01X700995Y1314938D02*
X701795Y1314272D01*
X702695Y1313872D01*
X703495D01*
X704295Y1314272D01*
X704895Y1314938D01*
X705195Y1315872D01*
X704995Y1316805D01*
X704495Y1317605D01*
X703595Y1318139D01*
X702395Y1318405D01*
X701695Y1318939D01*
X701395Y1319872D01*
X701595Y1320805D01*
X702095Y1321472D01*
X702795Y1321872D01*
X703495D01*
X704195Y1321605D01*
X704795Y1320939D01*
G01X709895Y1321872D02*
X712295D01*
G01X711095D02*
Y1313872D01*
G01X709895D02*
X712295D01*
G01X717195Y1321872D02*
X720995D01*
X717195Y1313872D01*
X720995D01*
G01X729095D02*
X725095D01*
Y1321872D01*
X729095D01*
G01X727495Y1318005D02*
X725095D01*
G01X741995Y1316539D02*
X744395D01*
G01X743095Y1318272D02*
Y1314805D01*
G01X757195Y1320539D02*
X757795Y1321339D01*
X758495Y1321739D01*
X759295Y1321872D01*
X760295Y1321605D01*
X760995Y1320939D01*
X761195Y1320139D01*
X761095Y1319338D01*
X760695Y1318672D01*
X758695Y1317339D01*
X757795Y1316405D01*
X757195Y1315072D01*
X756995Y1313872D01*
X761195D01*
G01X767095Y1321872D02*
X766295Y1321605D01*
X765695Y1320939D01*
X765295Y1320139D01*
X764995Y1319072D01*
X764895Y1317872D01*
X764995Y1316672D01*
X765295Y1315605D01*
X765695Y1314805D01*
X766295Y1314139D01*
X767095Y1313872D01*
X767895Y1314139D01*
X768495Y1314805D01*
X768895Y1315605D01*
X769195Y1316672D01*
X769295Y1317872D01*
X769195Y1319072D01*
X768895Y1320139D01*
X768495Y1320939D01*
X767895Y1321605D01*
X767095Y1321872D01*
G01X772495Y1313872D02*
Y1321872D01*
X775095Y1315205D01*
X777695Y1321872D01*
Y1313872D01*
G01X781895Y1321872D02*
X784295D01*
G01X783095D02*
Y1313872D01*
G01X781895D02*
X784295D01*
G01X789095Y1321872D02*
Y1313872D01*
X793095D01*
G01X20595Y1328872D02*
X23095Y1336872D01*
X25595Y1328872D01*
G01X24695Y1331672D02*
X21495D01*
G01X31095Y1328605D02*
X30895Y1328739D01*
Y1329005D01*
X31095Y1329139D01*
X31295Y1329005D01*
Y1328739D01*
X31095Y1328605D01*
G01X37895Y1336872D02*
X40295D01*
G01X39095D02*
Y1328872D01*
G01X37895D02*
X40295D01*
G01X45195D02*
Y1336872D01*
X48995D01*
G01X47595Y1333005D02*
X45195D01*
G01X63095Y1336872D02*
Y1328872D01*
G01X60795Y1336872D02*
X65395D01*
G01X68995Y1328872D02*
Y1336872D01*
G01X73195D02*
Y1328872D01*
G01Y1332872D02*
X68995D01*
G01X81095Y1328872D02*
X77095D01*
Y1336872D01*
X81095D01*
G01X79495Y1333005D02*
X77095D01*
G01X93095Y1328872D02*
Y1336872D01*
X95495D01*
X96295Y1336472D01*
X96895Y1335539D01*
X97095Y1334472D01*
X96895Y1333405D01*
X96395Y1332605D01*
X95495Y1332205D01*
X93095D01*
G01X103095Y1336872D02*
Y1328872D01*
G01X100795Y1336872D02*
X105395D01*
G01X108995Y1328872D02*
Y1336872D01*
G01X113195D02*
Y1328872D01*
G01Y1332872D02*
X108995D01*
G01X127095Y1336872D02*
Y1328872D01*
G01X124795Y1336872D02*
X129395D01*
G01X135095Y1328872D02*
X134295Y1329005D01*
X133595Y1329539D01*
X132995Y1330339D01*
X132595Y1331272D01*
X132395Y1332339D01*
Y1333405D01*
X132595Y1334472D01*
X132995Y1335405D01*
X133595Y1336205D01*
X134295Y1336739D01*
X135095Y1336872D01*
X135895Y1336739D01*
X136595Y1336205D01*
X137195Y1335405D01*
X137595Y1334472D01*
X137795Y1333405D01*
Y1332339D01*
X137595Y1331272D01*
X137195Y1330339D01*
X136595Y1329539D01*
X135895Y1329005D01*
X135095Y1328872D01*
G01X143095D02*
X142295Y1329005D01*
X141595Y1329539D01*
X140995Y1330339D01*
X140595Y1331272D01*
X140395Y1332339D01*
Y1333405D01*
X140595Y1334472D01*
X140995Y1335405D01*
X141595Y1336205D01*
X142295Y1336739D01*
X143095Y1336872D01*
X143895Y1336739D01*
X144595Y1336205D01*
X145195Y1335405D01*
X145595Y1334472D01*
X145795Y1333405D01*
Y1332339D01*
X145595Y1331272D01*
X145195Y1330339D01*
X144595Y1329539D01*
X143895Y1329005D01*
X143095Y1328872D01*
G01X149095Y1336872D02*
Y1328872D01*
X153095D01*
G01X157895Y1336872D02*
X160295D01*
G01X159095D02*
Y1328872D01*
G01X157895D02*
X160295D01*
G01X164795D02*
Y1336872D01*
X169395Y1328872D01*
Y1336872D01*
G01X175695Y1332872D02*
X177695D01*
Y1330472D01*
X177095Y1329672D01*
X176395Y1329139D01*
X175395Y1328872D01*
X174395Y1329139D01*
X173695Y1329672D01*
X173095Y1330472D01*
X172695Y1331405D01*
X172495Y1332472D01*
Y1333405D01*
X172695Y1334205D01*
X173095Y1335139D01*
X173695Y1335939D01*
X174295Y1336472D01*
X175095Y1336872D01*
X175795D01*
X176595Y1336605D01*
X177195Y1336072D01*
G01X188995Y1328872D02*
Y1336872D01*
G01X193195D02*
Y1328872D01*
G01Y1332872D02*
X188995D01*
G01X199095Y1328872D02*
X198295Y1329005D01*
X197595Y1329539D01*
X196995Y1330339D01*
X196595Y1331272D01*
X196395Y1332339D01*
Y1333405D01*
X196595Y1334472D01*
X196995Y1335405D01*
X197595Y1336205D01*
X198295Y1336739D01*
X199095Y1336872D01*
X199895Y1336739D01*
X200595Y1336205D01*
X201195Y1335405D01*
X201595Y1334472D01*
X201795Y1333405D01*
Y1332339D01*
X201595Y1331272D01*
X201195Y1330339D01*
X200595Y1329539D01*
X199895Y1329005D01*
X199095Y1328872D01*
G01X205095Y1336872D02*
Y1328872D01*
X209095D01*
G01X217095D02*
X213095D01*
Y1336872D01*
X217095D01*
G01X215495Y1333005D02*
X213095D01*
G01X229895Y1336872D02*
X232295D01*
G01X231095D02*
Y1328872D01*
G01X229895D02*
X232295D01*
G01X236995Y1329938D02*
X237795Y1329272D01*
X238695Y1328872D01*
X239495D01*
X240295Y1329272D01*
X240895Y1329938D01*
X241195Y1330872D01*
X240995Y1331805D01*
X240495Y1332605D01*
X239595Y1333139D01*
X238395Y1333405D01*
X237695Y1333939D01*
X237395Y1334872D01*
X237595Y1335805D01*
X238095Y1336472D01*
X238795Y1336872D01*
X239495D01*
X240195Y1336605D01*
X240795Y1335939D01*
G01X252495Y1328872D02*
Y1336872D01*
X255095Y1330205D01*
X257695Y1336872D01*
Y1328872D01*
G01X260595D02*
X263095Y1336872D01*
X265595Y1328872D01*
G01X264695Y1331672D02*
X261495D01*
G01X268895Y1328872D02*
Y1336872D01*
X270895D01*
X271695Y1336472D01*
X272295Y1335939D01*
X272795Y1335139D01*
X273195Y1334205D01*
X273295Y1332872D01*
X273195Y1331539D01*
X272795Y1330605D01*
X272295Y1329805D01*
X271695Y1329272D01*
X270895Y1328872D01*
X268895D01*
G01X281095D02*
X277095D01*
Y1336872D01*
X281095D01*
G01X279495Y1333005D02*
X277095D01*
G01X295895Y1333139D02*
X296295Y1333539D01*
X296595Y1334205D01*
X296795Y1335139D01*
X296595Y1335939D01*
X296195Y1336472D01*
X295495Y1336872D01*
X292795D01*
Y1328872D01*
X296095D01*
X296795Y1329405D01*
X297195Y1330205D01*
X297395Y1331139D01*
X297195Y1332072D01*
X296595Y1332872D01*
X295895Y1333139D01*
X292795D01*
G01X303095Y1328872D02*
Y1332472D01*
X301095Y1336872D01*
G01X305095D02*
X303095Y1332472D01*
G01X316895Y1328872D02*
Y1336872D01*
X318895D01*
X319695Y1336472D01*
X320295Y1335939D01*
X320795Y1335139D01*
X321195Y1334205D01*
X321295Y1332872D01*
X321195Y1331539D01*
X320795Y1330605D01*
X320295Y1329805D01*
X319695Y1329272D01*
X318895Y1328872D01*
X316895D01*
G01X325095D02*
Y1336872D01*
X327595D01*
X328395Y1336472D01*
X328895Y1335939D01*
X329095Y1334872D01*
X328895Y1333805D01*
X328295Y1333139D01*
X327595Y1332739D01*
X325095D01*
G01X327595D02*
X329095Y1328872D01*
G01X333895Y1336872D02*
X336295D01*
G01X335095D02*
Y1328872D01*
G01X333895D02*
X336295D01*
G01X341095Y1336872D02*
Y1328872D01*
X345095D01*
G01X349095Y1336872D02*
Y1328872D01*
X353095D01*
G01X357895Y1336872D02*
X360295D01*
G01X359095D02*
Y1328872D01*
G01X357895D02*
X360295D01*
G01X364795D02*
Y1336872D01*
X369395Y1328872D01*
Y1336872D01*
G01X375695Y1332872D02*
X377695D01*
Y1330472D01*
X377095Y1329672D01*
X376395Y1329139D01*
X375395Y1328872D01*
X374395Y1329139D01*
X373695Y1329672D01*
X373095Y1330472D01*
X372695Y1331405D01*
X372495Y1332472D01*
Y1333405D01*
X372695Y1334205D01*
X373095Y1335139D01*
X373695Y1335939D01*
X374295Y1336472D01*
X375095Y1336872D01*
X375795D01*
X376595Y1336605D01*
X377195Y1336072D01*
G01X382895Y1327405D02*
X383295Y1329139D01*
G01X396795Y1328872D02*
Y1336872D01*
X401395Y1328872D01*
Y1336872D01*
G01X407095Y1328872D02*
X406295Y1329005D01*
X405595Y1329539D01*
X404995Y1330339D01*
X404595Y1331272D01*
X404395Y1332339D01*
Y1333405D01*
X404595Y1334472D01*
X404995Y1335405D01*
X405595Y1336205D01*
X406295Y1336739D01*
X407095Y1336872D01*
X407895Y1336739D01*
X408595Y1336205D01*
X409195Y1335405D01*
X409595Y1334472D01*
X409795Y1333405D01*
Y1332339D01*
X409595Y1331272D01*
X409195Y1330339D01*
X408595Y1329539D01*
X407895Y1329005D01*
X407095Y1328872D01*
G01X412795D02*
Y1336872D01*
X417395Y1328872D01*
Y1336872D01*
G01X421795Y1331539D02*
X424395D01*
G01X429195Y1328872D02*
Y1336872D01*
X432995D01*
G01X431595Y1333005D02*
X429195D01*
G01X436895Y1336872D02*
Y1331139D01*
X437295Y1329938D01*
X438095Y1329139D01*
X439095Y1328872D01*
X440095Y1329139D01*
X440895Y1329938D01*
X441295Y1331139D01*
Y1336872D01*
G01X444795Y1328872D02*
Y1336872D01*
X449395Y1328872D01*
Y1336872D01*
G01X457295Y1336205D02*
X456695Y1336605D01*
X455995Y1336872D01*
X455195D01*
X454295Y1336472D01*
X453595Y1335805D01*
X453095Y1335005D01*
X452695Y1333672D01*
X452595Y1332472D01*
X452795Y1331272D01*
X453095Y1330472D01*
X453695Y1329672D01*
X454395Y1329139D01*
X455095Y1328872D01*
X455795D01*
X456495Y1329139D01*
X457095Y1329539D01*
X457595Y1330072D01*
G01X463095Y1336872D02*
Y1328872D01*
G01X460795Y1336872D02*
X465395D01*
G01X469895D02*
X472295D01*
G01X471095D02*
Y1328872D01*
G01X469895D02*
X472295D01*
G01X479095D02*
X478295Y1329005D01*
X477595Y1329539D01*
X476995Y1330339D01*
X476595Y1331272D01*
X476395Y1332339D01*
Y1333405D01*
X476595Y1334472D01*
X476995Y1335405D01*
X477595Y1336205D01*
X478295Y1336739D01*
X479095Y1336872D01*
X479895Y1336739D01*
X480595Y1336205D01*
X481195Y1335405D01*
X481595Y1334472D01*
X481795Y1333405D01*
Y1332339D01*
X481595Y1331272D01*
X481195Y1330339D01*
X480595Y1329539D01*
X479895Y1329005D01*
X479095Y1328872D01*
G01X484795D02*
Y1336872D01*
X489395Y1328872D01*
Y1336872D01*
G01X492595Y1328872D02*
X495095Y1336872D01*
X497595Y1328872D01*
G01X496695Y1331672D02*
X493495D01*
G01X501095Y1336872D02*
Y1328872D01*
X505095D01*
G01X517095D02*
Y1336872D01*
X519495D01*
X520295Y1336472D01*
X520895Y1335539D01*
X521095Y1334472D01*
X520895Y1333405D01*
X520395Y1332605D01*
X519495Y1332205D01*
X517095D01*
G01X524595Y1328872D02*
X527095Y1336872D01*
X529595Y1328872D01*
G01X528695Y1331672D02*
X525495D01*
G01X532895Y1328872D02*
Y1336872D01*
X534895D01*
X535695Y1336472D01*
X536295Y1335939D01*
X536795Y1335139D01*
X537195Y1334205D01*
X537295Y1332872D01*
X537195Y1331539D01*
X536795Y1330605D01*
X536295Y1329805D01*
X535695Y1329272D01*
X534895Y1328872D01*
X532895D01*
G01X548995Y1329938D02*
X549795Y1329272D01*
X550695Y1328872D01*
X551495D01*
X552295Y1329272D01*
X552895Y1329938D01*
X553195Y1330872D01*
X552995Y1331805D01*
X552495Y1332605D01*
X551595Y1333139D01*
X550395Y1333405D01*
X549695Y1333939D01*
X549395Y1334872D01*
X549595Y1335805D01*
X550095Y1336472D01*
X550795Y1336872D01*
X551495D01*
X552195Y1336605D01*
X552795Y1335939D01*
G01X557895Y1336872D02*
X560295D01*
G01X559095D02*
Y1328872D01*
G01X557895D02*
X560295D01*
G01X565195Y1336872D02*
X568995D01*
X565195Y1328872D01*
X568995D01*
G01X577095D02*
X573095D01*
Y1336872D01*
X577095D01*
G01X575495Y1333005D02*
X573095D01*
G01X589895Y1336872D02*
X592295D01*
G01X591095D02*
Y1328872D01*
G01X589895D02*
X592295D01*
G01X596995Y1329938D02*
X597795Y1329272D01*
X598695Y1328872D01*
X599495D01*
X600295Y1329272D01*
X600895Y1329938D01*
X601195Y1330872D01*
X600995Y1331805D01*
X600495Y1332605D01*
X599595Y1333139D01*
X598395Y1333405D01*
X597695Y1333939D01*
X597395Y1334872D01*
X597595Y1335805D01*
X598095Y1336472D01*
X598795Y1336872D01*
X599495D01*
X600195Y1336605D01*
X600795Y1335939D01*
G01X615095Y1336872D02*
Y1328872D01*
G01X612795Y1336872D02*
X617395D01*
G01X620995Y1328872D02*
Y1336872D01*
G01X625195D02*
Y1328872D01*
G01Y1332872D02*
X620995D01*
G01X633095Y1328872D02*
X629095D01*
Y1336872D01*
X633095D01*
G01X631495Y1333005D02*
X629095D01*
G01X644895Y1328872D02*
Y1336872D01*
X646895D01*
X647695Y1336472D01*
X648295Y1335939D01*
X648795Y1335139D01*
X649195Y1334205D01*
X649295Y1332872D01*
X649195Y1331539D01*
X648795Y1330605D01*
X648295Y1329805D01*
X647695Y1329272D01*
X646895Y1328872D01*
X644895D01*
G01X653095D02*
Y1336872D01*
X655595D01*
X656395Y1336472D01*
X656895Y1335939D01*
X657095Y1334872D01*
X656895Y1333805D01*
X656295Y1333139D01*
X655595Y1332739D01*
X653095D01*
G01X655595D02*
X657095Y1328872D01*
G01X661895Y1336872D02*
X664295D01*
G01X663095D02*
Y1328872D01*
G01X661895D02*
X664295D01*
G01X669095Y1336872D02*
Y1328872D01*
X673095D01*
G01X677095Y1336872D02*
Y1328872D01*
X681095D01*
G01X692995Y1329938D02*
X693795Y1329272D01*
X694695Y1328872D01*
X695495D01*
X696295Y1329272D01*
X696895Y1329938D01*
X697195Y1330872D01*
X696995Y1331805D01*
X696495Y1332605D01*
X695595Y1333139D01*
X694395Y1333405D01*
X693695Y1333939D01*
X693395Y1334872D01*
X693595Y1335805D01*
X694095Y1336472D01*
X694795Y1336872D01*
X695495D01*
X696195Y1336605D01*
X696795Y1335939D01*
G01X701895Y1336872D02*
X704295D01*
G01X703095D02*
Y1328872D01*
G01X701895D02*
X704295D01*
G01X709195Y1336872D02*
X712995D01*
X709195Y1328872D01*
X712995D01*
G01X721095D02*
X717095D01*
Y1336872D01*
X721095D01*
G01X719495Y1333005D02*
X717095D01*
G01X733995Y1331539D02*
X736395D01*
G01X735095Y1333272D02*
Y1329805D01*
G01X751095Y1328872D02*
Y1336872D01*
X749895Y1335272D01*
G01Y1328872D02*
X752295D01*
G01X759095Y1336872D02*
X758295Y1336605D01*
X757695Y1335939D01*
X757295Y1335139D01*
X756995Y1334072D01*
X756895Y1332872D01*
X756995Y1331672D01*
X757295Y1330605D01*
X757695Y1329805D01*
X758295Y1329139D01*
X759095Y1328872D01*
X759895Y1329139D01*
X760495Y1329805D01*
X760895Y1330605D01*
X761195Y1331672D01*
X761295Y1332872D01*
X761195Y1334072D01*
X760895Y1335139D01*
X760495Y1335939D01*
X759895Y1336605D01*
X759095Y1336872D01*
G01X764495Y1328872D02*
Y1336872D01*
X767095Y1330205D01*
X769695Y1336872D01*
Y1328872D01*
G01X773895Y1336872D02*
X776295D01*
G01X775095D02*
Y1328872D01*
G01X773895D02*
X776295D01*
G01X781095Y1336872D02*
Y1328872D01*
X785095D01*
G01X13695Y1437872D02*
X15695D01*
Y1435472D01*
X15095Y1434672D01*
X14395Y1434139D01*
X13395Y1433872D01*
X12395Y1434139D01*
X11695Y1434672D01*
X11095Y1435472D01*
X10695Y1436405D01*
X10495Y1437472D01*
Y1438405D01*
X10695Y1439205D01*
X11095Y1440139D01*
X11695Y1440939D01*
X12295Y1441472D01*
X13095Y1441872D01*
X13795D01*
X14595Y1441605D01*
X15195Y1441072D01*
G01X19095Y1433872D02*
Y1441872D01*
X21595D01*
X22395Y1441472D01*
X22895Y1440939D01*
X23095Y1439872D01*
X22895Y1438805D01*
X22295Y1438139D01*
X21595Y1437739D01*
X19095D01*
G01X21595D02*
X23095Y1433872D01*
G01X29095D02*
X28295Y1434005D01*
X27595Y1434539D01*
X26995Y1435339D01*
X26595Y1436272D01*
X26395Y1437339D01*
Y1438405D01*
X26595Y1439472D01*
X26995Y1440405D01*
X27595Y1441205D01*
X28295Y1441739D01*
X29095Y1441872D01*
X29895Y1441739D01*
X30595Y1441205D01*
X31195Y1440405D01*
X31595Y1439472D01*
X31795Y1438405D01*
Y1437339D01*
X31595Y1436272D01*
X31195Y1435339D01*
X30595Y1434539D01*
X29895Y1434005D01*
X29095Y1433872D01*
G01X34895Y1441872D02*
Y1436139D01*
X35295Y1434938D01*
X36095Y1434139D01*
X37095Y1433872D01*
X38095Y1434139D01*
X38895Y1434938D01*
X39295Y1436139D01*
Y1441872D01*
G01X43095Y1433872D02*
Y1441872D01*
X45495D01*
X46295Y1441472D01*
X46895Y1440539D01*
X47095Y1439472D01*
X46895Y1438405D01*
X46395Y1437605D01*
X45495Y1437205D01*
X43095D01*
G01X50995Y1434938D02*
X51795Y1434272D01*
X52695Y1433872D01*
X53495D01*
X54295Y1434272D01*
X54895Y1434938D01*
X55195Y1435872D01*
X54995Y1436805D01*
X54495Y1437605D01*
X53595Y1438139D01*
X52395Y1438405D01*
X51695Y1438939D01*
X51395Y1439872D01*
X51595Y1440805D01*
X52095Y1441472D01*
X52795Y1441872D01*
X53495D01*
X54195Y1441605D01*
X54795Y1440939D01*
G01X66595Y1433872D02*
X69095Y1441872D01*
X71595Y1433872D01*
G01X70695Y1436672D02*
X67495D01*
G01X82595Y1433872D02*
X85095Y1441872D01*
X87595Y1433872D01*
G01X86695Y1436672D02*
X83495D01*
G01X90795Y1433872D02*
Y1441872D01*
X95395Y1433872D01*
Y1441872D01*
G01X98895Y1433872D02*
Y1441872D01*
X100895D01*
X101695Y1441472D01*
X102295Y1440939D01*
X102795Y1440139D01*
X103195Y1439205D01*
X103295Y1437872D01*
X103195Y1436539D01*
X102795Y1435605D01*
X102295Y1434805D01*
X101695Y1434272D01*
X100895Y1433872D01*
X98895D01*
G01X117895Y1438139D02*
X118295Y1438539D01*
X118595Y1439205D01*
X118795Y1440139D01*
X118595Y1440939D01*
X118195Y1441472D01*
X117495Y1441872D01*
X114795D01*
Y1433872D01*
X118095D01*
X118795Y1434405D01*
X119195Y1435205D01*
X119395Y1436139D01*
X119195Y1437072D01*
X118595Y1437872D01*
X117895Y1438139D01*
X114795D01*
G01X124895Y1432405D02*
X125295Y1434139D01*
G01X133095Y1441872D02*
Y1433872D01*
G01X130795Y1441872D02*
X135395D01*
G01X138995Y1433872D02*
Y1441872D01*
G01X143195D02*
Y1433872D01*
G01Y1437872D02*
X138995D01*
G01X151095Y1433872D02*
X147095D01*
Y1441872D01*
X151095D01*
G01X149495Y1438005D02*
X147095D01*
G01X154795Y1433872D02*
Y1441872D01*
X159395Y1433872D01*
Y1441872D01*
G01X173695Y1437872D02*
X175695D01*
Y1435472D01*
X175095Y1434672D01*
X174395Y1434139D01*
X173395Y1433872D01*
X172395Y1434139D01*
X171695Y1434672D01*
X171095Y1435472D01*
X170695Y1436405D01*
X170495Y1437472D01*
Y1438405D01*
X170695Y1439205D01*
X171095Y1440139D01*
X171695Y1440939D01*
X172295Y1441472D01*
X173095Y1441872D01*
X173795D01*
X174595Y1441605D01*
X175195Y1441072D01*
G01X179095Y1433872D02*
Y1441872D01*
X181595D01*
X182395Y1441472D01*
X182895Y1440939D01*
X183095Y1439872D01*
X182895Y1438805D01*
X182295Y1438139D01*
X181595Y1437739D01*
X179095D01*
G01X181595D02*
X183095Y1433872D01*
G01X189095D02*
X188295Y1434005D01*
X187595Y1434539D01*
X186995Y1435339D01*
X186595Y1436272D01*
X186395Y1437339D01*
Y1438405D01*
X186595Y1439472D01*
X186995Y1440405D01*
X187595Y1441205D01*
X188295Y1441739D01*
X189095Y1441872D01*
X189895Y1441739D01*
X190595Y1441205D01*
X191195Y1440405D01*
X191595Y1439472D01*
X191795Y1438405D01*
Y1437339D01*
X191595Y1436272D01*
X191195Y1435339D01*
X190595Y1434539D01*
X189895Y1434005D01*
X189095Y1433872D01*
G01X194895Y1441872D02*
Y1436139D01*
X195295Y1434938D01*
X196095Y1434139D01*
X197095Y1433872D01*
X198095Y1434139D01*
X198895Y1434938D01*
X199295Y1436139D01*
Y1441872D01*
G01X203095Y1433872D02*
Y1441872D01*
X205495D01*
X206295Y1441472D01*
X206895Y1440539D01*
X207095Y1439472D01*
X206895Y1438405D01*
X206395Y1437605D01*
X205495Y1437205D01*
X203095D01*
G01X218595Y1433872D02*
X221095Y1441872D01*
X223595Y1433872D01*
G01X222695Y1436672D02*
X219495D01*
G01X239295Y1441205D02*
X238695Y1441605D01*
X237995Y1441872D01*
X237195D01*
X236295Y1441472D01*
X235595Y1440805D01*
X235095Y1440005D01*
X234695Y1438672D01*
X234595Y1437472D01*
X234795Y1436272D01*
X235095Y1435472D01*
X235695Y1434672D01*
X236395Y1434139D01*
X237095Y1433872D01*
X237795D01*
X238495Y1434139D01*
X239095Y1434539D01*
X239595Y1435072D01*
G01X242595Y1433872D02*
X245095Y1441872D01*
X247595Y1433872D01*
G01X246695Y1436672D02*
X243495D01*
G01X250795Y1433872D02*
Y1441872D01*
X255395Y1433872D01*
Y1441872D01*
G01X269895Y1438139D02*
X270295Y1438539D01*
X270595Y1439205D01*
X270795Y1440139D01*
X270595Y1440939D01*
X270195Y1441472D01*
X269495Y1441872D01*
X266795D01*
Y1433872D01*
X270095D01*
X270795Y1434405D01*
X271195Y1435205D01*
X271395Y1436139D01*
X271195Y1437072D01*
X270595Y1437872D01*
X269895Y1438139D01*
X266795D01*
G01X279095Y1433872D02*
X275095D01*
Y1441872D01*
X279095D01*
G01X277495Y1438005D02*
X275095D01*
G01X291095Y1433872D02*
Y1441872D01*
X293495D01*
X294295Y1441472D01*
X294895Y1440539D01*
X295095Y1439472D01*
X294895Y1438405D01*
X294395Y1437605D01*
X293495Y1437205D01*
X291095D01*
G01X299095Y1441872D02*
Y1433872D01*
X303095D01*
G01X306595D02*
X309095Y1441872D01*
X311595Y1433872D01*
G01X310695Y1436672D02*
X307495D01*
G01X319295Y1441205D02*
X318695Y1441605D01*
X317995Y1441872D01*
X317195D01*
X316295Y1441472D01*
X315595Y1440805D01*
X315095Y1440005D01*
X314695Y1438672D01*
X314595Y1437472D01*
X314795Y1436272D01*
X315095Y1435472D01*
X315695Y1434672D01*
X316395Y1434139D01*
X317095Y1433872D01*
X317795D01*
X318495Y1434139D01*
X319095Y1434539D01*
X319595Y1435072D01*
G01X327095Y1433872D02*
X323095D01*
Y1441872D01*
X327095D01*
G01X325495Y1438005D02*
X323095D01*
G01X330895Y1433872D02*
Y1441872D01*
X332895D01*
X333695Y1441472D01*
X334295Y1440939D01*
X334795Y1440139D01*
X335195Y1439205D01*
X335295Y1437872D01*
X335195Y1436539D01*
X334795Y1435605D01*
X334295Y1434805D01*
X333695Y1434272D01*
X332895Y1433872D01*
X330895D01*
G01X346995Y1434938D02*
X347795Y1434272D01*
X348695Y1433872D01*
X349495D01*
X350295Y1434272D01*
X350895Y1434938D01*
X351195Y1435872D01*
X350995Y1436805D01*
X350495Y1437605D01*
X349595Y1438139D01*
X348395Y1438405D01*
X347695Y1438939D01*
X347395Y1439872D01*
X347595Y1440805D01*
X348095Y1441472D01*
X348795Y1441872D01*
X349495D01*
X350195Y1441605D01*
X350795Y1440939D01*
G01X359095Y1433872D02*
X355095D01*
Y1441872D01*
X359095D01*
G01X357495Y1438005D02*
X355095D01*
G01X363095Y1433872D02*
Y1441872D01*
X365495D01*
X366295Y1441472D01*
X366895Y1440539D01*
X367095Y1439472D01*
X366895Y1438405D01*
X366395Y1437605D01*
X365495Y1437205D01*
X363095D01*
G01X370595Y1433872D02*
X373095Y1441872D01*
X375595Y1433872D01*
G01X374695Y1436672D02*
X371495D01*
G01X379095Y1433872D02*
Y1441872D01*
X381595D01*
X382395Y1441472D01*
X382895Y1440939D01*
X383095Y1439872D01*
X382895Y1438805D01*
X382295Y1438139D01*
X381595Y1437739D01*
X379095D01*
G01X381595D02*
X383095Y1433872D01*
G01X386595D02*
X389095Y1441872D01*
X391595Y1433872D01*
G01X390695Y1436672D02*
X387495D01*
G01X397095Y1441872D02*
Y1433872D01*
G01X394795Y1441872D02*
X399395D01*
G01X407095Y1433872D02*
X403095D01*
Y1441872D01*
X407095D01*
G01X405495Y1438005D02*
X403095D01*
G01X411095Y1441872D02*
Y1433872D01*
X415095D01*
G01X421095D02*
Y1437472D01*
X419095Y1441872D01*
G01X423095D02*
X421095Y1437472D01*
G01X435195Y1433872D02*
Y1441872D01*
X438995D01*
G01X437595Y1438005D02*
X435195D01*
G01X443095Y1433872D02*
Y1441872D01*
X445595D01*
X446395Y1441472D01*
X446895Y1440939D01*
X447095Y1439872D01*
X446895Y1438805D01*
X446295Y1438139D01*
X445595Y1437739D01*
X443095D01*
G01X445595D02*
X447095Y1433872D01*
G01X453095D02*
X452295Y1434005D01*
X451595Y1434539D01*
X450995Y1435339D01*
X450595Y1436272D01*
X450395Y1437339D01*
Y1438405D01*
X450595Y1439472D01*
X450995Y1440405D01*
X451595Y1441205D01*
X452295Y1441739D01*
X453095Y1441872D01*
X453895Y1441739D01*
X454595Y1441205D01*
X455195Y1440405D01*
X455595Y1439472D01*
X455795Y1438405D01*
Y1437339D01*
X455595Y1436272D01*
X455195Y1435339D01*
X454595Y1434539D01*
X453895Y1434005D01*
X453095Y1433872D01*
G01X458495D02*
Y1441872D01*
X461095Y1435205D01*
X463695Y1441872D01*
Y1433872D01*
G01X477695Y1437872D02*
X479695D01*
Y1435472D01*
X479095Y1434672D01*
X478395Y1434139D01*
X477395Y1433872D01*
X476395Y1434139D01*
X475695Y1434672D01*
X475095Y1435472D01*
X474695Y1436405D01*
X474495Y1437472D01*
Y1438405D01*
X474695Y1439205D01*
X475095Y1440139D01*
X475695Y1440939D01*
X476295Y1441472D01*
X477095Y1441872D01*
X477795D01*
X478595Y1441605D01*
X479195Y1441072D01*
G01X483095Y1433872D02*
Y1441872D01*
X485595D01*
X486395Y1441472D01*
X486895Y1440939D01*
X487095Y1439872D01*
X486895Y1438805D01*
X486295Y1438139D01*
X485595Y1437739D01*
X483095D01*
G01X485595D02*
X487095Y1433872D01*
G01X493095D02*
X492295Y1434005D01*
X491595Y1434539D01*
X490995Y1435339D01*
X490595Y1436272D01*
X490395Y1437339D01*
Y1438405D01*
X490595Y1439472D01*
X490995Y1440405D01*
X491595Y1441205D01*
X492295Y1441739D01*
X493095Y1441872D01*
X493895Y1441739D01*
X494595Y1441205D01*
X495195Y1440405D01*
X495595Y1439472D01*
X495795Y1438405D01*
Y1437339D01*
X495595Y1436272D01*
X495195Y1435339D01*
X494595Y1434539D01*
X493895Y1434005D01*
X493095Y1433872D01*
G01X498895Y1441872D02*
Y1436139D01*
X499295Y1434938D01*
X500095Y1434139D01*
X501095Y1433872D01*
X502095Y1434139D01*
X502895Y1434938D01*
X503295Y1436139D01*
Y1441872D01*
G01X507095Y1433872D02*
Y1441872D01*
X509495D01*
X510295Y1441472D01*
X510895Y1440539D01*
X511095Y1439472D01*
X510895Y1438405D01*
X510395Y1437605D01*
X509495Y1437205D01*
X507095D01*
G01X525895Y1438139D02*
X526295Y1438539D01*
X526595Y1439205D01*
X526795Y1440139D01*
X526595Y1440939D01*
X526195Y1441472D01*
X525495Y1441872D01*
X522795D01*
Y1433872D01*
X526095D01*
X526795Y1434405D01*
X527195Y1435205D01*
X527395Y1436139D01*
X527195Y1437072D01*
X526595Y1437872D01*
X525895Y1438139D01*
X522795D01*
G01X533095Y1433605D02*
X532895Y1433739D01*
Y1434005D01*
X533095Y1434139D01*
X533295Y1434005D01*
Y1433739D01*
X533095Y1433605D01*
G01X13095Y1456872D02*
Y1448872D01*
G01X10795Y1456872D02*
X15395D01*
G01X21095Y1448872D02*
X20295Y1449005D01*
X19595Y1449539D01*
X18995Y1450339D01*
X18595Y1451272D01*
X18395Y1452339D01*
Y1453405D01*
X18595Y1454472D01*
X18995Y1455405D01*
X19595Y1456205D01*
X20295Y1456739D01*
X21095Y1456872D01*
X21895Y1456739D01*
X22595Y1456205D01*
X23195Y1455405D01*
X23595Y1454472D01*
X23795Y1453405D01*
Y1452339D01*
X23595Y1451272D01*
X23195Y1450339D01*
X22595Y1449539D01*
X21895Y1449005D01*
X21095Y1448872D01*
G01X37095Y1456872D02*
Y1448872D01*
G01X34795Y1456872D02*
X39395D01*
G01X42995Y1448872D02*
Y1456872D01*
G01X47195D02*
Y1448872D01*
G01Y1452872D02*
X42995D01*
G01X55095Y1448872D02*
X51095D01*
Y1456872D01*
X55095D01*
G01X53495Y1453005D02*
X51095D01*
G01X69895Y1453139D02*
X70295Y1453539D01*
X70595Y1454205D01*
X70795Y1455139D01*
X70595Y1455939D01*
X70195Y1456472D01*
X69495Y1456872D01*
X66795D01*
Y1448872D01*
X70095D01*
X70795Y1449405D01*
X71195Y1450205D01*
X71395Y1451139D01*
X71195Y1452072D01*
X70595Y1452872D01*
X69895Y1453139D01*
X66795D01*
G01X77095Y1448872D02*
X76295Y1449005D01*
X75595Y1449539D01*
X74995Y1450339D01*
X74595Y1451272D01*
X74395Y1452339D01*
Y1453405D01*
X74595Y1454472D01*
X74995Y1455405D01*
X75595Y1456205D01*
X76295Y1456739D01*
X77095Y1456872D01*
X77895Y1456739D01*
X78595Y1456205D01*
X79195Y1455405D01*
X79595Y1454472D01*
X79795Y1453405D01*
Y1452339D01*
X79595Y1451272D01*
X79195Y1450339D01*
X78595Y1449539D01*
X77895Y1449005D01*
X77095Y1448872D01*
G01X82595D02*
X85095Y1456872D01*
X87595Y1448872D01*
G01X86695Y1451672D02*
X83495D01*
G01X91095Y1448872D02*
Y1456872D01*
X93595D01*
X94395Y1456472D01*
X94895Y1455939D01*
X95095Y1454872D01*
X94895Y1453805D01*
X94295Y1453139D01*
X93595Y1452739D01*
X91095D01*
G01X93595D02*
X95095Y1448872D01*
G01X98895D02*
Y1456872D01*
X100895D01*
X101695Y1456472D01*
X102295Y1455939D01*
X102795Y1455139D01*
X103195Y1454205D01*
X103295Y1452872D01*
X103195Y1451539D01*
X102795Y1450605D01*
X102295Y1449805D01*
X101695Y1449272D01*
X100895Y1448872D01*
X98895D01*
G01X119295Y1456205D02*
X118695Y1456605D01*
X117995Y1456872D01*
X117195D01*
X116295Y1456472D01*
X115595Y1455805D01*
X115095Y1455005D01*
X114695Y1453672D01*
X114595Y1452472D01*
X114795Y1451272D01*
X115095Y1450472D01*
X115695Y1449672D01*
X116395Y1449139D01*
X117095Y1448872D01*
X117795D01*
X118495Y1449139D01*
X119095Y1449539D01*
X119595Y1450072D01*
G01X125095Y1448872D02*
X124295Y1449005D01*
X123595Y1449539D01*
X122995Y1450339D01*
X122595Y1451272D01*
X122395Y1452339D01*
Y1453405D01*
X122595Y1454472D01*
X122995Y1455405D01*
X123595Y1456205D01*
X124295Y1456739D01*
X125095Y1456872D01*
X125895Y1456739D01*
X126595Y1456205D01*
X127195Y1455405D01*
X127595Y1454472D01*
X127795Y1453405D01*
Y1452339D01*
X127595Y1451272D01*
X127195Y1450339D01*
X126595Y1449539D01*
X125895Y1449005D01*
X125095Y1448872D01*
G01X130895Y1456872D02*
Y1451139D01*
X131295Y1449938D01*
X132095Y1449139D01*
X133095Y1448872D01*
X134095Y1449139D01*
X134895Y1449938D01*
X135295Y1451139D01*
Y1456872D01*
G01X139095Y1448872D02*
Y1456872D01*
X141495D01*
X142295Y1456472D01*
X142895Y1455539D01*
X143095Y1454472D01*
X142895Y1453405D01*
X142395Y1452605D01*
X141495Y1452205D01*
X139095D01*
G01X149095Y1448872D02*
X148295Y1449005D01*
X147595Y1449539D01*
X146995Y1450339D01*
X146595Y1451272D01*
X146395Y1452339D01*
Y1453405D01*
X146595Y1454472D01*
X146995Y1455405D01*
X147595Y1456205D01*
X148295Y1456739D01*
X149095Y1456872D01*
X149895Y1456739D01*
X150595Y1456205D01*
X151195Y1455405D01*
X151595Y1454472D01*
X151795Y1453405D01*
Y1452339D01*
X151595Y1451272D01*
X151195Y1450339D01*
X150595Y1449539D01*
X149895Y1449005D01*
X149095Y1448872D01*
G01X154795D02*
Y1456872D01*
X159395Y1448872D01*
Y1456872D01*
G01X162995Y1449938D02*
X163795Y1449272D01*
X164695Y1448872D01*
X165495D01*
X166295Y1449272D01*
X166895Y1449938D01*
X167195Y1450872D01*
X166995Y1451805D01*
X166495Y1452605D01*
X165595Y1453139D01*
X164395Y1453405D01*
X163695Y1453939D01*
X163395Y1454872D01*
X163595Y1455805D01*
X164095Y1456472D01*
X164795Y1456872D01*
X165495D01*
X166195Y1456605D01*
X166795Y1455939D01*
G01X173095Y1448605D02*
X172895Y1448739D01*
Y1449005D01*
X173095Y1449139D01*
X173295Y1449005D01*
Y1448739D01*
X173095Y1448605D01*
G01X179895Y1456872D02*
X182295D01*
G01X181095D02*
Y1448872D01*
G01X179895D02*
X182295D01*
G01X187195D02*
Y1456872D01*
X190995D01*
G01X189595Y1453005D02*
X187195D01*
G01X203895Y1456872D02*
X206295D01*
G01X205095D02*
Y1448872D01*
G01X203895D02*
X206295D01*
G01X213095Y1456872D02*
Y1448872D01*
G01X210795Y1456872D02*
X215395D01*
G01X227895D02*
X230295D01*
G01X229095D02*
Y1448872D01*
G01X227895D02*
X230295D01*
G01X234995Y1449938D02*
X235795Y1449272D01*
X236695Y1448872D01*
X237495D01*
X238295Y1449272D01*
X238895Y1449938D01*
X239195Y1450872D01*
X238995Y1451805D01*
X238495Y1452605D01*
X237595Y1453139D01*
X236395Y1453405D01*
X235695Y1453939D01*
X235395Y1454872D01*
X235595Y1455805D01*
X236095Y1456472D01*
X236795Y1456872D01*
X237495D01*
X238195Y1456605D01*
X238795Y1455939D01*
G01X250795Y1448872D02*
Y1456872D01*
X255395Y1448872D01*
Y1456872D01*
G01X261095Y1448872D02*
X260295Y1449005D01*
X259595Y1449539D01*
X258995Y1450339D01*
X258595Y1451272D01*
X258395Y1452339D01*
Y1453405D01*
X258595Y1454472D01*
X258995Y1455405D01*
X259595Y1456205D01*
X260295Y1456739D01*
X261095Y1456872D01*
X261895Y1456739D01*
X262595Y1456205D01*
X263195Y1455405D01*
X263595Y1454472D01*
X263795Y1453405D01*
Y1452339D01*
X263595Y1451272D01*
X263195Y1450339D01*
X262595Y1449539D01*
X261895Y1449005D01*
X261095Y1448872D01*
G01X269095Y1456872D02*
Y1448872D01*
G01X266795Y1456872D02*
X271395D01*
G01X283095Y1448872D02*
Y1456872D01*
X285495D01*
X286295Y1456472D01*
X286895Y1455539D01*
X287095Y1454472D01*
X286895Y1453405D01*
X286395Y1452605D01*
X285495Y1452205D01*
X283095D01*
G01X293095Y1448872D02*
X292295Y1449005D01*
X291595Y1449539D01*
X290995Y1450339D01*
X290595Y1451272D01*
X290395Y1452339D01*
Y1453405D01*
X290595Y1454472D01*
X290995Y1455405D01*
X291595Y1456205D01*
X292295Y1456739D01*
X293095Y1456872D01*
X293895Y1456739D01*
X294595Y1456205D01*
X295195Y1455405D01*
X295595Y1454472D01*
X295795Y1453405D01*
Y1452339D01*
X295595Y1451272D01*
X295195Y1450339D01*
X294595Y1449539D01*
X293895Y1449005D01*
X293095Y1448872D01*
G01X298995Y1449938D02*
X299795Y1449272D01*
X300695Y1448872D01*
X301495D01*
X302295Y1449272D01*
X302895Y1449938D01*
X303195Y1450872D01*
X302995Y1451805D01*
X302495Y1452605D01*
X301595Y1453139D01*
X300395Y1453405D01*
X299695Y1453939D01*
X299395Y1454872D01*
X299595Y1455805D01*
X300095Y1456472D01*
X300795Y1456872D01*
X301495D01*
X302195Y1456605D01*
X302795Y1455939D01*
G01X306995Y1449938D02*
X307795Y1449272D01*
X308695Y1448872D01*
X309495D01*
X310295Y1449272D01*
X310895Y1449938D01*
X311195Y1450872D01*
X310995Y1451805D01*
X310495Y1452605D01*
X309595Y1453139D01*
X308395Y1453405D01*
X307695Y1453939D01*
X307395Y1454872D01*
X307595Y1455805D01*
X308095Y1456472D01*
X308795Y1456872D01*
X309495D01*
X310195Y1456605D01*
X310795Y1455939D01*
G01X315895Y1456872D02*
X318295D01*
G01X317095D02*
Y1448872D01*
G01X315895D02*
X318295D01*
G01X325895Y1453139D02*
X326295Y1453539D01*
X326595Y1454205D01*
X326795Y1455139D01*
X326595Y1455939D01*
X326195Y1456472D01*
X325495Y1456872D01*
X322795D01*
Y1448872D01*
X326095D01*
X326795Y1449405D01*
X327195Y1450205D01*
X327395Y1451139D01*
X327195Y1452072D01*
X326595Y1452872D01*
X325895Y1453139D01*
X322795D01*
G01X331095Y1456872D02*
Y1448872D01*
X335095D01*
G01X343095D02*
X339095D01*
Y1456872D01*
X343095D01*
G01X341495Y1453005D02*
X339095D01*
G01X357095Y1456872D02*
Y1448872D01*
G01X354795Y1456872D02*
X359395D01*
G01X365095Y1448872D02*
X364295Y1449005D01*
X363595Y1449539D01*
X362995Y1450339D01*
X362595Y1451272D01*
X362395Y1452339D01*
Y1453405D01*
X362595Y1454472D01*
X362995Y1455405D01*
X363595Y1456205D01*
X364295Y1456739D01*
X365095Y1456872D01*
X365895Y1456739D01*
X366595Y1456205D01*
X367195Y1455405D01*
X367595Y1454472D01*
X367795Y1453405D01*
Y1452339D01*
X367595Y1451272D01*
X367195Y1450339D01*
X366595Y1449539D01*
X365895Y1449005D01*
X365095Y1448872D01*
G01X379195D02*
Y1456872D01*
X382995D01*
G01X381595Y1453005D02*
X379195D01*
G01X387895Y1456872D02*
X390295D01*
G01X389095D02*
Y1448872D01*
G01X387895D02*
X390295D01*
G01X397095Y1456872D02*
Y1448872D01*
G01X394795Y1456872D02*
X399395D01*
G01X411895D02*
X414295D01*
G01X413095D02*
Y1448872D01*
G01X411895D02*
X414295D01*
G01X418795D02*
Y1456872D01*
X423395Y1448872D01*
Y1456872D01*
G01X437095D02*
Y1448872D01*
G01X434795Y1456872D02*
X439395D01*
G01X442995Y1448872D02*
Y1456872D01*
G01X447195D02*
Y1448872D01*
G01Y1452872D02*
X442995D01*
G01X455095Y1448872D02*
X451095D01*
Y1456872D01*
X455095D01*
G01X453495Y1453005D02*
X451095D01*
G01X467095Y1456872D02*
Y1448872D01*
X471095D01*
G01X477095D02*
X476295Y1449005D01*
X475595Y1449539D01*
X474995Y1450339D01*
X474595Y1451272D01*
X474395Y1452339D01*
Y1453405D01*
X474595Y1454472D01*
X474995Y1455405D01*
X475595Y1456205D01*
X476295Y1456739D01*
X477095Y1456872D01*
X477895Y1456739D01*
X478595Y1456205D01*
X479195Y1455405D01*
X479595Y1454472D01*
X479795Y1453405D01*
Y1452339D01*
X479595Y1451272D01*
X479195Y1450339D01*
X478595Y1449539D01*
X477895Y1449005D01*
X477095Y1448872D01*
G01X487295Y1456205D02*
X486695Y1456605D01*
X485995Y1456872D01*
X485195D01*
X484295Y1456472D01*
X483595Y1455805D01*
X483095Y1455005D01*
X482695Y1453672D01*
X482595Y1452472D01*
X482795Y1451272D01*
X483095Y1450472D01*
X483695Y1449672D01*
X484395Y1449139D01*
X485095Y1448872D01*
X485795D01*
X486495Y1449139D01*
X487095Y1449539D01*
X487595Y1450072D01*
G01X490595Y1448872D02*
X493095Y1456872D01*
X495595Y1448872D01*
G01X494695Y1451672D02*
X491495D01*
G01X501095Y1456872D02*
Y1448872D01*
G01X498795Y1456872D02*
X503395D01*
G01X507895D02*
X510295D01*
G01X509095D02*
Y1448872D01*
G01X507895D02*
X510295D01*
G01X517095D02*
X516295Y1449005D01*
X515595Y1449539D01*
X514995Y1450339D01*
X514595Y1451272D01*
X514395Y1452339D01*
Y1453405D01*
X514595Y1454472D01*
X514995Y1455405D01*
X515595Y1456205D01*
X516295Y1456739D01*
X517095Y1456872D01*
X517895Y1456739D01*
X518595Y1456205D01*
X519195Y1455405D01*
X519595Y1454472D01*
X519795Y1453405D01*
Y1452339D01*
X519595Y1451272D01*
X519195Y1450339D01*
X518595Y1449539D01*
X517895Y1449005D01*
X517095Y1448872D01*
G01X522795D02*
Y1456872D01*
X527395Y1448872D01*
Y1456872D01*
G01X530995Y1449938D02*
X531795Y1449272D01*
X532695Y1448872D01*
X533495D01*
X534295Y1449272D01*
X534895Y1449938D01*
X535195Y1450872D01*
X534995Y1451805D01*
X534495Y1452605D01*
X533595Y1453139D01*
X532395Y1453405D01*
X531695Y1453939D01*
X531395Y1454872D01*
X531595Y1455805D01*
X532095Y1456472D01*
X532795Y1456872D01*
X533495D01*
X534195Y1456605D01*
X534795Y1455939D01*
G01X547195Y1448872D02*
Y1456872D01*
X550995D01*
G01X549595Y1453005D02*
X547195D01*
G01X557095Y1448872D02*
X556295Y1449005D01*
X555595Y1449539D01*
X554995Y1450339D01*
X554595Y1451272D01*
X554395Y1452339D01*
Y1453405D01*
X554595Y1454472D01*
X554995Y1455405D01*
X555595Y1456205D01*
X556295Y1456739D01*
X557095Y1456872D01*
X557895Y1456739D01*
X558595Y1456205D01*
X559195Y1455405D01*
X559595Y1454472D01*
X559795Y1453405D01*
Y1452339D01*
X559595Y1451272D01*
X559195Y1450339D01*
X558595Y1449539D01*
X557895Y1449005D01*
X557095Y1448872D01*
G01X563095D02*
Y1456872D01*
X565595D01*
X566395Y1456472D01*
X566895Y1455939D01*
X567095Y1454872D01*
X566895Y1453805D01*
X566295Y1453139D01*
X565595Y1452739D01*
X563095D01*
G01X565595D02*
X567095Y1448872D01*
G01X581895Y1453139D02*
X582295Y1453539D01*
X582595Y1454205D01*
X582795Y1455139D01*
X582595Y1455939D01*
X582195Y1456472D01*
X581495Y1456872D01*
X578795D01*
Y1448872D01*
X582095D01*
X582795Y1449405D01*
X583195Y1450205D01*
X583395Y1451139D01*
X583195Y1452072D01*
X582595Y1452872D01*
X581895Y1453139D01*
X578795D01*
G01X589095Y1448872D02*
X588295Y1449005D01*
X587595Y1449539D01*
X586995Y1450339D01*
X586595Y1451272D01*
X586395Y1452339D01*
Y1453405D01*
X586595Y1454472D01*
X586995Y1455405D01*
X587595Y1456205D01*
X588295Y1456739D01*
X589095Y1456872D01*
X589895Y1456739D01*
X590595Y1456205D01*
X591195Y1455405D01*
X591595Y1454472D01*
X591795Y1453405D01*
Y1452339D01*
X591595Y1451272D01*
X591195Y1450339D01*
X590595Y1449539D01*
X589895Y1449005D01*
X589095Y1448872D01*
G01X597095Y1456872D02*
Y1448872D01*
G01X594795Y1456872D02*
X599395D01*
G01X602995Y1448872D02*
Y1456872D01*
G01X607195D02*
Y1448872D01*
G01Y1452872D02*
X602995D01*
G01X11095Y1463872D02*
Y1471872D01*
X13495D01*
X14295Y1471472D01*
X14895Y1470539D01*
X15095Y1469472D01*
X14895Y1468405D01*
X14395Y1467605D01*
X13495Y1467205D01*
X11095D01*
G01X19095Y1471872D02*
Y1463872D01*
X23095D01*
G01X31095D02*
X27095D01*
Y1471872D01*
X31095D01*
G01X29495Y1468005D02*
X27095D01*
G01X34595Y1463872D02*
X37095Y1471872D01*
X39595Y1463872D01*
G01X38695Y1466672D02*
X35495D01*
G01X42995Y1464938D02*
X43795Y1464272D01*
X44695Y1463872D01*
X45495D01*
X46295Y1464272D01*
X46895Y1464938D01*
X47195Y1465872D01*
X46995Y1466805D01*
X46495Y1467605D01*
X45595Y1468139D01*
X44395Y1468405D01*
X43695Y1468939D01*
X43395Y1469872D01*
X43595Y1470805D01*
X44095Y1471472D01*
X44795Y1471872D01*
X45495D01*
X46195Y1471605D01*
X46795Y1470939D01*
G01X55095Y1463872D02*
X51095D01*
Y1471872D01*
X55095D01*
G01X53495Y1468005D02*
X51095D01*
G01X67195Y1463872D02*
Y1471872D01*
X70995D01*
G01X69595Y1468005D02*
X67195D01*
G01X77095Y1463872D02*
X76295Y1464005D01*
X75595Y1464539D01*
X74995Y1465339D01*
X74595Y1466272D01*
X74395Y1467339D01*
Y1468405D01*
X74595Y1469472D01*
X74995Y1470405D01*
X75595Y1471205D01*
X76295Y1471739D01*
X77095Y1471872D01*
X77895Y1471739D01*
X78595Y1471205D01*
X79195Y1470405D01*
X79595Y1469472D01*
X79795Y1468405D01*
Y1467339D01*
X79595Y1466272D01*
X79195Y1465339D01*
X78595Y1464539D01*
X77895Y1464005D01*
X77095Y1463872D01*
G01X83095Y1471872D02*
Y1463872D01*
X87095D01*
G01X91095Y1471872D02*
Y1463872D01*
X95095D01*
G01X101095D02*
X100295Y1464005D01*
X99595Y1464539D01*
X98995Y1465339D01*
X98595Y1466272D01*
X98395Y1467339D01*
Y1468405D01*
X98595Y1469472D01*
X98995Y1470405D01*
X99595Y1471205D01*
X100295Y1471739D01*
X101095Y1471872D01*
X101895Y1471739D01*
X102595Y1471205D01*
X103195Y1470405D01*
X103595Y1469472D01*
X103795Y1468405D01*
Y1467339D01*
X103595Y1466272D01*
X103195Y1465339D01*
X102595Y1464539D01*
X101895Y1464005D01*
X101095Y1463872D01*
G01X106095Y1471872D02*
X107495Y1463872D01*
X109095Y1471872D01*
X110695Y1463872D01*
X112095Y1471872D01*
G01X125095D02*
Y1463872D01*
G01X122795Y1471872D02*
X127395D01*
G01X130995Y1463872D02*
Y1471872D01*
G01X135195D02*
Y1463872D01*
G01Y1467872D02*
X130995D01*
G01X143095Y1463872D02*
X139095D01*
Y1471872D01*
X143095D01*
G01X141495Y1468005D02*
X139095D01*
G01X154995Y1464938D02*
X155795Y1464272D01*
X156695Y1463872D01*
X157495D01*
X158295Y1464272D01*
X158895Y1464938D01*
X159195Y1465872D01*
X158995Y1466805D01*
X158495Y1467605D01*
X157595Y1468139D01*
X156395Y1468405D01*
X155695Y1468939D01*
X155395Y1469872D01*
X155595Y1470805D01*
X156095Y1471472D01*
X156795Y1471872D01*
X157495D01*
X158195Y1471605D01*
X158795Y1470939D01*
G01X163095Y1471872D02*
Y1463872D01*
X167095D01*
G01X171895Y1471872D02*
X174295D01*
G01X173095D02*
Y1463872D01*
G01X171895D02*
X174295D01*
G01X178895D02*
Y1471872D01*
X180895D01*
X181695Y1471472D01*
X182295Y1470939D01*
X182795Y1470139D01*
X183195Y1469205D01*
X183295Y1467872D01*
X183195Y1466539D01*
X182795Y1465605D01*
X182295Y1464805D01*
X181695Y1464272D01*
X180895Y1463872D01*
X178895D01*
G01X191095D02*
X187095D01*
Y1471872D01*
X191095D01*
G01X189495Y1468005D02*
X187095D01*
G01X194995Y1464938D02*
X195795Y1464272D01*
X196695Y1463872D01*
X197495D01*
X198295Y1464272D01*
X198895Y1464938D01*
X199195Y1465872D01*
X198995Y1466805D01*
X198495Y1467605D01*
X197595Y1468139D01*
X196395Y1468405D01*
X195695Y1468939D01*
X195395Y1469872D01*
X195595Y1470805D01*
X196095Y1471472D01*
X196795Y1471872D01*
X197495D01*
X198195Y1471605D01*
X198795Y1470939D01*
G01X213095Y1471872D02*
Y1463872D01*
G01X210795Y1471872D02*
X215395D01*
G01X221095Y1463872D02*
X220295Y1464005D01*
X219595Y1464539D01*
X218995Y1465339D01*
X218595Y1466272D01*
X218395Y1467339D01*
Y1468405D01*
X218595Y1469472D01*
X218995Y1470405D01*
X219595Y1471205D01*
X220295Y1471739D01*
X221095Y1471872D01*
X221895Y1471739D01*
X222595Y1471205D01*
X223195Y1470405D01*
X223595Y1469472D01*
X223795Y1468405D01*
Y1467339D01*
X223595Y1466272D01*
X223195Y1465339D01*
X222595Y1464539D01*
X221895Y1464005D01*
X221095Y1463872D01*
G01X237695Y1467872D02*
X239695D01*
Y1465472D01*
X239095Y1464672D01*
X238395Y1464139D01*
X237395Y1463872D01*
X236395Y1464139D01*
X235695Y1464672D01*
X235095Y1465472D01*
X234695Y1466405D01*
X234495Y1467472D01*
Y1468405D01*
X234695Y1469205D01*
X235095Y1470139D01*
X235695Y1470939D01*
X236295Y1471472D01*
X237095Y1471872D01*
X237795D01*
X238595Y1471605D01*
X239195Y1471072D01*
G01X247095Y1463872D02*
X243095D01*
Y1471872D01*
X247095D01*
G01X245495Y1468005D02*
X243095D01*
G01X250795Y1463872D02*
Y1471872D01*
X255395Y1463872D01*
Y1471872D01*
G01X263095Y1463872D02*
X259095D01*
Y1471872D01*
X263095D01*
G01X261495Y1468005D02*
X259095D01*
G01X267095Y1463872D02*
Y1471872D01*
X269595D01*
X270395Y1471472D01*
X270895Y1470939D01*
X271095Y1469872D01*
X270895Y1468805D01*
X270295Y1468139D01*
X269595Y1467739D01*
X267095D01*
G01X269595D02*
X271095Y1463872D01*
G01X274595D02*
X277095Y1471872D01*
X279595Y1463872D01*
G01X278695Y1466672D02*
X275495D01*
G01X285095Y1471872D02*
Y1463872D01*
G01X282795Y1471872D02*
X287395D01*
G01X295095Y1463872D02*
X291095D01*
Y1471872D01*
X295095D01*
G01X293495Y1468005D02*
X291095D01*
G01X309095Y1471872D02*
Y1463872D01*
G01X306795Y1471872D02*
X311395D01*
G01X314995Y1463872D02*
Y1471872D01*
G01X319195D02*
Y1463872D01*
G01Y1467872D02*
X314995D01*
G01X327095Y1463872D02*
X323095D01*
Y1471872D01*
X327095D01*
G01X325495Y1468005D02*
X323095D01*
G01X339095Y1463872D02*
Y1471872D01*
X341495D01*
X342295Y1471472D01*
X342895Y1470539D01*
X343095Y1469472D01*
X342895Y1468405D01*
X342395Y1467605D01*
X341495Y1467205D01*
X339095D01*
G01X346595Y1463872D02*
X349095Y1471872D01*
X351595Y1463872D01*
G01X350695Y1466672D02*
X347495D01*
G01X354895Y1463872D02*
Y1471872D01*
X356895D01*
X357695Y1471472D01*
X358295Y1470939D01*
X358795Y1470139D01*
X359195Y1469205D01*
X359295Y1467872D01*
X359195Y1466539D01*
X358795Y1465605D01*
X358295Y1464805D01*
X357695Y1464272D01*
X356895Y1463872D01*
X354895D01*
G01X362995Y1464938D02*
X363795Y1464272D01*
X364695Y1463872D01*
X365495D01*
X366295Y1464272D01*
X366895Y1464938D01*
X367195Y1465872D01*
X366995Y1466805D01*
X366495Y1467605D01*
X365595Y1468139D01*
X364395Y1468405D01*
X363695Y1468939D01*
X363395Y1469872D01*
X363595Y1470805D01*
X364095Y1471472D01*
X364795Y1471872D01*
X365495D01*
X366195Y1471605D01*
X366795Y1470939D01*
G01X378595Y1463872D02*
X381095Y1471872D01*
X383595Y1463872D01*
G01X382695Y1466672D02*
X379495D01*
G01X386795Y1463872D02*
Y1471872D01*
X391395Y1463872D01*
Y1471872D01*
G01X394895Y1463872D02*
Y1471872D01*
X396895D01*
X397695Y1471472D01*
X398295Y1470939D01*
X398795Y1470139D01*
X399195Y1469205D01*
X399295Y1467872D01*
X399195Y1466539D01*
X398795Y1465605D01*
X398295Y1464805D01*
X397695Y1464272D01*
X396895Y1463872D01*
X394895D01*
G01X410495D02*
Y1471872D01*
X413095Y1465205D01*
X415695Y1471872D01*
Y1463872D01*
G01X418595D02*
X421095Y1471872D01*
X423595Y1463872D01*
G01X422695Y1466672D02*
X419495D01*
G01X426995Y1464938D02*
X427795Y1464272D01*
X428695Y1463872D01*
X429495D01*
X430295Y1464272D01*
X430895Y1464938D01*
X431195Y1465872D01*
X430995Y1466805D01*
X430495Y1467605D01*
X429595Y1468139D01*
X428395Y1468405D01*
X427695Y1468939D01*
X427395Y1469872D01*
X427595Y1470805D01*
X428095Y1471472D01*
X428795Y1471872D01*
X429495D01*
X430195Y1471605D01*
X430795Y1470939D01*
G01X434895Y1463872D02*
Y1471872D01*
G01X438695D02*
X434895Y1466938D01*
G01X439295Y1463872D02*
X436595Y1469205D01*
G01X450595Y1463872D02*
X453095Y1471872D01*
X455595Y1463872D01*
G01X454695Y1466672D02*
X451495D01*
G01X458795Y1463872D02*
Y1471872D01*
X463395Y1463872D01*
Y1471872D01*
G01X466895Y1463872D02*
Y1471872D01*
X468895D01*
X469695Y1471472D01*
X470295Y1470939D01*
X470795Y1470139D01*
X471195Y1469205D01*
X471295Y1467872D01*
X471195Y1466539D01*
X470795Y1465605D01*
X470295Y1464805D01*
X469695Y1464272D01*
X468895Y1463872D01*
X466895D01*
G01X482595D02*
X485095Y1471872D01*
X487595Y1463872D01*
G01X486695Y1466672D02*
X483495D01*
G01X490895Y1463872D02*
Y1471872D01*
X492895D01*
X493695Y1471472D01*
X494295Y1470939D01*
X494795Y1470139D01*
X495195Y1469205D01*
X495295Y1467872D01*
X495195Y1466539D01*
X494795Y1465605D01*
X494295Y1464805D01*
X493695Y1464272D01*
X492895Y1463872D01*
X490895D01*
G01X498895D02*
Y1471872D01*
X500895D01*
X501695Y1471472D01*
X502295Y1470939D01*
X502795Y1470139D01*
X503195Y1469205D01*
X503295Y1467872D01*
X503195Y1466539D01*
X502795Y1465605D01*
X502295Y1464805D01*
X501695Y1464272D01*
X500895Y1463872D01*
X498895D01*
G01X517095Y1471872D02*
Y1463872D01*
G01X514795Y1471872D02*
X519395D01*
G01X522995Y1463872D02*
Y1471872D01*
G01X527195D02*
Y1463872D01*
G01Y1467872D02*
X522995D01*
G01X535095Y1463872D02*
X531095D01*
Y1471872D01*
X535095D01*
G01X533495Y1468005D02*
X531095D01*
G01X549095Y1471872D02*
Y1463872D01*
G01X546795Y1471872D02*
X551395D01*
G01X559095Y1463872D02*
X555095D01*
Y1471872D01*
X559095D01*
G01X557495Y1468005D02*
X555095D01*
G01X562995Y1464938D02*
X563795Y1464272D01*
X564695Y1463872D01*
X565495D01*
X566295Y1464272D01*
X566895Y1464938D01*
X567195Y1465872D01*
X566995Y1466805D01*
X566495Y1467605D01*
X565595Y1468139D01*
X564395Y1468405D01*
X563695Y1468939D01*
X563395Y1469872D01*
X563595Y1470805D01*
X564095Y1471472D01*
X564795Y1471872D01*
X565495D01*
X566195Y1471605D01*
X566795Y1470939D01*
G01X573095Y1471872D02*
Y1463872D01*
G01X570795Y1471872D02*
X575395D01*
G01X587095Y1463872D02*
Y1471872D01*
X589495D01*
X590295Y1471472D01*
X590895Y1470539D01*
X591095Y1469472D01*
X590895Y1468405D01*
X590395Y1467605D01*
X589495Y1467205D01*
X587095D01*
G01X594595Y1463872D02*
X597095Y1471872D01*
X599595Y1463872D01*
G01X598695Y1466672D02*
X595495D01*
G01X602895Y1463872D02*
Y1471872D01*
X604895D01*
X605695Y1471472D01*
X606295Y1470939D01*
X606795Y1470139D01*
X607195Y1469205D01*
X607295Y1467872D01*
X607195Y1466539D01*
X606795Y1465605D01*
X606295Y1464805D01*
X605695Y1464272D01*
X604895Y1463872D01*
X602895D01*
G01X610995Y1464938D02*
X611795Y1464272D01*
X612695Y1463872D01*
X613495D01*
X614295Y1464272D01*
X614895Y1464938D01*
X615195Y1465872D01*
X614995Y1466805D01*
X614495Y1467605D01*
X613595Y1468139D01*
X612395Y1468405D01*
X611695Y1468939D01*
X611395Y1469872D01*
X611595Y1470805D01*
X612095Y1471472D01*
X612795Y1471872D01*
X613495D01*
X614195Y1471605D01*
X614795Y1470939D01*
G01X10595Y1493872D02*
X13095Y1501872D01*
X15595Y1493872D01*
G01X14695Y1496672D02*
X11495D01*
G01X18795Y1493872D02*
Y1501872D01*
X23395Y1493872D01*
Y1501872D01*
G01X29095Y1493872D02*
Y1497472D01*
X27095Y1501872D01*
G01X31095D02*
X29095Y1497472D01*
G01X43095Y1493872D02*
Y1501872D01*
X45495D01*
X46295Y1501472D01*
X46895Y1500539D01*
X47095Y1499472D01*
X46895Y1498405D01*
X46395Y1497605D01*
X45495Y1497205D01*
X43095D01*
G01X51095Y1493872D02*
Y1501872D01*
X53595D01*
X54395Y1501472D01*
X54895Y1500939D01*
X55095Y1499872D01*
X54895Y1498805D01*
X54295Y1498139D01*
X53595Y1497739D01*
X51095D01*
G01X53595D02*
X55095Y1493872D01*
G01X61095D02*
X60295Y1494005D01*
X59595Y1494539D01*
X58995Y1495339D01*
X58595Y1496272D01*
X58395Y1497339D01*
Y1498405D01*
X58595Y1499472D01*
X58995Y1500405D01*
X59595Y1501205D01*
X60295Y1501739D01*
X61095Y1501872D01*
X61895Y1501739D01*
X62595Y1501205D01*
X63195Y1500405D01*
X63595Y1499472D01*
X63795Y1498405D01*
Y1497339D01*
X63595Y1496272D01*
X63195Y1495339D01*
X62595Y1494539D01*
X61895Y1494005D01*
X61095Y1493872D01*
G01X67095D02*
Y1501872D01*
X69495D01*
X70295Y1501472D01*
X70895Y1500539D01*
X71095Y1499472D01*
X70895Y1498405D01*
X70395Y1497605D01*
X69495Y1497205D01*
X67095D01*
G01X77095Y1493872D02*
X76295Y1494005D01*
X75595Y1494539D01*
X74995Y1495339D01*
X74595Y1496272D01*
X74395Y1497339D01*
Y1498405D01*
X74595Y1499472D01*
X74995Y1500405D01*
X75595Y1501205D01*
X76295Y1501739D01*
X77095Y1501872D01*
X77895Y1501739D01*
X78595Y1501205D01*
X79195Y1500405D01*
X79595Y1499472D01*
X79795Y1498405D01*
Y1497339D01*
X79595Y1496272D01*
X79195Y1495339D01*
X78595Y1494539D01*
X77895Y1494005D01*
X77095Y1493872D01*
G01X82995Y1494938D02*
X83795Y1494272D01*
X84695Y1493872D01*
X85495D01*
X86295Y1494272D01*
X86895Y1494938D01*
X87195Y1495872D01*
X86995Y1496805D01*
X86495Y1497605D01*
X85595Y1498139D01*
X84395Y1498405D01*
X83695Y1498939D01*
X83395Y1499872D01*
X83595Y1500805D01*
X84095Y1501472D01*
X84795Y1501872D01*
X85495D01*
X86195Y1501605D01*
X86795Y1500939D01*
G01X95095Y1493872D02*
X91095D01*
Y1501872D01*
X95095D01*
G01X93495Y1498005D02*
X91095D01*
G01X98895Y1493872D02*
Y1501872D01*
X100895D01*
X101695Y1501472D01*
X102295Y1500939D01*
X102795Y1500139D01*
X103195Y1499205D01*
X103295Y1497872D01*
X103195Y1496539D01*
X102795Y1495605D01*
X102295Y1494805D01*
X101695Y1494272D01*
X100895Y1493872D01*
X98895D01*
G01X119295Y1501205D02*
X118695Y1501605D01*
X117995Y1501872D01*
X117195D01*
X116295Y1501472D01*
X115595Y1500805D01*
X115095Y1500005D01*
X114695Y1498672D01*
X114595Y1497472D01*
X114795Y1496272D01*
X115095Y1495472D01*
X115695Y1494672D01*
X116395Y1494139D01*
X117095Y1493872D01*
X117795D01*
X118495Y1494139D01*
X119095Y1494539D01*
X119595Y1495072D01*
G01X122995Y1493872D02*
Y1501872D01*
G01X127195D02*
Y1493872D01*
G01Y1497872D02*
X122995D01*
G01X130595Y1493872D02*
X133095Y1501872D01*
X135595Y1493872D01*
G01X134695Y1496672D02*
X131495D01*
G01X138795Y1493872D02*
Y1501872D01*
X143395Y1493872D01*
Y1501872D01*
G01X149695Y1497872D02*
X151695D01*
Y1495472D01*
X151095Y1494672D01*
X150395Y1494139D01*
X149395Y1493872D01*
X148395Y1494139D01*
X147695Y1494672D01*
X147095Y1495472D01*
X146695Y1496405D01*
X146495Y1497472D01*
Y1498405D01*
X146695Y1499205D01*
X147095Y1500139D01*
X147695Y1500939D01*
X148295Y1501472D01*
X149095Y1501872D01*
X149795D01*
X150595Y1501605D01*
X151195Y1501072D01*
G01X159095Y1493872D02*
X155095D01*
Y1501872D01*
X159095D01*
G01X157495Y1498005D02*
X155095D01*
G01X171095Y1493872D02*
Y1501872D01*
X173595D01*
X174395Y1501472D01*
X174895Y1500939D01*
X175095Y1499872D01*
X174895Y1498805D01*
X174295Y1498139D01*
X173595Y1497739D01*
X171095D01*
G01X173595D02*
X175095Y1493872D01*
G01X183095D02*
X179095D01*
Y1501872D01*
X183095D01*
G01X181495Y1498005D02*
X179095D01*
G01X189095Y1493872D02*
X188295Y1494005D01*
X187595Y1494539D01*
X186995Y1495339D01*
X186595Y1496272D01*
X186395Y1497339D01*
Y1498405D01*
X186595Y1499472D01*
X186995Y1500405D01*
X187595Y1501205D01*
X188295Y1501739D01*
X189095Y1501872D01*
X189895Y1501739D01*
X190595Y1501205D01*
X191195Y1500405D01*
X191595Y1499472D01*
X191795Y1498405D01*
Y1497339D01*
X191595Y1496272D01*
X191195Y1495339D01*
X190595Y1494539D01*
X189895Y1494005D01*
X189095Y1493872D01*
G01X189895Y1496005D02*
X191095Y1493872D01*
G01X194895Y1501872D02*
Y1496139D01*
X195295Y1494938D01*
X196095Y1494139D01*
X197095Y1493872D01*
X198095Y1494139D01*
X198895Y1494938D01*
X199295Y1496139D01*
Y1501872D01*
G01X207095Y1493872D02*
X203095D01*
Y1501872D01*
X207095D01*
G01X205495Y1498005D02*
X203095D01*
G01X210995Y1494938D02*
X211795Y1494272D01*
X212695Y1493872D01*
X213495D01*
X214295Y1494272D01*
X214895Y1494938D01*
X215195Y1495872D01*
X214995Y1496805D01*
X214495Y1497605D01*
X213595Y1498139D01*
X212395Y1498405D01*
X211695Y1498939D01*
X211395Y1499872D01*
X211595Y1500805D01*
X212095Y1501472D01*
X212795Y1501872D01*
X213495D01*
X214195Y1501605D01*
X214795Y1500939D01*
G01X221095Y1501872D02*
Y1493872D01*
G01X218795Y1501872D02*
X223395D01*
G01X234495Y1493872D02*
Y1501872D01*
X237095Y1495205D01*
X239695Y1501872D01*
Y1493872D01*
G01X242895Y1501872D02*
Y1496139D01*
X243295Y1494938D01*
X244095Y1494139D01*
X245095Y1493872D01*
X246095Y1494139D01*
X246895Y1494938D01*
X247295Y1496139D01*
Y1501872D01*
G01X250995Y1494938D02*
X251795Y1494272D01*
X252695Y1493872D01*
X253495D01*
X254295Y1494272D01*
X254895Y1494938D01*
X255195Y1495872D01*
X254995Y1496805D01*
X254495Y1497605D01*
X253595Y1498139D01*
X252395Y1498405D01*
X251695Y1498939D01*
X251395Y1499872D01*
X251595Y1500805D01*
X252095Y1501472D01*
X252795Y1501872D01*
X253495D01*
X254195Y1501605D01*
X254795Y1500939D01*
G01X261095Y1501872D02*
Y1493872D01*
G01X258795Y1501872D02*
X263395D01*
G01X277895Y1498139D02*
X278295Y1498539D01*
X278595Y1499205D01*
X278795Y1500139D01*
X278595Y1500939D01*
X278195Y1501472D01*
X277495Y1501872D01*
X274795D01*
Y1493872D01*
X278095D01*
X278795Y1494405D01*
X279195Y1495205D01*
X279395Y1496139D01*
X279195Y1497072D01*
X278595Y1497872D01*
X277895Y1498139D01*
X274795D01*
G01X287095Y1493872D02*
X283095D01*
Y1501872D01*
X287095D01*
G01X285495Y1498005D02*
X283095D01*
G01X298595Y1493872D02*
X301095Y1501872D01*
X303595Y1493872D01*
G01X302695Y1496672D02*
X299495D01*
G01X307095Y1493872D02*
Y1501872D01*
X309495D01*
X310295Y1501472D01*
X310895Y1500539D01*
X311095Y1499472D01*
X310895Y1498405D01*
X310395Y1497605D01*
X309495Y1497205D01*
X307095D01*
G01X315095Y1493872D02*
Y1501872D01*
X317495D01*
X318295Y1501472D01*
X318895Y1500539D01*
X319095Y1499472D01*
X318895Y1498405D01*
X318395Y1497605D01*
X317495Y1497205D01*
X315095D01*
G01X323095Y1493872D02*
Y1501872D01*
X325595D01*
X326395Y1501472D01*
X326895Y1500939D01*
X327095Y1499872D01*
X326895Y1498805D01*
X326295Y1498139D01*
X325595Y1497739D01*
X323095D01*
G01X325595D02*
X327095Y1493872D01*
G01X333095D02*
X332295Y1494005D01*
X331595Y1494539D01*
X330995Y1495339D01*
X330595Y1496272D01*
X330395Y1497339D01*
Y1498405D01*
X330595Y1499472D01*
X330995Y1500405D01*
X331595Y1501205D01*
X332295Y1501739D01*
X333095Y1501872D01*
X333895Y1501739D01*
X334595Y1501205D01*
X335195Y1500405D01*
X335595Y1499472D01*
X335795Y1498405D01*
Y1497339D01*
X335595Y1496272D01*
X335195Y1495339D01*
X334595Y1494539D01*
X333895Y1494005D01*
X333095Y1493872D01*
G01X338595Y1501872D02*
X341095Y1493872D01*
X343595Y1501872D01*
G01X351095Y1493872D02*
X347095D01*
Y1501872D01*
X351095D01*
G01X349495Y1498005D02*
X347095D01*
G01X354895Y1493872D02*
Y1501872D01*
X356895D01*
X357695Y1501472D01*
X358295Y1500939D01*
X358795Y1500139D01*
X359195Y1499205D01*
X359295Y1497872D01*
X359195Y1496539D01*
X358795Y1495605D01*
X358295Y1494805D01*
X357695Y1494272D01*
X356895Y1493872D01*
X354895D01*
G01X373895Y1498139D02*
X374295Y1498539D01*
X374595Y1499205D01*
X374795Y1500139D01*
X374595Y1500939D01*
X374195Y1501472D01*
X373495Y1501872D01*
X370795D01*
Y1493872D01*
X374095D01*
X374795Y1494405D01*
X375195Y1495205D01*
X375395Y1496139D01*
X375195Y1497072D01*
X374595Y1497872D01*
X373895Y1498139D01*
X370795D01*
G01X381095Y1493872D02*
Y1497472D01*
X379095Y1501872D01*
G01X383095D02*
X381095Y1497472D01*
G01X397095Y1493872D02*
X396295Y1494005D01*
X395595Y1494539D01*
X394995Y1495339D01*
X394595Y1496272D01*
X394395Y1497339D01*
Y1498405D01*
X394595Y1499472D01*
X394995Y1500405D01*
X395595Y1501205D01*
X396295Y1501739D01*
X397095Y1501872D01*
X397895Y1501739D01*
X398595Y1501205D01*
X399195Y1500405D01*
X399595Y1499472D01*
X399795Y1498405D01*
Y1497339D01*
X399595Y1496272D01*
X399195Y1495339D01*
X398595Y1494539D01*
X397895Y1494005D01*
X397095Y1493872D01*
G01X397895Y1496005D02*
X399095Y1493872D01*
G01X402895Y1501872D02*
Y1496139D01*
X403295Y1494938D01*
X404095Y1494139D01*
X405095Y1493872D01*
X406095Y1494139D01*
X406895Y1494938D01*
X407295Y1496139D01*
Y1501872D01*
G01X410595Y1493872D02*
X413095Y1501872D01*
X415595Y1493872D01*
G01X414695Y1496672D02*
X411495D01*
G01X418795Y1493872D02*
Y1501872D01*
X423395Y1493872D01*
Y1501872D01*
G01X429095D02*
Y1493872D01*
G01X426795Y1501872D02*
X431395D01*
G01X434595Y1493872D02*
X437095Y1501872D01*
X439595Y1493872D01*
G01X438695Y1496672D02*
X435495D01*
G01X451095Y1493872D02*
Y1501872D01*
X453495D01*
X454295Y1501472D01*
X454895Y1500539D01*
X455095Y1499472D01*
X454895Y1498405D01*
X454395Y1497605D01*
X453495Y1497205D01*
X451095D01*
G01X459095Y1493872D02*
Y1501872D01*
X461595D01*
X462395Y1501472D01*
X462895Y1500939D01*
X463095Y1499872D01*
X462895Y1498805D01*
X462295Y1498139D01*
X461595Y1497739D01*
X459095D01*
G01X461595D02*
X463095Y1493872D01*
G01X467895Y1501872D02*
X470295D01*
G01X469095D02*
Y1493872D01*
G01X467895D02*
X470295D01*
G01X477095D02*
X476295Y1494005D01*
X475595Y1494539D01*
X474995Y1495339D01*
X474595Y1496272D01*
X474395Y1497339D01*
Y1498405D01*
X474595Y1499472D01*
X474995Y1500405D01*
X475595Y1501205D01*
X476295Y1501739D01*
X477095Y1501872D01*
X477895Y1501739D01*
X478595Y1501205D01*
X479195Y1500405D01*
X479595Y1499472D01*
X479795Y1498405D01*
Y1497339D01*
X479595Y1496272D01*
X479195Y1495339D01*
X478595Y1494539D01*
X477895Y1494005D01*
X477095Y1493872D01*
G01X483095D02*
Y1501872D01*
X485595D01*
X486395Y1501472D01*
X486895Y1500939D01*
X487095Y1499872D01*
X486895Y1498805D01*
X486295Y1498139D01*
X485595Y1497739D01*
X483095D01*
G01X485595D02*
X487095Y1493872D01*
G01X501095Y1501872D02*
Y1493872D01*
G01X498795Y1501872D02*
X503395D01*
G01X509095Y1493872D02*
X508295Y1494005D01*
X507595Y1494539D01*
X506995Y1495339D01*
X506595Y1496272D01*
X506395Y1497339D01*
Y1498405D01*
X506595Y1499472D01*
X506995Y1500405D01*
X507595Y1501205D01*
X508295Y1501739D01*
X509095Y1501872D01*
X509895Y1501739D01*
X510595Y1501205D01*
X511195Y1500405D01*
X511595Y1499472D01*
X511795Y1498405D01*
Y1497339D01*
X511595Y1496272D01*
X511195Y1495339D01*
X510595Y1494539D01*
X509895Y1494005D01*
X509095Y1493872D01*
G01X523895Y1501872D02*
X526295D01*
G01X525095D02*
Y1493872D01*
G01X523895D02*
X526295D01*
G01X533095Y1501872D02*
Y1493872D01*
G01X530795Y1501872D02*
X535395D01*
G01X538995Y1494938D02*
X539795Y1494272D01*
X540695Y1493872D01*
X541495D01*
X542295Y1494272D01*
X542895Y1494938D01*
X543195Y1495872D01*
X542995Y1496805D01*
X542495Y1497605D01*
X541595Y1498139D01*
X540395Y1498405D01*
X539695Y1498939D01*
X539395Y1499872D01*
X539595Y1500805D01*
X540095Y1501472D01*
X540795Y1501872D01*
X541495D01*
X542195Y1501605D01*
X542795Y1500939D01*
G01X555895Y1501872D02*
X558295D01*
G01X557095D02*
Y1493872D01*
G01X555895D02*
X558295D01*
G01X562495D02*
Y1501872D01*
X565095Y1495205D01*
X567695Y1501872D01*
Y1493872D01*
G01X571095D02*
Y1501872D01*
X573495D01*
X574295Y1501472D01*
X574895Y1500539D01*
X575095Y1499472D01*
X574895Y1498405D01*
X574395Y1497605D01*
X573495Y1497205D01*
X571095D01*
G01X579095Y1501872D02*
Y1493872D01*
X583095D01*
G01X591095D02*
X587095D01*
Y1501872D01*
X591095D01*
G01X589495Y1498005D02*
X587095D01*
G01X594495Y1493872D02*
Y1501872D01*
X597095Y1495205D01*
X599695Y1501872D01*
Y1493872D01*
G01X607095D02*
X603095D01*
Y1501872D01*
X607095D01*
G01X605495Y1498005D02*
X603095D01*
G01X610795Y1493872D02*
Y1501872D01*
X615395Y1493872D01*
Y1501872D01*
G01X621095D02*
Y1493872D01*
G01X618795Y1501872D02*
X623395D01*
G01X626595Y1493872D02*
X629095Y1501872D01*
X631595Y1493872D01*
G01X630695Y1496672D02*
X627495D01*
G01X637095Y1501872D02*
Y1493872D01*
G01X634795Y1501872D02*
X639395D01*
G01X643895D02*
X646295D01*
G01X645095D02*
Y1493872D01*
G01X643895D02*
X646295D01*
G01X653095D02*
X652295Y1494005D01*
X651595Y1494539D01*
X650995Y1495339D01*
X650595Y1496272D01*
X650395Y1497339D01*
Y1498405D01*
X650595Y1499472D01*
X650995Y1500405D01*
X651595Y1501205D01*
X652295Y1501739D01*
X653095Y1501872D01*
X653895Y1501739D01*
X654595Y1501205D01*
X655195Y1500405D01*
X655595Y1499472D01*
X655795Y1498405D01*
Y1497339D01*
X655595Y1496272D01*
X655195Y1495339D01*
X654595Y1494539D01*
X653895Y1494005D01*
X653095Y1493872D01*
G01X658795D02*
Y1501872D01*
X663395Y1493872D01*
Y1501872D01*
G01X669095Y1493605D02*
X668895Y1493739D01*
Y1494005D01*
X669095Y1494139D01*
X669295Y1494005D01*
Y1493739D01*
X669095Y1493605D01*
G01X10995Y1524938D02*
X11795Y1524272D01*
X12695Y1523872D01*
X13495D01*
X14295Y1524272D01*
X14895Y1524938D01*
X15195Y1525872D01*
X14995Y1526805D01*
X14495Y1527605D01*
X13595Y1528139D01*
X12395Y1528405D01*
X11695Y1528939D01*
X11395Y1529872D01*
X11595Y1530805D01*
X12095Y1531472D01*
X12795Y1531872D01*
X13495D01*
X14195Y1531605D01*
X14795Y1530939D01*
G01X19095Y1523872D02*
Y1531872D01*
X21495D01*
X22295Y1531472D01*
X22895Y1530539D01*
X23095Y1529472D01*
X22895Y1528405D01*
X22395Y1527605D01*
X21495Y1527205D01*
X19095D01*
G01X26595Y1523872D02*
X29095Y1531872D01*
X31595Y1523872D01*
G01X30695Y1526672D02*
X27495D01*
G01X39295Y1531205D02*
X38695Y1531605D01*
X37995Y1531872D01*
X37195D01*
X36295Y1531472D01*
X35595Y1530805D01*
X35095Y1530005D01*
X34695Y1528672D01*
X34595Y1527472D01*
X34795Y1526272D01*
X35095Y1525472D01*
X35695Y1524672D01*
X36395Y1524139D01*
X37095Y1523872D01*
X37795D01*
X38495Y1524139D01*
X39095Y1524539D01*
X39595Y1525072D01*
G01X43895Y1531872D02*
X46295D01*
G01X45095D02*
Y1523872D01*
G01X43895D02*
X46295D01*
G01X50795D02*
Y1531872D01*
X55395Y1523872D01*
Y1531872D01*
G01X61695Y1527872D02*
X63695D01*
Y1525472D01*
X63095Y1524672D01*
X62395Y1524139D01*
X61395Y1523872D01*
X60395Y1524139D01*
X59695Y1524672D01*
X59095Y1525472D01*
X58695Y1526405D01*
X58495Y1527472D01*
Y1528405D01*
X58695Y1529205D01*
X59095Y1530139D01*
X59695Y1530939D01*
X60295Y1531472D01*
X61095Y1531872D01*
X61795D01*
X62595Y1531605D01*
X63195Y1531072D01*
G01X74595Y1523872D02*
X77095Y1531872D01*
X79595Y1523872D01*
G01X78695Y1526672D02*
X75495D01*
G01X82795Y1523872D02*
Y1531872D01*
X87395Y1523872D01*
Y1531872D01*
G01X90895Y1523872D02*
Y1531872D01*
X92895D01*
X93695Y1531472D01*
X94295Y1530939D01*
X94795Y1530139D01*
X95195Y1529205D01*
X95295Y1527872D01*
X95195Y1526539D01*
X94795Y1525605D01*
X94295Y1524805D01*
X93695Y1524272D01*
X92895Y1523872D01*
X90895D01*
G01X106495D02*
Y1531872D01*
X109095Y1525205D01*
X111695Y1531872D01*
Y1523872D01*
G01X114595D02*
X117095Y1531872D01*
X119595Y1523872D01*
G01X118695Y1526672D02*
X115495D01*
G01X125095Y1531872D02*
Y1523872D01*
G01X122795Y1531872D02*
X127395D01*
G01X135095Y1523872D02*
X131095D01*
Y1531872D01*
X135095D01*
G01X133495Y1528005D02*
X131095D01*
G01X139095Y1523872D02*
Y1531872D01*
X141595D01*
X142395Y1531472D01*
X142895Y1530939D01*
X143095Y1529872D01*
X142895Y1528805D01*
X142295Y1528139D01*
X141595Y1527739D01*
X139095D01*
G01X141595D02*
X143095Y1523872D01*
G01X147895Y1531872D02*
X150295D01*
G01X149095D02*
Y1523872D01*
G01X147895D02*
X150295D01*
G01X154595D02*
X157095Y1531872D01*
X159595Y1523872D01*
G01X158695Y1526672D02*
X155495D01*
G01X163095Y1531872D02*
Y1523872D01*
X167095D01*
G01X178895D02*
Y1531872D01*
X180895D01*
X181695Y1531472D01*
X182295Y1530939D01*
X182795Y1530139D01*
X183195Y1529205D01*
X183295Y1527872D01*
X183195Y1526539D01*
X182795Y1525605D01*
X182295Y1524805D01*
X181695Y1524272D01*
X180895Y1523872D01*
X178895D01*
G01X187895Y1531872D02*
X190295D01*
G01X189095D02*
Y1523872D01*
G01X187895D02*
X190295D01*
G01X199095D02*
X195095D01*
Y1531872D01*
X199095D01*
G01X197495Y1528005D02*
X195095D01*
G01X203095Y1531872D02*
Y1523872D01*
X207095D01*
G01X215095D02*
X211095D01*
Y1531872D01*
X215095D01*
G01X213495Y1528005D02*
X211095D01*
G01X223295Y1531205D02*
X222695Y1531605D01*
X221995Y1531872D01*
X221195D01*
X220295Y1531472D01*
X219595Y1530805D01*
X219095Y1530005D01*
X218695Y1528672D01*
X218595Y1527472D01*
X218795Y1526272D01*
X219095Y1525472D01*
X219695Y1524672D01*
X220395Y1524139D01*
X221095Y1523872D01*
X221795D01*
X222495Y1524139D01*
X223095Y1524539D01*
X223595Y1525072D01*
G01X229095Y1531872D02*
Y1523872D01*
G01X226795Y1531872D02*
X231395D01*
G01X235095Y1523872D02*
Y1531872D01*
X237595D01*
X238395Y1531472D01*
X238895Y1530939D01*
X239095Y1529872D01*
X238895Y1528805D01*
X238295Y1528139D01*
X237595Y1527739D01*
X235095D01*
G01X237595D02*
X239095Y1523872D01*
G01X243895Y1531872D02*
X246295D01*
G01X245095D02*
Y1523872D01*
G01X243895D02*
X246295D01*
G01X255295Y1531205D02*
X254695Y1531605D01*
X253995Y1531872D01*
X253195D01*
X252295Y1531472D01*
X251595Y1530805D01*
X251095Y1530005D01*
X250695Y1528672D01*
X250595Y1527472D01*
X250795Y1526272D01*
X251095Y1525472D01*
X251695Y1524672D01*
X252395Y1524139D01*
X253095Y1523872D01*
X253795D01*
X254495Y1524139D01*
X255095Y1524539D01*
X255595Y1525072D01*
G01X271295Y1531205D02*
X270695Y1531605D01*
X269995Y1531872D01*
X269195D01*
X268295Y1531472D01*
X267595Y1530805D01*
X267095Y1530005D01*
X266695Y1528672D01*
X266595Y1527472D01*
X266795Y1526272D01*
X267095Y1525472D01*
X267695Y1524672D01*
X268395Y1524139D01*
X269095Y1523872D01*
X269795D01*
X270495Y1524139D01*
X271095Y1524539D01*
X271595Y1525072D01*
G01X277095Y1523872D02*
X276295Y1524005D01*
X275595Y1524539D01*
X274995Y1525339D01*
X274595Y1526272D01*
X274395Y1527339D01*
Y1528405D01*
X274595Y1529472D01*
X274995Y1530405D01*
X275595Y1531205D01*
X276295Y1531739D01*
X277095Y1531872D01*
X277895Y1531739D01*
X278595Y1531205D01*
X279195Y1530405D01*
X279595Y1529472D01*
X279795Y1528405D01*
Y1527339D01*
X279595Y1526272D01*
X279195Y1525339D01*
X278595Y1524539D01*
X277895Y1524005D01*
X277095Y1523872D01*
G01X282795D02*
Y1531872D01*
X287395Y1523872D01*
Y1531872D01*
G01X290995Y1524938D02*
X291795Y1524272D01*
X292695Y1523872D01*
X293495D01*
X294295Y1524272D01*
X294895Y1524938D01*
X295195Y1525872D01*
X294995Y1526805D01*
X294495Y1527605D01*
X293595Y1528139D01*
X292395Y1528405D01*
X291695Y1528939D01*
X291395Y1529872D01*
X291595Y1530805D01*
X292095Y1531472D01*
X292795Y1531872D01*
X293495D01*
X294195Y1531605D01*
X294795Y1530939D01*
G01X301095Y1531872D02*
Y1523872D01*
G01X298795Y1531872D02*
X303395D01*
G01X306595Y1523872D02*
X309095Y1531872D01*
X311595Y1523872D01*
G01X310695Y1526672D02*
X307495D01*
G01X314795Y1523872D02*
Y1531872D01*
X319395Y1523872D01*
Y1531872D01*
G01X325095D02*
Y1523872D01*
G01X322795Y1531872D02*
X327395D01*
G01X341095D02*
Y1523872D01*
G01X338795Y1531872D02*
X343395D01*
G01X349095Y1523872D02*
X348295Y1524005D01*
X347595Y1524539D01*
X346995Y1525339D01*
X346595Y1526272D01*
X346395Y1527339D01*
Y1528405D01*
X346595Y1529472D01*
X346995Y1530405D01*
X347595Y1531205D01*
X348295Y1531739D01*
X349095Y1531872D01*
X349895Y1531739D01*
X350595Y1531205D01*
X351195Y1530405D01*
X351595Y1529472D01*
X351795Y1528405D01*
Y1527339D01*
X351595Y1526272D01*
X351195Y1525339D01*
X350595Y1524539D01*
X349895Y1524005D01*
X349095Y1523872D01*
G01X362595D02*
X365095Y1531872D01*
X367595Y1523872D01*
G01X366695Y1526672D02*
X363495D01*
G01X375295Y1531205D02*
X374695Y1531605D01*
X373995Y1531872D01*
X373195D01*
X372295Y1531472D01*
X371595Y1530805D01*
X371095Y1530005D01*
X370695Y1528672D01*
X370595Y1527472D01*
X370795Y1526272D01*
X371095Y1525472D01*
X371695Y1524672D01*
X372395Y1524139D01*
X373095Y1523872D01*
X373795D01*
X374495Y1524139D01*
X375095Y1524539D01*
X375595Y1525072D01*
G01X378995Y1523872D02*
Y1531872D01*
G01X383195D02*
Y1523872D01*
G01Y1527872D02*
X378995D01*
G01X387895Y1531872D02*
X390295D01*
G01X389095D02*
Y1523872D01*
G01X387895D02*
X390295D01*
G01X399095D02*
X395095D01*
Y1531872D01*
X399095D01*
G01X397495Y1528005D02*
X395095D01*
G01X402595Y1531872D02*
X405095Y1523872D01*
X407595Y1531872D01*
G01X415095Y1523872D02*
X411095D01*
Y1531872D01*
X415095D01*
G01X413495Y1528005D02*
X411095D01*
G01X427095Y1523872D02*
Y1531872D01*
X429595D01*
X430395Y1531472D01*
X430895Y1530939D01*
X431095Y1529872D01*
X430895Y1528805D01*
X430295Y1528139D01*
X429595Y1527739D01*
X427095D01*
G01X429595D02*
X431095Y1523872D01*
G01X439095D02*
X435095D01*
Y1531872D01*
X439095D01*
G01X437495Y1528005D02*
X435095D01*
G01X445095Y1523872D02*
X444295Y1524005D01*
X443595Y1524539D01*
X442995Y1525339D01*
X442595Y1526272D01*
X442395Y1527339D01*
Y1528405D01*
X442595Y1529472D01*
X442995Y1530405D01*
X443595Y1531205D01*
X444295Y1531739D01*
X445095Y1531872D01*
X445895Y1531739D01*
X446595Y1531205D01*
X447195Y1530405D01*
X447595Y1529472D01*
X447795Y1528405D01*
Y1527339D01*
X447595Y1526272D01*
X447195Y1525339D01*
X446595Y1524539D01*
X445895Y1524005D01*
X445095Y1523872D01*
G01X445895Y1526005D02*
X447095Y1523872D01*
G01X450895Y1531872D02*
Y1526139D01*
X451295Y1524938D01*
X452095Y1524139D01*
X453095Y1523872D01*
X454095Y1524139D01*
X454895Y1524938D01*
X455295Y1526139D01*
Y1531872D01*
G01X459895D02*
X462295D01*
G01X461095D02*
Y1523872D01*
G01X459895D02*
X462295D01*
G01X467095D02*
Y1531872D01*
X469595D01*
X470395Y1531472D01*
X470895Y1530939D01*
X471095Y1529872D01*
X470895Y1528805D01*
X470295Y1528139D01*
X469595Y1527739D01*
X467095D01*
G01X469595D02*
X471095Y1523872D01*
G01X479095D02*
X475095D01*
Y1531872D01*
X479095D01*
G01X477495Y1528005D02*
X475095D01*
G01X482895Y1523872D02*
Y1531872D01*
X484895D01*
X485695Y1531472D01*
X486295Y1530939D01*
X486795Y1530139D01*
X487195Y1529205D01*
X487295Y1527872D01*
X487195Y1526539D01*
X486795Y1525605D01*
X486295Y1524805D01*
X485695Y1524272D01*
X484895Y1523872D01*
X482895D01*
G01X11895Y1516872D02*
X14295D01*
G01X13095D02*
Y1508872D01*
G01X11895D02*
X14295D01*
G01X18495D02*
Y1516872D01*
X21095Y1510205D01*
X23695Y1516872D01*
Y1508872D01*
G01X27095D02*
Y1516872D01*
X29495D01*
X30295Y1516472D01*
X30895Y1515539D01*
X31095Y1514472D01*
X30895Y1513405D01*
X30395Y1512605D01*
X29495Y1512205D01*
X27095D01*
G01X39095Y1508872D02*
X35095D01*
Y1516872D01*
X39095D01*
G01X37495Y1513005D02*
X35095D01*
G01X42895Y1508872D02*
Y1516872D01*
X44895D01*
X45695Y1516472D01*
X46295Y1515939D01*
X46795Y1515139D01*
X47195Y1514205D01*
X47295Y1512872D01*
X47195Y1511539D01*
X46795Y1510605D01*
X46295Y1509805D01*
X45695Y1509272D01*
X44895Y1508872D01*
X42895D01*
G01X50595D02*
X53095Y1516872D01*
X55595Y1508872D01*
G01X54695Y1511672D02*
X51495D01*
G01X58795Y1508872D02*
Y1516872D01*
X63395Y1508872D01*
Y1516872D01*
G01X71295Y1516205D02*
X70695Y1516605D01*
X69995Y1516872D01*
X69195D01*
X68295Y1516472D01*
X67595Y1515805D01*
X67095Y1515005D01*
X66695Y1513672D01*
X66595Y1512472D01*
X66795Y1511272D01*
X67095Y1510472D01*
X67695Y1509672D01*
X68395Y1509139D01*
X69095Y1508872D01*
X69795D01*
X70495Y1509139D01*
X71095Y1509539D01*
X71595Y1510072D01*
G01X79095Y1508872D02*
X75095D01*
Y1516872D01*
X79095D01*
G01X77495Y1513005D02*
X75095D01*
G01X82995Y1509938D02*
X83795Y1509272D01*
X84695Y1508872D01*
X85495D01*
X86295Y1509272D01*
X86895Y1509938D01*
X87195Y1510872D01*
X86995Y1511805D01*
X86495Y1512605D01*
X85595Y1513139D01*
X84395Y1513405D01*
X83695Y1513939D01*
X83395Y1514872D01*
X83595Y1515805D01*
X84095Y1516472D01*
X84795Y1516872D01*
X85495D01*
X86195Y1516605D01*
X86795Y1515939D01*
G01X98595Y1508872D02*
X101095Y1516872D01*
X103595Y1508872D01*
G01X102695Y1511672D02*
X99495D01*
G01X106795Y1508872D02*
Y1516872D01*
X111395Y1508872D01*
Y1516872D01*
G01X114895Y1508872D02*
Y1516872D01*
X116895D01*
X117695Y1516472D01*
X118295Y1515939D01*
X118795Y1515139D01*
X119195Y1514205D01*
X119295Y1512872D01*
X119195Y1511539D01*
X118795Y1510605D01*
X118295Y1509805D01*
X117695Y1509272D01*
X116895Y1508872D01*
X114895D01*
G01X133895Y1513139D02*
X134295Y1513539D01*
X134595Y1514205D01*
X134795Y1515139D01*
X134595Y1515939D01*
X134195Y1516472D01*
X133495Y1516872D01*
X130795D01*
Y1508872D01*
X134095D01*
X134795Y1509405D01*
X135195Y1510205D01*
X135395Y1511139D01*
X135195Y1512072D01*
X134595Y1512872D01*
X133895Y1513139D01*
X130795D01*
G01X141095Y1508872D02*
X140295Y1509005D01*
X139595Y1509539D01*
X138995Y1510339D01*
X138595Y1511272D01*
X138395Y1512339D01*
Y1513405D01*
X138595Y1514472D01*
X138995Y1515405D01*
X139595Y1516205D01*
X140295Y1516739D01*
X141095Y1516872D01*
X141895Y1516739D01*
X142595Y1516205D01*
X143195Y1515405D01*
X143595Y1514472D01*
X143795Y1513405D01*
Y1512339D01*
X143595Y1511272D01*
X143195Y1510339D01*
X142595Y1509539D01*
X141895Y1509005D01*
X141095Y1508872D01*
G01X146595D02*
X149095Y1516872D01*
X151595Y1508872D01*
G01X150695Y1511672D02*
X147495D01*
G01X155095Y1508872D02*
Y1516872D01*
X157595D01*
X158395Y1516472D01*
X158895Y1515939D01*
X159095Y1514872D01*
X158895Y1513805D01*
X158295Y1513139D01*
X157595Y1512739D01*
X155095D01*
G01X157595D02*
X159095Y1508872D01*
G01X162895D02*
Y1516872D01*
X164895D01*
X165695Y1516472D01*
X166295Y1515939D01*
X166795Y1515139D01*
X167195Y1514205D01*
X167295Y1512872D01*
X167195Y1511539D01*
X166795Y1510605D01*
X166295Y1509805D01*
X165695Y1509272D01*
X164895Y1508872D01*
X162895D01*
G01X181095Y1516872D02*
Y1508872D01*
G01X178795Y1516872D02*
X183395D01*
G01X186995Y1508872D02*
Y1516872D01*
G01X191195D02*
Y1508872D01*
G01Y1512872D02*
X186995D01*
G01X195895Y1516872D02*
X198295D01*
G01X197095D02*
Y1508872D01*
G01X195895D02*
X198295D01*
G01X207295Y1516205D02*
X206695Y1516605D01*
X205995Y1516872D01*
X205195D01*
X204295Y1516472D01*
X203595Y1515805D01*
X203095Y1515005D01*
X202695Y1513672D01*
X202595Y1512472D01*
X202795Y1511272D01*
X203095Y1510472D01*
X203695Y1509672D01*
X204395Y1509139D01*
X205095Y1508872D01*
X205795D01*
X206495Y1509139D01*
X207095Y1509539D01*
X207595Y1510072D01*
G01X210895Y1508872D02*
Y1516872D01*
G01X214695D02*
X210895Y1511938D01*
G01X215295Y1508872D02*
X212595Y1514205D01*
G01X218795Y1508872D02*
Y1516872D01*
X223395Y1508872D01*
Y1516872D01*
G01X231095Y1508872D02*
X227095D01*
Y1516872D01*
X231095D01*
G01X229495Y1513005D02*
X227095D01*
G01X234995Y1509938D02*
X235795Y1509272D01*
X236695Y1508872D01*
X237495D01*
X238295Y1509272D01*
X238895Y1509938D01*
X239195Y1510872D01*
X238995Y1511805D01*
X238495Y1512605D01*
X237595Y1513139D01*
X236395Y1513405D01*
X235695Y1513939D01*
X235395Y1514872D01*
X235595Y1515805D01*
X236095Y1516472D01*
X236795Y1516872D01*
X237495D01*
X238195Y1516605D01*
X238795Y1515939D01*
G01X242995Y1509938D02*
X243795Y1509272D01*
X244695Y1508872D01*
X245495D01*
X246295Y1509272D01*
X246895Y1509938D01*
X247195Y1510872D01*
X246995Y1511805D01*
X246495Y1512605D01*
X245595Y1513139D01*
X244395Y1513405D01*
X243695Y1513939D01*
X243395Y1514872D01*
X243595Y1515805D01*
X244095Y1516472D01*
X244795Y1516872D01*
X245495D01*
X246195Y1516605D01*
X246795Y1515939D01*
G01X253095Y1508605D02*
X252895Y1508739D01*
Y1509005D01*
X253095Y1509139D01*
X253295Y1509005D01*
Y1508739D01*
X253095Y1508605D01*
G01X15295Y1546205D02*
X14695Y1546605D01*
X13995Y1546872D01*
X13195D01*
X12295Y1546472D01*
X11595Y1545805D01*
X11095Y1545005D01*
X10695Y1543672D01*
X10595Y1542472D01*
X10795Y1541272D01*
X11095Y1540472D01*
X11695Y1539672D01*
X12395Y1539139D01*
X13095Y1538872D01*
X13795D01*
X14495Y1539139D01*
X15095Y1539539D01*
X15595Y1540072D01*
G01X18995Y1538872D02*
Y1546872D01*
G01X23195D02*
Y1538872D01*
G01Y1542872D02*
X18995D01*
G01X26595Y1538872D02*
X29095Y1546872D01*
X31595Y1538872D01*
G01X30695Y1541672D02*
X27495D01*
G01X35095Y1538872D02*
Y1546872D01*
X37595D01*
X38395Y1546472D01*
X38895Y1545939D01*
X39095Y1544872D01*
X38895Y1543805D01*
X38295Y1543139D01*
X37595Y1542739D01*
X35095D01*
G01X37595D02*
X39095Y1538872D01*
G01X45095Y1546872D02*
Y1538872D01*
G01X42795Y1546872D02*
X47395D01*
G01X53095Y1538605D02*
X52895Y1538739D01*
Y1539005D01*
X53095Y1539139D01*
X53295Y1539005D01*
Y1538739D01*
X53095Y1538605D01*
G01X66495Y1538872D02*
Y1546872D01*
X69095Y1540205D01*
X71695Y1546872D01*
Y1538872D01*
G01X74595D02*
X77095Y1546872D01*
X79595Y1538872D01*
G01X78695Y1541672D02*
X75495D01*
G01X82795Y1538872D02*
Y1546872D01*
X87395Y1538872D01*
Y1546872D01*
G01X90895D02*
Y1541139D01*
X91295Y1539938D01*
X92095Y1539139D01*
X93095Y1538872D01*
X94095Y1539139D01*
X94895Y1539938D01*
X95295Y1541139D01*
Y1546872D01*
G01X99195Y1538872D02*
Y1546872D01*
X102995D01*
G01X101595Y1543005D02*
X99195D01*
G01X106595Y1538872D02*
X109095Y1546872D01*
X111595Y1538872D01*
G01X110695Y1541672D02*
X107495D01*
G01X119295Y1546205D02*
X118695Y1546605D01*
X117995Y1546872D01*
X117195D01*
X116295Y1546472D01*
X115595Y1545805D01*
X115095Y1545005D01*
X114695Y1543672D01*
X114595Y1542472D01*
X114795Y1541272D01*
X115095Y1540472D01*
X115695Y1539672D01*
X116395Y1539139D01*
X117095Y1538872D01*
X117795D01*
X118495Y1539139D01*
X119095Y1539539D01*
X119595Y1540072D01*
G01X125095Y1546872D02*
Y1538872D01*
G01X122795Y1546872D02*
X127395D01*
G01X130895D02*
Y1541139D01*
X131295Y1539938D01*
X132095Y1539139D01*
X133095Y1538872D01*
X134095Y1539139D01*
X134895Y1539938D01*
X135295Y1541139D01*
Y1546872D01*
G01X139095Y1538872D02*
Y1546872D01*
X141595D01*
X142395Y1546472D01*
X142895Y1545939D01*
X143095Y1544872D01*
X142895Y1543805D01*
X142295Y1543139D01*
X141595Y1542739D01*
X139095D01*
G01X141595D02*
X143095Y1538872D01*
G01X151095D02*
X147095D01*
Y1546872D01*
X151095D01*
G01X149495Y1543005D02*
X147095D01*
G01X155095Y1538872D02*
Y1546872D01*
X157595D01*
X158395Y1546472D01*
X158895Y1545939D01*
X159095Y1544872D01*
X158895Y1543805D01*
X158295Y1543139D01*
X157595Y1542739D01*
X155095D01*
G01X157595D02*
X159095Y1538872D01*
G01X171895Y1546872D02*
X174295D01*
G01X173095D02*
Y1538872D01*
G01X171895D02*
X174295D01*
G01X178995Y1539938D02*
X179795Y1539272D01*
X180695Y1538872D01*
X181495D01*
X182295Y1539272D01*
X182895Y1539938D01*
X183195Y1540872D01*
X182995Y1541805D01*
X182495Y1542605D01*
X181595Y1543139D01*
X180395Y1543405D01*
X179695Y1543939D01*
X179395Y1544872D01*
X179595Y1545805D01*
X180095Y1546472D01*
X180795Y1546872D01*
X181495D01*
X182195Y1546605D01*
X182795Y1545939D01*
G01X195195Y1538872D02*
Y1546872D01*
X198995D01*
G01X197595Y1543005D02*
X195195D01*
G01X203095Y1538872D02*
Y1546872D01*
X205595D01*
X206395Y1546472D01*
X206895Y1545939D01*
X207095Y1544872D01*
X206895Y1543805D01*
X206295Y1543139D01*
X205595Y1542739D01*
X203095D01*
G01X205595D02*
X207095Y1538872D01*
G01X215095D02*
X211095D01*
Y1546872D01*
X215095D01*
G01X213495Y1543005D02*
X211095D01*
G01X223095Y1538872D02*
X219095D01*
Y1546872D01*
X223095D01*
G01X221495Y1543005D02*
X219095D01*
G01X237095Y1546872D02*
Y1538872D01*
G01X234795Y1546872D02*
X239395D01*
G01X245095Y1538872D02*
X244295Y1539005D01*
X243595Y1539539D01*
X242995Y1540339D01*
X242595Y1541272D01*
X242395Y1542339D01*
Y1543405D01*
X242595Y1544472D01*
X242995Y1545405D01*
X243595Y1546205D01*
X244295Y1546739D01*
X245095Y1546872D01*
X245895Y1546739D01*
X246595Y1546205D01*
X247195Y1545405D01*
X247595Y1544472D01*
X247795Y1543405D01*
Y1542339D01*
X247595Y1541272D01*
X247195Y1540339D01*
X246595Y1539539D01*
X245895Y1539005D01*
X245095Y1538872D01*
G01X258595D02*
X261095Y1546872D01*
X263595Y1538872D01*
G01X262695Y1541672D02*
X259495D01*
G01X266895Y1538872D02*
Y1546872D01*
X268895D01*
X269695Y1546472D01*
X270295Y1545939D01*
X270795Y1545139D01*
X271195Y1544205D01*
X271295Y1542872D01*
X271195Y1541539D01*
X270795Y1540605D01*
X270295Y1539805D01*
X269695Y1539272D01*
X268895Y1538872D01*
X266895D01*
G01X275095Y1540472D02*
X275595Y1539672D01*
X276195Y1539139D01*
X276895Y1538872D01*
X277695Y1539139D01*
X278295Y1539672D01*
X278895Y1540472D01*
X279095Y1541539D01*
Y1546872D01*
G01X282895D02*
Y1541139D01*
X283295Y1539938D01*
X284095Y1539139D01*
X285095Y1538872D01*
X286095Y1539139D01*
X286895Y1539938D01*
X287295Y1541139D01*
Y1546872D01*
G01X290995Y1539938D02*
X291795Y1539272D01*
X292695Y1538872D01*
X293495D01*
X294295Y1539272D01*
X294895Y1539938D01*
X295195Y1540872D01*
X294995Y1541805D01*
X294495Y1542605D01*
X293595Y1543139D01*
X292395Y1543405D01*
X291695Y1543939D01*
X291395Y1544872D01*
X291595Y1545805D01*
X292095Y1546472D01*
X292795Y1546872D01*
X293495D01*
X294195Y1546605D01*
X294795Y1545939D01*
G01X301095Y1546872D02*
Y1538872D01*
G01X298795Y1546872D02*
X303395D01*
G01X317095D02*
Y1538872D01*
G01X314795Y1546872D02*
X319395D01*
G01X323095Y1538872D02*
Y1546872D01*
X325595D01*
X326395Y1546472D01*
X326895Y1545939D01*
X327095Y1544872D01*
X326895Y1543805D01*
X326295Y1543139D01*
X325595Y1542739D01*
X323095D01*
G01X325595D02*
X327095Y1538872D01*
G01X330595D02*
X333095Y1546872D01*
X335595Y1538872D01*
G01X334695Y1541672D02*
X331495D01*
G01X343295Y1546205D02*
X342695Y1546605D01*
X341995Y1546872D01*
X341195D01*
X340295Y1546472D01*
X339595Y1545805D01*
X339095Y1545005D01*
X338695Y1543672D01*
X338595Y1542472D01*
X338795Y1541272D01*
X339095Y1540472D01*
X339695Y1539672D01*
X340395Y1539139D01*
X341095Y1538872D01*
X341795D01*
X342495Y1539139D01*
X343095Y1539539D01*
X343595Y1540072D01*
G01X351095Y1538872D02*
X347095D01*
Y1546872D01*
X351095D01*
G01X349495Y1543005D02*
X347095D01*
G01X362095Y1546872D02*
X363495Y1538872D01*
X365095Y1546872D01*
X366695Y1538872D01*
X368095Y1546872D01*
G01X371895D02*
X374295D01*
G01X373095D02*
Y1538872D01*
G01X371895D02*
X374295D01*
G01X378895D02*
Y1546872D01*
X380895D01*
X381695Y1546472D01*
X382295Y1545939D01*
X382795Y1545139D01*
X383195Y1544205D01*
X383295Y1542872D01*
X383195Y1541539D01*
X382795Y1540605D01*
X382295Y1539805D01*
X381695Y1539272D01*
X380895Y1538872D01*
X378895D01*
G01X389095Y1546872D02*
Y1538872D01*
G01X386795Y1546872D02*
X391395D01*
G01X394995Y1538872D02*
Y1546872D01*
G01X399195D02*
Y1538872D01*
G01Y1542872D02*
X394995D01*
G01X402995Y1539938D02*
X403795Y1539272D01*
X404695Y1538872D01*
X405495D01*
X406295Y1539272D01*
X406895Y1539938D01*
X407195Y1540872D01*
X406995Y1541805D01*
X406495Y1542605D01*
X405595Y1543139D01*
X404395Y1543405D01*
X403695Y1543939D01*
X403395Y1544872D01*
X403595Y1545805D01*
X404095Y1546472D01*
X404795Y1546872D01*
X405495D01*
X406195Y1546605D01*
X406795Y1545939D01*
G01X412895Y1537405D02*
X413295Y1539139D01*
G01X434895Y1538872D02*
Y1546872D01*
X436895D01*
X437695Y1546472D01*
X438295Y1545939D01*
X438795Y1545139D01*
X439195Y1544205D01*
X439295Y1542872D01*
X439195Y1541539D01*
X438795Y1540605D01*
X438295Y1539805D01*
X437695Y1539272D01*
X436895Y1538872D01*
X434895D01*
G01X443895Y1546872D02*
X446295D01*
G01X445095D02*
Y1538872D01*
G01X443895D02*
X446295D01*
G01X455095D02*
X451095D01*
Y1546872D01*
X455095D01*
G01X453495Y1543005D02*
X451095D01*
G01X459095Y1546872D02*
Y1538872D01*
X463095D01*
G01X471095D02*
X467095D01*
Y1546872D01*
X471095D01*
G01X469495Y1543005D02*
X467095D01*
G01X479295Y1546205D02*
X478695Y1546605D01*
X477995Y1546872D01*
X477195D01*
X476295Y1546472D01*
X475595Y1545805D01*
X475095Y1545005D01*
X474695Y1543672D01*
X474595Y1542472D01*
X474795Y1541272D01*
X475095Y1540472D01*
X475695Y1539672D01*
X476395Y1539139D01*
X477095Y1538872D01*
X477795D01*
X478495Y1539139D01*
X479095Y1539539D01*
X479595Y1540072D01*
G01X485095Y1546872D02*
Y1538872D01*
G01X482795Y1546872D02*
X487395D01*
G01X491095Y1538872D02*
Y1546872D01*
X493595D01*
X494395Y1546472D01*
X494895Y1545939D01*
X495095Y1544872D01*
X494895Y1543805D01*
X494295Y1543139D01*
X493595Y1542739D01*
X491095D01*
G01X493595D02*
X495095Y1538872D01*
G01X499895Y1546872D02*
X502295D01*
G01X501095D02*
Y1538872D01*
G01X499895D02*
X502295D01*
G01X511295Y1546205D02*
X510695Y1546605D01*
X509995Y1546872D01*
X509195D01*
X508295Y1546472D01*
X507595Y1545805D01*
X507095Y1545005D01*
X506695Y1543672D01*
X506595Y1542472D01*
X506795Y1541272D01*
X507095Y1540472D01*
X507695Y1539672D01*
X508395Y1539139D01*
X509095Y1538872D01*
X509795D01*
X510495Y1539139D01*
X511095Y1539539D01*
X511595Y1540072D01*
G01X73850Y-102250D02*
Y-106900D01*
X61350D01*
Y-102250D01*
G01X73850Y-46450D02*
Y-41800D01*
X61350D01*
Y-46450D01*
G01X60630Y107520D02*
G02Y91929I0J-7796D01*
G02Y107520I0J7796D01*
G01Y91929D02*
G02Y107520I0J7796D01*
G02Y91929I0J-7796D01*
G01Y490000D02*
G02Y474409I0J-7796D01*
G02Y490000I0J7796D01*
G01Y474409D02*
G02Y490000I0J7796D01*
G02Y474409I0J-7796D01*
G01Y492205D02*
Y615500D01*
X37595Y675175D01*
G01X36284Y1152379D02*
Y1205529D01*
G01X82795Y107520D02*
G02Y91929I0J-7796D01*
G02Y107520I0J7796D01*
G01Y91929D02*
G02Y107520I0J7796D01*
G02Y91929I0J-7796D01*
G01Y490000D02*
G02Y474409I0J-7796D01*
G02Y490000I0J7796D01*
G01Y474409D02*
G02Y490000I0J7796D01*
G02Y474409I0J-7796D01*
G01Y492205D02*
Y615500D01*
X70100D01*
Y672375D01*
G01X88850Y686400D02*
Y681750D01*
X76350D01*
Y686400D01*
G01X88850Y754600D02*
Y759250D01*
X76350D01*
Y754600D01*
G01X120929Y1000805D02*
X89433D01*
G01D02*
X130772D01*
G01X81559Y1070687D02*
G03I-2953J0D01*
G01Y1090372D02*
G03I-2953J0D01*
G01X75654Y1132694D02*
X650457D01*
G01X75654Y1148442D02*
Y1132694D01*
G01Y1152379D02*
X650457D01*
G01Y1148442D02*
X75654D01*
G01Y1168128D02*
Y1152379D01*
G01X650457Y1168128D02*
X75654D01*
G01Y1172065D02*
Y1242931D01*
G01Y1235057D02*
X370929D01*
G01X119097Y41376D02*
X120100Y-34500D01*
G01X118111Y53150D02*
G02Y41338I0J-5906D01*
G01D02*
X106300D01*
G01X120689Y34396D02*
X119097Y41376D01*
X117690Y34357D01*
X120689Y34396D01*
G01X106300Y53150D02*
X118111D01*
G01X108858Y107520D02*
G02Y91929I0J-7796D01*
G02Y107520I0J7796D01*
G01Y91929D02*
G02Y107520I0J7796D01*
G02Y91929I0J-7796D01*
G01Y490000D02*
G02Y474409I0J-7796D01*
G02Y490000I0J7796D01*
G01Y474409D02*
G02Y490000I0J7796D01*
G02Y474409I0J-7796D01*
G01Y492205D02*
Y630500D01*
X120100D01*
Y668975D01*
G01X118111Y541339D02*
G02Y529527I0J-5906D01*
G01X106300Y541339D02*
X118111D01*
G01Y529527D02*
X106300D01*
G01X126612Y537795D02*
X122782Y531747D01*
X128754Y535695D01*
X126612Y537795D01*
G01X122782Y531747D02*
X195100Y605500D01*
G01X118111Y545433D02*
Y610500D01*
X170100D01*
Y668975D01*
G01X113285Y982047D02*
X114215Y981005D01*
X115300Y980380D01*
X116695Y980172D01*
X118090Y980589D01*
X119175Y981422D01*
X119950Y982880D01*
X120105Y984547D01*
X119795Y986214D01*
X119020Y987255D01*
X117935Y988089D01*
X116850Y988297D01*
X115765Y988089D01*
X114370Y987255D01*
X114835Y992672D01*
X119020D01*
G01X125065Y980172D02*
Y992672D01*
X129095Y982255D01*
X133125Y992672D01*
Y980172D01*
G01X137465D02*
Y992672D01*
X141495Y982255D01*
X145525Y992672D01*
Y980172D01*
G01X120929Y1063185D02*
Y992931D01*
G01Y1070687D02*
G03I-2952J0D01*
G01X101244D02*
G03I-2953J0D01*
G01X120929Y1090372D02*
G03I-2952J0D01*
G01X101244D02*
G03I-2953J0D01*
G01X138850Y686550D02*
Y681900D01*
X126350D01*
Y686550D01*
G01X138850Y754750D02*
Y759400D01*
X126350D01*
Y754750D01*
G01X172110Y973246D02*
X140614D01*
G01D02*
X181953D01*
G01X140614Y1063535D02*
Y992931D01*
G01Y1000805D02*
X172110D01*
G01D02*
X130772D01*
G01X140614Y1073639D02*
X146520D01*
G01Y1067734D02*
X140614D01*
G01X146520Y1073639D02*
Y1067734D01*
G01X140614D02*
Y1073639D01*
G01Y1093324D02*
X146520D01*
G01Y1087419D02*
X140614D01*
G01X146520Y1093324D02*
Y1087419D01*
G01X140614D02*
Y1093324D01*
G01X178819Y281339D02*
G02Y273071I0J-4134D01*
G02Y281339I0J4134D01*
G01Y273071D02*
G03Y281339I0J4134D01*
G03Y273071I0J-4134D01*
G01X188850Y705150D02*
Y700500D01*
X176350D01*
Y705150D01*
G01X188850Y736150D02*
Y740800D01*
X176350D01*
Y736150D01*
G01X166285Y950647D02*
X167215Y949605D01*
X168300Y948980D01*
X169695Y948772D01*
X171090Y949189D01*
X172175Y950022D01*
X172950Y951480D01*
X173105Y953147D01*
X172795Y954814D01*
X172020Y955855D01*
X170935Y956689D01*
X169850Y956897D01*
X168765Y956689D01*
X167370Y955855D01*
X167835Y961272D01*
X172020D01*
G01X178065Y948772D02*
Y961272D01*
X182095Y950855D01*
X186125Y961272D01*
Y948772D01*
G01X190465D02*
Y961272D01*
X194495Y950855D01*
X198525Y961272D01*
Y948772D01*
G01X223291Y973246D02*
X181953D01*
G01X172110Y1063797D02*
Y965372D01*
G01X191795Y1024947D02*
X160299D01*
G01D02*
X194748D01*
G01X166205Y1073639D02*
X172110D01*
G01Y1067734D02*
X166205D01*
G01X172110Y1073639D02*
Y1067734D01*
G01X166205D02*
Y1073639D01*
G01Y1093324D02*
X172110D01*
G01Y1087419D02*
X166205D01*
G01X172110Y1093324D02*
Y1087419D01*
G01X166205D02*
Y1093324D01*
G01X199093Y-769672D02*
Y-844672D01*
G01Y-819672D02*
X302093D01*
Y-794672D01*
G01X199093D02*
X302093D01*
G01X193819Y281339D02*
G02Y273071I0J-4134D01*
G02Y281339I0J4134D01*
G01Y273071D02*
G03Y281339I0J4134D01*
G03Y273071I0J-4134D01*
G01Y480354D02*
G02Y474055I0J-3149D01*
G02Y480354I0J3149D01*
G01Y474055D02*
G03Y480354I0J3149D01*
G03Y474055I0J-3149D01*
G01X191795Y1063797D02*
Y965372D01*
G01Y973246D02*
X223291D01*
G01X197701Y1063112D02*
Y1017073D01*
G01X191795Y1059613D02*
Y1017073D01*
G01X197701Y1024947D02*
X264227D01*
G01D02*
X194748D01*
G01X191795Y1073639D02*
X197701D01*
G01Y1067734D02*
X191795D01*
G01X197701Y1073639D02*
Y1067734D01*
G01X191795D02*
Y1073639D01*
G01Y1093324D02*
X197701D01*
G01Y1087419D02*
X191795D01*
G01X197701Y1093324D02*
Y1087419D01*
G01X191795D02*
Y1093324D01*
G01X201638Y1087419D02*
X321368D01*
G01X201638Y1093324D02*
X321368D01*
G01X325401Y172944D02*
X220029D01*
X216046Y168961D01*
G01X223819Y480354D02*
G02Y474055I0J-3149D01*
G02Y480354I0J3149D01*
G01Y474055D02*
G03Y480354I0J3149D01*
G03Y474055I0J-3149D01*
G01X221710Y1027900D02*
Y1040400D01*
X219850Y1037900D01*
G01Y1027900D02*
X223570D01*
G01X234110Y1027483D02*
X233800Y1027692D01*
Y1028108D01*
X234110Y1028317D01*
X234420Y1028108D01*
Y1027692D01*
X234110Y1027483D01*
G01X243100Y1029775D02*
X244030Y1028733D01*
X245115Y1028108D01*
X246510Y1027900D01*
X247905Y1028317D01*
X248990Y1029150D01*
X249765Y1030608D01*
X249920Y1032275D01*
X249610Y1033942D01*
X248835Y1034983D01*
X247750Y1035817D01*
X246665Y1036025D01*
X245580Y1035817D01*
X244185Y1034983D01*
X244650Y1040400D01*
X248835D01*
G01X254880Y1027900D02*
Y1040400D01*
X258910Y1029983D01*
X262940Y1040400D01*
Y1027900D01*
G01X267280D02*
Y1040400D01*
X271310Y1029983D01*
X275340Y1040400D01*
Y1027900D01*
G01X268002Y-108950D02*
Y-113600D01*
X255502D01*
Y-108950D01*
G01X249252Y119685D02*
Y-23475D01*
G01X268002Y-40750D02*
Y-36100D01*
X255502D01*
Y-40750D01*
G01X268819Y281339D02*
G02Y273071I0J-4134D01*
G02Y281339I0J4134D01*
G01X253819D02*
G02Y273071I0J-4134D01*
G02Y281339I0J4134D01*
G01X268819Y273071D02*
G03Y281339I0J4134D01*
G03Y273071I0J-4134D01*
G01X253819D02*
G03Y281339I0J4134D01*
G03Y273071I0J-4134D01*
G01Y480354D02*
G02Y474055I0J-3149D01*
G02Y480354I0J3149D01*
G01Y474055D02*
G03Y480354I0J3149D01*
G03Y474055I0J-3149D01*
G01X250995Y1644938D02*
X251795Y1644272D01*
X252695Y1643872D01*
X253495D01*
X254295Y1644272D01*
X254895Y1644938D01*
X255195Y1645872D01*
X254995Y1646805D01*
X254495Y1647605D01*
X253595Y1648139D01*
X252395Y1648405D01*
X251695Y1648939D01*
X251395Y1649872D01*
X251595Y1650805D01*
X252095Y1651472D01*
X252795Y1651872D01*
X253495D01*
X254195Y1651605D01*
X254795Y1650939D01*
G01X261095Y1643872D02*
X260295Y1644005D01*
X259595Y1644539D01*
X258995Y1645339D01*
X258595Y1646272D01*
X258395Y1647339D01*
Y1648405D01*
X258595Y1649472D01*
X258995Y1650405D01*
X259595Y1651205D01*
X260295Y1651739D01*
X261095Y1651872D01*
X261895Y1651739D01*
X262595Y1651205D01*
X263195Y1650405D01*
X263595Y1649472D01*
X263795Y1648405D01*
Y1647339D01*
X263595Y1646272D01*
X263195Y1645339D01*
X262595Y1644539D01*
X261895Y1644005D01*
X261095Y1643872D01*
G01X267095Y1651872D02*
Y1643872D01*
X271095D01*
G01X274895D02*
Y1651872D01*
X276895D01*
X277695Y1651472D01*
X278295Y1650939D01*
X278795Y1650139D01*
X279195Y1649205D01*
X279295Y1647872D01*
X279195Y1646539D01*
X278795Y1645605D01*
X278295Y1644805D01*
X277695Y1644272D01*
X276895Y1643872D01*
X274895D01*
G01X287095D02*
X283095D01*
Y1651872D01*
X287095D01*
G01X285495Y1648005D02*
X283095D01*
G01X291095Y1643872D02*
Y1651872D01*
X293595D01*
X294395Y1651472D01*
X294895Y1650939D01*
X295095Y1649872D01*
X294895Y1648805D01*
X294295Y1648139D01*
X293595Y1647739D01*
X291095D01*
G01X293595D02*
X295095Y1643872D01*
G01X298495D02*
Y1651872D01*
X301095Y1645205D01*
X303695Y1651872D01*
Y1643872D01*
G01X306595D02*
X309095Y1651872D01*
X311595Y1643872D01*
G01X310695Y1646672D02*
X307495D01*
G01X314995Y1644938D02*
X315795Y1644272D01*
X316695Y1643872D01*
X317495D01*
X318295Y1644272D01*
X318895Y1644938D01*
X319195Y1645872D01*
X318995Y1646805D01*
X318495Y1647605D01*
X317595Y1648139D01*
X316395Y1648405D01*
X315695Y1648939D01*
X315395Y1649872D01*
X315595Y1650805D01*
X316095Y1651472D01*
X316795Y1651872D01*
X317495D01*
X318195Y1651605D01*
X318795Y1650939D01*
G01X322895Y1643872D02*
Y1651872D01*
G01X326695D02*
X322895Y1646938D01*
G01X327295Y1643872D02*
X324595Y1649205D01*
G01X341095Y1643872D02*
X340295Y1644005D01*
X339595Y1644539D01*
X338995Y1645339D01*
X338595Y1646272D01*
X338395Y1647339D01*
Y1648405D01*
X338595Y1649472D01*
X338995Y1650405D01*
X339595Y1651205D01*
X340295Y1651739D01*
X341095Y1651872D01*
X341895Y1651739D01*
X342595Y1651205D01*
X343195Y1650405D01*
X343595Y1649472D01*
X343795Y1648405D01*
Y1647339D01*
X343595Y1646272D01*
X343195Y1645339D01*
X342595Y1644539D01*
X341895Y1644005D01*
X341095Y1643872D01*
G01X347095D02*
Y1651872D01*
X349495D01*
X350295Y1651472D01*
X350895Y1650539D01*
X351095Y1649472D01*
X350895Y1648405D01*
X350395Y1647605D01*
X349495Y1647205D01*
X347095D01*
G01X359095Y1643872D02*
X355095D01*
Y1651872D01*
X359095D01*
G01X357495Y1648005D02*
X355095D01*
G01X362795Y1643872D02*
Y1651872D01*
X367395Y1643872D01*
Y1651872D01*
G01X381095Y1643872D02*
X380295Y1644005D01*
X379595Y1644539D01*
X378995Y1645339D01*
X378595Y1646272D01*
X378395Y1647339D01*
Y1648405D01*
X378595Y1649472D01*
X378995Y1650405D01*
X379595Y1651205D01*
X380295Y1651739D01*
X381095Y1651872D01*
X381895Y1651739D01*
X382595Y1651205D01*
X383195Y1650405D01*
X383595Y1649472D01*
X383795Y1648405D01*
Y1647339D01*
X383595Y1646272D01*
X383195Y1645339D01*
X382595Y1644539D01*
X381895Y1644005D01*
X381095Y1643872D01*
G01X386795D02*
Y1651872D01*
X391395Y1643872D01*
Y1651872D01*
G01X405895Y1648139D02*
X406295Y1648539D01*
X406595Y1649205D01*
X406795Y1650139D01*
X406595Y1650939D01*
X406195Y1651472D01*
X405495Y1651872D01*
X402795D01*
Y1643872D01*
X406095D01*
X406795Y1644405D01*
X407195Y1645205D01*
X407395Y1646139D01*
X407195Y1647072D01*
X406595Y1647872D01*
X405895Y1648139D01*
X402795D01*
G01X413095Y1643872D02*
X412295Y1644005D01*
X411595Y1644539D01*
X410995Y1645339D01*
X410595Y1646272D01*
X410395Y1647339D01*
Y1648405D01*
X410595Y1649472D01*
X410995Y1650405D01*
X411595Y1651205D01*
X412295Y1651739D01*
X413095Y1651872D01*
X413895Y1651739D01*
X414595Y1651205D01*
X415195Y1650405D01*
X415595Y1649472D01*
X415795Y1648405D01*
Y1647339D01*
X415595Y1646272D01*
X415195Y1645339D01*
X414595Y1644539D01*
X413895Y1644005D01*
X413095Y1643872D01*
G01X421095Y1651872D02*
Y1643872D01*
G01X418795Y1651872D02*
X423395D01*
G01X426995Y1643872D02*
Y1651872D01*
G01X431195D02*
Y1643872D01*
G01Y1647872D02*
X426995D01*
G01X442995Y1644938D02*
X443795Y1644272D01*
X444695Y1643872D01*
X445495D01*
X446295Y1644272D01*
X446895Y1644938D01*
X447195Y1645872D01*
X446995Y1646805D01*
X446495Y1647605D01*
X445595Y1648139D01*
X444395Y1648405D01*
X443695Y1648939D01*
X443395Y1649872D01*
X443595Y1650805D01*
X444095Y1651472D01*
X444795Y1651872D01*
X445495D01*
X446195Y1651605D01*
X446795Y1650939D01*
G01X451895Y1651872D02*
X454295D01*
G01X453095D02*
Y1643872D01*
G01X451895D02*
X454295D01*
G01X458895D02*
Y1651872D01*
X460895D01*
X461695Y1651472D01*
X462295Y1650939D01*
X462795Y1650139D01*
X463195Y1649205D01*
X463295Y1647872D01*
X463195Y1646539D01*
X462795Y1645605D01*
X462295Y1644805D01*
X461695Y1644272D01*
X460895Y1643872D01*
X458895D01*
G01X471095D02*
X467095D01*
Y1651872D01*
X471095D01*
G01X469495Y1648005D02*
X467095D01*
G01X477095Y1643605D02*
X476895Y1643739D01*
Y1644005D01*
X477095Y1644139D01*
X477295Y1644005D01*
Y1643739D01*
X477095Y1643605D01*
G01X293452Y162985D02*
Y126385D01*
X485052D01*
Y162985D01*
X293452D01*
G01X304636Y978611D02*
X292136D01*
X294636Y976751D01*
G01X304636D02*
Y980471D01*
G01X305053Y991011D02*
X304844Y990701D01*
X304428D01*
X304219Y991011D01*
X304428Y991321D01*
X304844D01*
X305053Y991011D01*
G01X302761Y1000001D02*
X303803Y1000931D01*
X304428Y1002016D01*
X304636Y1003411D01*
X304219Y1004806D01*
X303386Y1005891D01*
X301928Y1006666D01*
X300261Y1006821D01*
X298594Y1006511D01*
X297553Y1005736D01*
X296719Y1004651D01*
X296511Y1003566D01*
X296719Y1002481D01*
X297553Y1001086D01*
X292136Y1001551D01*
Y1005736D01*
G01X304636Y1011781D02*
X292136D01*
X302553Y1015811D01*
X292136Y1019841D01*
X304636D01*
G01Y1024181D02*
X292136D01*
X302553Y1028211D01*
X292136Y1032241D01*
X304636D01*
G01X309600Y-829672D02*
Y-824672D01*
X310866D01*
X311373Y-824922D01*
X311753Y-825255D01*
X312070Y-825755D01*
X312323Y-826339D01*
X312386Y-827172D01*
X312323Y-828005D01*
X312070Y-828589D01*
X311753Y-829089D01*
X311373Y-829422D01*
X310866Y-829672D01*
X309600D01*
G01X314510D02*
X316093Y-824672D01*
X317676Y-829672D01*
G01X317106Y-827922D02*
X315080D01*
G01X321193Y-824672D02*
Y-829672D01*
G01X319736Y-824672D02*
X322650D01*
G01X327560Y-829672D02*
X325026D01*
Y-824672D01*
X327560D01*
G01X326546Y-827089D02*
X325026D01*
G01X331393Y-829839D02*
X331266Y-829755D01*
Y-829589D01*
X331393Y-829505D01*
X331520Y-829589D01*
Y-829755D01*
X331393Y-829839D01*
G01Y-827589D02*
X331266Y-827505D01*
Y-827339D01*
X331393Y-827255D01*
X331520Y-827339D01*
Y-827505D01*
X331393Y-827589D01*
G01X304093Y-769672D02*
Y-844672D01*
G01X302093Y-769672D02*
Y-844672D01*
G01X304093Y-819672D02*
X504093D01*
G01X309726Y-804672D02*
Y-799672D01*
X311246D01*
X311753Y-799922D01*
X312133Y-800505D01*
X312260Y-801172D01*
X312133Y-801839D01*
X311816Y-802339D01*
X311246Y-802589D01*
X309726D01*
G01X314953Y-804839D02*
X317233Y-799672D01*
G01X319736Y-804672D02*
Y-799672D01*
X322650Y-804672D01*
Y-799672D01*
G01X326293Y-804839D02*
X326166Y-804755D01*
Y-804589D01*
X326293Y-804505D01*
X326420Y-804589D01*
Y-804755D01*
X326293Y-804839D01*
G01Y-802589D02*
X326166Y-802505D01*
Y-802339D01*
X326293Y-802255D01*
X326420Y-802339D01*
Y-802505D01*
X326293Y-802589D01*
G01X304093Y-794672D02*
X504093D01*
G01X309726Y-779672D02*
Y-774672D01*
X311246D01*
X311753Y-774922D01*
X312133Y-775505D01*
X312260Y-776172D01*
X312133Y-776839D01*
X311816Y-777339D01*
X311246Y-777589D01*
X309726D01*
G01X314826Y-779672D02*
Y-774672D01*
X316410D01*
X316916Y-774922D01*
X317233Y-775255D01*
X317360Y-775922D01*
X317233Y-776589D01*
X316853Y-777005D01*
X316410Y-777255D01*
X314826D01*
G01X316410D02*
X317360Y-779672D01*
G01X321193D02*
X320686Y-779589D01*
X320243Y-779255D01*
X319863Y-778755D01*
X319610Y-778172D01*
X319483Y-777505D01*
Y-776839D01*
X319610Y-776172D01*
X319863Y-775589D01*
X320243Y-775089D01*
X320686Y-774755D01*
X321193Y-774672D01*
X321700Y-774755D01*
X322143Y-775089D01*
X322523Y-775589D01*
X322776Y-776172D01*
X322903Y-776839D01*
Y-777505D01*
X322776Y-778172D01*
X322523Y-778755D01*
X322143Y-779255D01*
X321700Y-779589D01*
X321193Y-779672D01*
G01X325026Y-778672D02*
X325343Y-779172D01*
X325723Y-779505D01*
X326166Y-779672D01*
X326673Y-779505D01*
X327053Y-779172D01*
X327433Y-778672D01*
X327560Y-778005D01*
Y-774672D01*
G01X332660Y-779672D02*
X330126D01*
Y-774672D01*
X332660D01*
G01X331646Y-777089D02*
X330126D01*
G01X337886Y-775089D02*
X337506Y-774839D01*
X337063Y-774672D01*
X336556D01*
X335986Y-774922D01*
X335543Y-775339D01*
X335226Y-775839D01*
X334973Y-776672D01*
X334910Y-777422D01*
X335036Y-778172D01*
X335226Y-778672D01*
X335606Y-779172D01*
X336050Y-779505D01*
X336493Y-779672D01*
X336936D01*
X337380Y-779505D01*
X337760Y-779255D01*
X338076Y-778922D01*
G01X341593Y-774672D02*
Y-779672D01*
G01X340136Y-774672D02*
X343050D01*
G01X346693Y-779839D02*
X346566Y-779755D01*
Y-779589D01*
X346693Y-779505D01*
X346820Y-779589D01*
Y-779755D01*
X346693Y-779839D01*
G01Y-777589D02*
X346566Y-777505D01*
Y-777339D01*
X346693Y-777255D01*
X346820Y-777339D01*
Y-777505D01*
X346693Y-777589D01*
G01X330814Y163272D02*
X330314Y165572D01*
X329014Y164872D01*
X330814Y163272D01*
X325401Y172944D01*
G01X313494Y1087419D02*
Y991600D01*
G01D02*
Y1090372D01*
G01Y1093324D02*
Y1124820D01*
G01D02*
Y1090372D01*
G01X321329Y1238009D02*
Y1250509D01*
X319469Y1248009D01*
G01Y1238009D02*
X323189D01*
G01X333729Y1250509D02*
X332489Y1250092D01*
X331559Y1249051D01*
X330939Y1247801D01*
X330474Y1246134D01*
X330319Y1244259D01*
X330474Y1242384D01*
X330939Y1240717D01*
X331559Y1239467D01*
X332489Y1238426D01*
X333729Y1238009D01*
X334969Y1238426D01*
X335899Y1239467D01*
X336519Y1240717D01*
X336984Y1242384D01*
X337139Y1244259D01*
X336984Y1246134D01*
X336519Y1247801D01*
X335899Y1249051D01*
X334969Y1250092D01*
X333729Y1250509D01*
G01X346129D02*
X344889Y1250092D01*
X343959Y1249051D01*
X343339Y1247801D01*
X342874Y1246134D01*
X342719Y1244259D01*
X342874Y1242384D01*
X343339Y1240717D01*
X343959Y1239467D01*
X344889Y1238426D01*
X346129Y1238009D01*
X347369Y1238426D01*
X348299Y1239467D01*
X348919Y1240717D01*
X349384Y1242384D01*
X349539Y1244259D01*
X349384Y1246134D01*
X348919Y1247801D01*
X348299Y1249051D01*
X347369Y1250092D01*
X346129Y1250509D01*
G01X356514Y1242176D02*
X360544D01*
G01X370929Y1238009D02*
Y1250509D01*
X369069Y1248009D01*
G01Y1238009D02*
X372789D01*
G01X379919Y1239884D02*
X380849Y1238842D01*
X381934Y1238217D01*
X383329Y1238009D01*
X384724Y1238426D01*
X385809Y1239259D01*
X386584Y1240717D01*
X386739Y1242384D01*
X386429Y1244051D01*
X385654Y1245092D01*
X384569Y1245926D01*
X383484Y1246134D01*
X382399Y1245926D01*
X381004Y1245092D01*
X381469Y1250509D01*
X385654D01*
G01X395729D02*
X394489Y1250092D01*
X393559Y1249051D01*
X392939Y1247801D01*
X392474Y1246134D01*
X392319Y1244259D01*
X392474Y1242384D01*
X392939Y1240717D01*
X393559Y1239467D01*
X394489Y1238426D01*
X395729Y1238009D01*
X396969Y1238426D01*
X397899Y1239467D01*
X398519Y1240717D01*
X398984Y1242384D01*
X399139Y1244259D01*
X398984Y1246134D01*
X398519Y1247801D01*
X397899Y1249051D01*
X396969Y1250092D01*
X395729Y1250509D01*
G01X404099Y1238009D02*
Y1250509D01*
X408129Y1240092D01*
X412159Y1250509D01*
Y1238009D01*
G01X416499D02*
Y1250509D01*
X420529Y1240092D01*
X424559Y1250509D01*
Y1238009D01*
G01X351299Y281339D02*
G02Y273071I0J-4134D01*
G02Y281339I0J4134D01*
G01X336299D02*
G02Y273071I0J-4134D01*
G02Y281339I0J4134D01*
G01X351299Y273071D02*
G03Y281339I0J4134D01*
G03Y273071I0J-4134D01*
G01X336299D02*
G03Y281339I0J4134D01*
G03Y273071I0J-4134D01*
G01X351299Y480354D02*
G02Y474055I0J-3149D01*
G02Y480354I0J3149D01*
G01Y474055D02*
G03Y480354I0J3149D01*
G03Y474055I0J-3149D01*
G01X381299Y480354D02*
G02Y474055I0J-3149D01*
G02Y480354I0J3149D01*
G01Y474055D02*
G03Y480354I0J3149D01*
G03Y474055I0J-3149D01*
G01X374095Y1080672D02*
X376095D01*
Y1078272D01*
X375495Y1077472D01*
X374795Y1076939D01*
X373795Y1076672D01*
X372795Y1076939D01*
X372095Y1077472D01*
X371495Y1078272D01*
X371095Y1079205D01*
X370895Y1080272D01*
Y1081205D01*
X371095Y1082005D01*
X371495Y1082939D01*
X372095Y1083739D01*
X372695Y1084272D01*
X373495Y1084672D01*
X374195D01*
X374995Y1084405D01*
X375595Y1083872D01*
G01X379495Y1076672D02*
Y1084672D01*
X381995D01*
X382795Y1084272D01*
X383295Y1083739D01*
X383495Y1082672D01*
X383295Y1081605D01*
X382695Y1080939D01*
X381995Y1080539D01*
X379495D01*
G01X381995D02*
X383495Y1076672D01*
G01X389495D02*
X388695Y1076805D01*
X387995Y1077339D01*
X387395Y1078139D01*
X386995Y1079072D01*
X386795Y1080139D01*
Y1081205D01*
X386995Y1082272D01*
X387395Y1083205D01*
X387995Y1084005D01*
X388695Y1084539D01*
X389495Y1084672D01*
X390295Y1084539D01*
X390995Y1084005D01*
X391595Y1083205D01*
X391995Y1082272D01*
X392195Y1081205D01*
Y1080139D01*
X391995Y1079072D01*
X391595Y1078139D01*
X390995Y1077339D01*
X390295Y1076805D01*
X389495Y1076672D01*
G01X395295Y1084672D02*
Y1078939D01*
X395695Y1077738D01*
X396495Y1076939D01*
X397495Y1076672D01*
X398495Y1076939D01*
X399295Y1077738D01*
X399695Y1078939D01*
Y1084672D01*
G01X403495Y1076672D02*
Y1084672D01*
X405895D01*
X406695Y1084272D01*
X407295Y1083339D01*
X407495Y1082272D01*
X407295Y1081205D01*
X406795Y1080405D01*
X405895Y1080005D01*
X403495D01*
G01X411395Y1077738D02*
X412195Y1077072D01*
X413095Y1076672D01*
X413895D01*
X414695Y1077072D01*
X415295Y1077738D01*
X415595Y1078672D01*
X415395Y1079605D01*
X414895Y1080405D01*
X413995Y1080939D01*
X412795Y1081205D01*
X412095Y1081739D01*
X411795Y1082672D01*
X411995Y1083605D01*
X412495Y1084272D01*
X413195Y1084672D01*
X413895D01*
X414595Y1084405D01*
X415195Y1083739D01*
G01X430295Y1080939D02*
X430695Y1081339D01*
X430995Y1082005D01*
X431195Y1082939D01*
X430995Y1083739D01*
X430595Y1084272D01*
X429895Y1084672D01*
X427195D01*
Y1076672D01*
X430495D01*
X431195Y1077205D01*
X431595Y1078005D01*
X431795Y1078939D01*
X431595Y1079872D01*
X430995Y1080672D01*
X430295Y1080939D01*
X427195D01*
G01X666205Y1235057D02*
X370929D01*
G01X419093Y-819672D02*
Y-844672D01*
G01X425716Y57073D02*
X500000Y53150D01*
X511811D01*
G02Y41339I0J-5905D01*
G01X500000D01*
X425716Y37415D01*
G02Y57073I-519J9829D01*
G01D02*
G03Y37415I-519J-9829D01*
G01X500000Y41339D01*
X511811D01*
G03Y53150I0J5906D01*
G01X500000D01*
X425716Y57073D01*
G01Y37415D02*
G02Y57073I-520J9829D01*
G01X411299Y281339D02*
G02Y273071I0J-4134D01*
G02Y281339I0J4134D01*
G01Y273071D02*
G03Y281339I0J4134D01*
G03Y273071I0J-4134D01*
G01Y480354D02*
G02Y474055I0J-3149D01*
G02Y480354I0J3149D01*
G01Y474055D02*
G03Y480354I0J3149D01*
G03Y474055I0J-3149D01*
G01X421726Y-822172D02*
Y-827172D01*
X424260D01*
G01X427333Y-822172D02*
X428853D01*
G01X428093D02*
Y-827172D01*
G01X427333D02*
X428853D01*
G01X433700Y-824505D02*
X433953Y-824255D01*
X434143Y-823839D01*
X434270Y-823255D01*
X434143Y-822755D01*
X433890Y-822422D01*
X433446Y-822172D01*
X431736D01*
Y-827172D01*
X433826D01*
X434270Y-826839D01*
X434523Y-826339D01*
X434650Y-825755D01*
X434523Y-825172D01*
X434143Y-824672D01*
X433700Y-824505D01*
X431736D01*
G01X438293Y-827339D02*
X438166Y-827255D01*
Y-827089D01*
X438293Y-827005D01*
X438420Y-827089D01*
Y-827255D01*
X438293Y-827339D01*
G01Y-825089D02*
X438166Y-825005D01*
Y-824839D01*
X438293Y-824755D01*
X438420Y-824839D01*
Y-825005D01*
X438293Y-825089D01*
G01X500000Y41338D02*
X425716Y37415D01*
G01Y57073D02*
X500000Y53150D01*
G01X426299Y281339D02*
G02Y273071I0J-4134D01*
G02Y281339I0J4134D01*
G01Y273071D02*
G03Y281339I0J4134D01*
G03Y273071I0J-4134D01*
G01X470106Y-847839D02*
X470213Y-847714D01*
X470293Y-847505D01*
X470346Y-847214D01*
X470293Y-846964D01*
X470186Y-846797D01*
X470000Y-846672D01*
X469280D01*
Y-849172D01*
X470160D01*
X470346Y-849005D01*
X470453Y-848755D01*
X470506Y-848464D01*
X470453Y-848172D01*
X470293Y-847922D01*
X470106Y-847839D01*
X469280D01*
G01X472573Y-849172D02*
Y-847505D01*
G01Y-847797D02*
X472466Y-847630D01*
X472306Y-847547D01*
X472120Y-847505D01*
X471933Y-847589D01*
X471773Y-847755D01*
X471666Y-848005D01*
X471613Y-848339D01*
X471666Y-848672D01*
X471773Y-848922D01*
X471933Y-849089D01*
X472120Y-849172D01*
X472306Y-849130D01*
X472466Y-849005D01*
X472573Y-848839D01*
G01X473893Y-848880D02*
X474026Y-849047D01*
X474213Y-849172D01*
X474373D01*
X474533Y-849089D01*
X474640Y-848964D01*
X474693Y-848797D01*
X474666Y-848547D01*
X474560Y-848422D01*
X474080Y-848172D01*
X473973Y-847880D01*
X474026Y-847672D01*
X474133Y-847547D01*
X474293Y-847505D01*
X474453Y-847547D01*
X474613Y-847672D01*
G01X476093Y-848047D02*
X476946D01*
X476866Y-847755D01*
X476733Y-847589D01*
X476546Y-847505D01*
X476360Y-847547D01*
X476200Y-847672D01*
X476093Y-847964D01*
X476040Y-848214D01*
Y-848464D01*
X476093Y-848714D01*
X476226Y-848964D01*
X476386Y-849130D01*
X476573Y-849172D01*
X476760Y-849089D01*
X476946Y-848839D01*
G01X478213Y-849172D02*
Y-846672D01*
G01Y-847922D02*
X478346Y-847672D01*
X478506Y-847547D01*
X478666Y-847505D01*
X478906Y-847589D01*
X479066Y-847755D01*
X479173Y-848047D01*
Y-848380D01*
X479120Y-848714D01*
X479013Y-848964D01*
X478826Y-849130D01*
X478666Y-849172D01*
X478506Y-849130D01*
X478346Y-849005D01*
X478213Y-848797D01*
G01X480893Y-849172D02*
X480733Y-849130D01*
X480573Y-848964D01*
X480466Y-848672D01*
X480413Y-848339D01*
X480466Y-848005D01*
X480573Y-847714D01*
X480733Y-847547D01*
X480893Y-847505D01*
X481053Y-847547D01*
X481213Y-847714D01*
X481320Y-848005D01*
X481346Y-848339D01*
X481320Y-848672D01*
X481213Y-848964D01*
X481053Y-849130D01*
X480893Y-849172D01*
G01X483573D02*
Y-847505D01*
G01Y-847797D02*
X483466Y-847630D01*
X483306Y-847547D01*
X483120Y-847505D01*
X482933Y-847589D01*
X482773Y-847755D01*
X482666Y-848005D01*
X482613Y-848339D01*
X482666Y-848672D01*
X482773Y-848922D01*
X482933Y-849089D01*
X483120Y-849172D01*
X483306Y-849130D01*
X483466Y-849005D01*
X483573Y-848839D01*
G01X484920Y-849172D02*
Y-847505D01*
G01Y-847839D02*
X485053Y-847672D01*
X485186Y-847547D01*
X485373Y-847505D01*
X485506Y-847547D01*
X485666Y-847672D01*
G01X487973Y-846672D02*
Y-849172D01*
G01Y-848797D02*
X487866Y-849005D01*
X487706Y-849130D01*
X487520Y-849172D01*
X487306Y-849089D01*
X487146Y-848880D01*
X487040Y-848630D01*
X487013Y-848339D01*
X487040Y-848047D01*
X487146Y-847797D01*
X487306Y-847589D01*
X487520Y-847505D01*
X487706Y-847547D01*
X487840Y-847630D01*
X487973Y-847797D01*
G01X491360Y-849172D02*
Y-846672D01*
X492026D01*
X492240Y-846797D01*
X492373Y-846964D01*
X492426Y-847297D01*
X492373Y-847630D01*
X492213Y-847839D01*
X492026Y-847964D01*
X491360D01*
G01X492026D02*
X492426Y-849172D01*
G01X493693Y-848047D02*
X494546D01*
X494466Y-847755D01*
X494333Y-847589D01*
X494146Y-847505D01*
X493960Y-847547D01*
X493800Y-847672D01*
X493693Y-847964D01*
X493640Y-848214D01*
Y-848464D01*
X493693Y-848714D01*
X493826Y-848964D01*
X493986Y-849130D01*
X494173Y-849172D01*
X494360Y-849089D01*
X494546Y-848839D01*
G01X495813Y-847505D02*
X496293Y-849172D01*
X496773Y-847505D01*
G01X498493Y-849255D02*
X498440Y-849214D01*
Y-849130D01*
X498493Y-849089D01*
X498546Y-849130D01*
Y-849214D01*
X498493Y-849255D01*
G01X500693Y-849172D02*
X500880Y-849130D01*
X501093Y-849005D01*
X501226Y-848797D01*
X501280Y-848505D01*
X501226Y-848214D01*
X501066Y-847964D01*
X500826Y-847839D01*
X500560D01*
X500400Y-847755D01*
X500266Y-847547D01*
X500213Y-847255D01*
X500293Y-846964D01*
X500480Y-846755D01*
X500693Y-846672D01*
X500906Y-846755D01*
X501093Y-846964D01*
X501173Y-847255D01*
X501120Y-847547D01*
X500986Y-847755D01*
X500826Y-847839D01*
X500560D01*
X500320Y-847964D01*
X500160Y-848214D01*
X500106Y-848505D01*
X500160Y-848797D01*
X500293Y-849005D01*
X500506Y-849130D01*
X500693Y-849172D01*
G01X503106Y-847839D02*
X503213Y-847714D01*
X503293Y-847505D01*
X503346Y-847214D01*
X503293Y-846964D01*
X503186Y-846797D01*
X503000Y-846672D01*
X502280D01*
Y-849172D01*
X503160D01*
X503346Y-849005D01*
X503453Y-848755D01*
X503506Y-848464D01*
X503453Y-848172D01*
X503293Y-847922D01*
X503106Y-847839D01*
X502280D01*
G01X465993Y-822172D02*
Y-827172D01*
G01X464536Y-822172D02*
X467450D01*
G01X471093Y-827172D02*
X470713Y-827089D01*
X470333Y-826755D01*
X470080Y-826172D01*
X469953Y-825505D01*
X470080Y-824839D01*
X470333Y-824255D01*
X470713Y-823922D01*
X471093Y-823839D01*
X471473Y-823922D01*
X471853Y-824255D01*
X472106Y-824839D01*
X472170Y-825505D01*
X472106Y-826172D01*
X471853Y-826755D01*
X471473Y-827089D01*
X471093Y-827172D01*
G01X476193D02*
X475813Y-827089D01*
X475433Y-826755D01*
X475180Y-826172D01*
X475053Y-825505D01*
X475180Y-824839D01*
X475433Y-824255D01*
X475813Y-823922D01*
X476193Y-823839D01*
X476573Y-823922D01*
X476953Y-824255D01*
X477206Y-824839D01*
X477270Y-825505D01*
X477206Y-826172D01*
X476953Y-826755D01*
X476573Y-827089D01*
X476193Y-827172D01*
G01X481293D02*
Y-822172D01*
G01X486393Y-827339D02*
X486266Y-827255D01*
Y-827089D01*
X486393Y-827005D01*
X486520Y-827089D01*
Y-827255D01*
X486393Y-827339D01*
G01Y-825089D02*
X486266Y-825005D01*
Y-824839D01*
X486393Y-824755D01*
X486520Y-824839D01*
Y-825005D01*
X486393Y-825089D01*
G01X462093Y-819672D02*
Y-844672D01*
G01Y-794672D02*
Y-819672D01*
G01X464726Y-802172D02*
Y-797172D01*
X466310D01*
X466816Y-797422D01*
X467133Y-797755D01*
X467260Y-798422D01*
X467133Y-799089D01*
X466753Y-799505D01*
X466310Y-799755D01*
X464726D01*
G01X466310D02*
X467260Y-802172D01*
G01X472360D02*
X469826D01*
Y-797172D01*
X472360D01*
G01X471346Y-799589D02*
X469826D01*
G01X474610Y-797172D02*
X476193Y-802172D01*
X477776Y-797172D01*
G01X481293Y-802339D02*
X481166Y-802255D01*
Y-802089D01*
X481293Y-802005D01*
X481420Y-802089D01*
Y-802255D01*
X481293Y-802339D01*
G01Y-800089D02*
X481166Y-800005D01*
Y-799839D01*
X481293Y-799755D01*
X481420Y-799839D01*
Y-800005D01*
X481293Y-800089D01*
G01X515402Y51988D02*
X495100Y-29500D01*
G01X511811Y41338D02*
X500000D01*
G01Y53150D02*
X511811D01*
G01X508780Y281339D02*
G02Y273071I0J-4134D01*
G02Y281339I0J4134D01*
G01X493780D02*
G02Y273071I0J-4134D01*
G02Y281339I0J4134D01*
G01X508780Y273071D02*
G03Y281339I0J4134D01*
G03Y273071I0J-4134D01*
G01X493780D02*
G03Y281339I0J4134D01*
G03Y273071I0J-4134D01*
G01X508780Y480354D02*
G02Y474055I0J-3149D01*
G02Y480354I0J3149D01*
G01Y474055D02*
G03Y480354I0J3149D01*
G03Y474055I0J-3149D01*
G01X548002Y-115300D02*
Y-119950D01*
X535502D01*
Y-115300D01*
G01X529252Y119685D02*
Y-20675D01*
G01X548002Y-34700D02*
Y-30050D01*
X535502D01*
Y-34700D01*
G01X511811Y53150D02*
G02Y41338I0J-5906D01*
G01X515165Y44833D02*
X515402Y51988D01*
X512254Y45558D01*
X515165Y44833D01*
G01X538780Y480354D02*
G02Y474055I0J-3149D01*
G02Y480354I0J3149D01*
G01Y474055D02*
G03Y480354I0J3149D01*
G03Y474055I0J-3149D01*
G01X568780Y281339D02*
G02Y273071I0J-4134D01*
G02Y281339I0J4134D01*
G01Y273071D02*
G03Y281339I0J4134D01*
G03Y273071I0J-4134D01*
G01Y480354D02*
G02Y474055I0J-3149D01*
G02Y480354I0J3149D01*
G01Y474055D02*
G03Y480354I0J3149D01*
G03Y474055I0J-3149D01*
G01X576500Y61996D02*
X635555D01*
Y30500D01*
X576500D01*
Y61996D01*
G01X583780Y281339D02*
G02Y273071I0J-4134D01*
G02Y281339I0J4134D01*
G01Y273071D02*
G03Y281339I0J4134D01*
G03Y273071I0J-4134D01*
G01X659055Y617244D02*
X600000D01*
Y656614D01*
X659055D01*
Y617244D01*
G01X613555Y1213872D02*
Y1226372D01*
X607820Y1217414D01*
X615570D01*
G01X620065Y1213872D02*
Y1226372D01*
X624095Y1215955D01*
X628125Y1226372D01*
Y1213872D01*
G01X632465D02*
Y1226372D01*
X636495Y1215955D01*
X640525Y1226372D01*
Y1213872D01*
G01X650457Y1207498D02*
X618961D01*
G01D02*
X658331D01*
G01X651260Y281339D02*
G02Y273071I0J-4134D01*
G02Y281339I0J4134D01*
G01Y273071D02*
G03Y281339I0J4134D01*
G03Y273071I0J-4134D01*
G01X658217Y623794D02*
Y620694D01*
X657297D01*
X656990Y620849D01*
X656760Y621211D01*
X656683Y621624D01*
X656760Y622037D01*
X656952Y622347D01*
X657297Y622502D01*
X658217D01*
G01X653507Y620952D02*
X653737Y620797D01*
X654005Y620694D01*
X654312D01*
X654657Y620849D01*
X654925Y621107D01*
X655117Y621417D01*
X655270Y621934D01*
X655308Y622399D01*
X655232Y622864D01*
X655117Y623174D01*
X654887Y623484D01*
X654618Y623691D01*
X654350Y623794D01*
X654082D01*
X653813Y623691D01*
X653583Y623536D01*
X653392Y623329D01*
G01X650943Y622141D02*
X650790Y621986D01*
X650675Y621727D01*
X650598Y621366D01*
X650675Y621056D01*
X650828Y620849D01*
X651097Y620694D01*
X652132D01*
Y623794D01*
X650867D01*
X650598Y623587D01*
X650445Y623277D01*
X650368Y622916D01*
X650445Y622554D01*
X650675Y622244D01*
X650943Y622141D01*
X652132D01*
G01X646008Y620694D02*
X645050Y623794D01*
X644092Y620694D01*
G01X641183Y623794D02*
X642717D01*
Y620694D01*
X641183D01*
G01X641797Y622192D02*
X642717D01*
G01X639732Y623794D02*
Y620694D01*
X637968Y623794D01*
Y620694D01*
G01X636593Y623794D02*
Y620694D01*
X635827D01*
X635520Y620849D01*
X635290Y621056D01*
X635098Y621366D01*
X634945Y621727D01*
X634907Y622244D01*
X634945Y622761D01*
X635098Y623122D01*
X635290Y623432D01*
X635520Y623639D01*
X635827Y623794D01*
X636593D01*
G01X632650D02*
X632957Y623742D01*
X633225Y623536D01*
X633455Y623226D01*
X633608Y622864D01*
X633685Y622451D01*
Y622037D01*
X633608Y621624D01*
X633455Y621262D01*
X633225Y620952D01*
X632957Y620746D01*
X632650Y620694D01*
X632343Y620746D01*
X632075Y620952D01*
X631845Y621262D01*
X631692Y621624D01*
X631615Y622037D01*
Y622451D01*
X631692Y622864D01*
X631845Y623226D01*
X632075Y623536D01*
X632343Y623742D01*
X632650Y623794D01*
G01X630317D02*
Y620694D01*
X629358D01*
X629052Y620849D01*
X628860Y621056D01*
X628783Y621469D01*
X628860Y621882D01*
X629090Y622141D01*
X629358Y622296D01*
X630317D01*
G01X629358D02*
X628783Y623794D01*
G01X650917Y625694D02*
Y628794D01*
X649383D01*
G01X647050D02*
X647357Y628742D01*
X647625Y628536D01*
X647855Y628226D01*
X648008Y627864D01*
X648085Y627451D01*
Y627037D01*
X648008Y626624D01*
X647855Y626262D01*
X647625Y625952D01*
X647357Y625746D01*
X647050Y625694D01*
X646743Y625746D01*
X646475Y625952D01*
X646245Y626262D01*
X646092Y626624D01*
X646015Y627037D01*
Y627451D01*
X646092Y627864D01*
X646245Y628226D01*
X646475Y628536D01*
X646743Y628742D01*
X647050Y628794D01*
G01X643720Y627244D02*
X642953D01*
Y628174D01*
X643183Y628484D01*
X643452Y628691D01*
X643835Y628794D01*
X644218Y628691D01*
X644487Y628484D01*
X644717Y628174D01*
X644870Y627812D01*
X644947Y627399D01*
Y627037D01*
X644870Y626727D01*
X644717Y626366D01*
X644487Y626056D01*
X644257Y625849D01*
X643950Y625694D01*
X643682D01*
X643375Y625797D01*
X643145Y626004D01*
G01X640850Y628794D02*
X641157Y628742D01*
X641425Y628536D01*
X641655Y628226D01*
X641808Y627864D01*
X641885Y627451D01*
Y627037D01*
X641808Y626624D01*
X641655Y626262D01*
X641425Y625952D01*
X641157Y625746D01*
X640850Y625694D01*
X640543Y625746D01*
X640275Y625952D01*
X640045Y626262D01*
X639892Y626624D01*
X639815Y627037D01*
Y627451D01*
X639892Y627864D01*
X640045Y628226D01*
X640275Y628536D01*
X640543Y628742D01*
X640850Y628794D01*
G01X643550Y756750D02*
X638900D01*
Y769250D01*
X643550D01*
G01X650457Y1132694D02*
X666205Y1140568D01*
G01Y1160254D02*
X650457Y1168128D01*
G01X666205Y1140568D02*
X650457Y1148442D01*
G01Y1152379D02*
X666205Y1160254D01*
G01X650457Y1172065D02*
Y1215372D01*
G01X683809Y-115300D02*
Y-119950D01*
X671309D01*
Y-115300D01*
G01X665059Y139408D02*
Y-20675D01*
G01X683809Y-34700D02*
Y-30050D01*
X671309D01*
Y-34700D01*
G01X704418Y114398D02*
X702118Y113898D01*
X702818Y112598D01*
X704418Y114398D01*
X684770Y102949D01*
G01X675059Y149408D02*
X1383154D01*
G01X666260Y281339D02*
G02Y273071I0J-4134D01*
G02Y281339I0J4134D01*
G01Y273071D02*
G03Y281339I0J4134D01*
G03Y273071I0J-4134D01*
G01Y480354D02*
G02Y474055I0J-3149D01*
G02Y480354I0J3149D01*
G01Y474055D02*
G03Y480354I0J3149D01*
G03Y474055I0J-3149D01*
G01X682257Y1109265D02*
Y1152572D01*
G01X701638Y1152379D02*
X658331D01*
G01X701638Y1148442D02*
X658331D01*
G01X666205Y1164190D02*
Y1215372D01*
G01Y1164190D02*
Y1242931D01*
G01Y1207498D02*
X697701D01*
G01D02*
X658331D01*
G01X936959Y154008D02*
Y115108D01*
X708359D01*
Y154008D01*
X936959D01*
G01X696260Y480354D02*
G02Y474055I0J-3149D01*
G02Y480354I0J3149D01*
G01Y474055D02*
G03Y480354I0J3149D01*
G03Y474055I0J-3149D01*
G01X686950Y756750D02*
X691600D01*
Y769250D01*
X686950D01*
G01X706195Y1114672D02*
X693695D01*
X696195Y1112812D01*
G01X706195D02*
Y1116532D01*
G01Y1123042D02*
X693695D01*
X704112Y1127072D01*
X693695Y1131102D01*
X706195D01*
G01Y1135442D02*
X693695D01*
X704112Y1139472D01*
X693695Y1143502D01*
X706195D01*
G01X726195Y1150472D02*
X728195D01*
Y1148072D01*
X727595Y1147272D01*
X726895Y1146739D01*
X725895Y1146472D01*
X724895Y1146739D01*
X724195Y1147272D01*
X723595Y1148072D01*
X723195Y1149005D01*
X722995Y1150072D01*
Y1151005D01*
X723195Y1151805D01*
X723595Y1152739D01*
X724195Y1153539D01*
X724795Y1154072D01*
X725595Y1154472D01*
X726295D01*
X727095Y1154205D01*
X727695Y1153672D01*
G01X731595Y1146472D02*
Y1154472D01*
X734095D01*
X734895Y1154072D01*
X735395Y1153539D01*
X735595Y1152472D01*
X735395Y1151405D01*
X734795Y1150739D01*
X734095Y1150339D01*
X731595D01*
G01X734095D02*
X735595Y1146472D01*
G01X741595D02*
X740795Y1146605D01*
X740095Y1147139D01*
X739495Y1147939D01*
X739095Y1148872D01*
X738895Y1149939D01*
Y1151005D01*
X739095Y1152072D01*
X739495Y1153005D01*
X740095Y1153805D01*
X740795Y1154339D01*
X741595Y1154472D01*
X742395Y1154339D01*
X743095Y1153805D01*
X743695Y1153005D01*
X744095Y1152072D01*
X744295Y1151005D01*
Y1149939D01*
X744095Y1148872D01*
X743695Y1147939D01*
X743095Y1147139D01*
X742395Y1146605D01*
X741595Y1146472D01*
G01X747395Y1154472D02*
Y1148739D01*
X747795Y1147538D01*
X748595Y1146739D01*
X749595Y1146472D01*
X750595Y1146739D01*
X751395Y1147538D01*
X751795Y1148739D01*
Y1154472D01*
G01X755595Y1146472D02*
Y1154472D01*
X757995D01*
X758795Y1154072D01*
X759395Y1153139D01*
X759595Y1152072D01*
X759395Y1151005D01*
X758895Y1150205D01*
X757995Y1149805D01*
X755595D01*
G01X763495Y1147538D02*
X764295Y1146872D01*
X765195Y1146472D01*
X765995D01*
X766795Y1146872D01*
X767395Y1147538D01*
X767695Y1148472D01*
X767495Y1149405D01*
X766995Y1150205D01*
X766095Y1150739D01*
X764895Y1151005D01*
X764195Y1151539D01*
X763895Y1152472D01*
X764095Y1153405D01*
X764595Y1154072D01*
X765295Y1154472D01*
X765995D01*
X766695Y1154205D01*
X767295Y1153539D01*
G01X779095Y1146472D02*
X781595Y1154472D01*
X784095Y1146472D01*
G01X783195Y1149272D02*
X779995D01*
G01X741260Y281339D02*
G02Y273071I0J-4134D01*
G02Y281339I0J4134D01*
G01X726260D02*
G02Y273071I0J-4134D01*
G02Y281339I0J4134D01*
G01X741260Y273071D02*
G03Y281339I0J4134D01*
G03Y273071I0J-4134D01*
G01X726260D02*
G03Y281339I0J4134D01*
G03Y273071I0J-4134D01*
G01Y480354D02*
G02Y474055I0J-3149D01*
G02Y480354I0J3149D01*
G01Y474055D02*
G03Y480354I0J3149D01*
G03Y474055I0J-3149D01*
G01X722825Y775500D02*
X1291339D01*
G01X905512Y41339D02*
X893701D01*
X819417Y37415D01*
G02Y57073I-519J9829D01*
G01X893701Y53150D01*
X905512D01*
G02Y41339I0J-5905D01*
G01Y53150D02*
G02Y41339I0J-5905D01*
G01X893701D01*
X819417Y37415D01*
G02Y57073I-519J9829D01*
G01X893701Y53150D01*
X905512D01*
G01X819417Y37415D02*
G02Y57073I-520J9829D01*
G01X893701Y41338D02*
X819417Y37415D01*
G01Y57073D02*
X893701Y53150D01*
G01X905512Y41338D02*
X893701D01*
G01Y53150D02*
X905512D01*
G01X902488Y237782D02*
X976772Y233858D01*
X988583D01*
G02Y222047I0J-5905D01*
G01X976772D01*
X902488Y218124D01*
G02Y237782I-519J9829D01*
G01D02*
G03Y218124I-519J-9829D01*
G01X976772Y222047D01*
X988583D01*
G03Y233858I0J5906D01*
G01X976772D01*
X902488Y237782D01*
G01X902405Y218171D02*
G02Y237829I-520J9829D01*
G01X877510Y568620D02*
Y661175D01*
G01X896260Y675200D02*
Y670550D01*
X883760D01*
Y675200D01*
G01X896260Y755800D02*
Y760450D01*
X883760D01*
Y755800D01*
G01X907358Y41588D02*
X905100Y-29500D01*
G01X905512Y53150D02*
G02Y41338I0J-5906D01*
G01X908635Y34544D02*
X907358Y41588D01*
X905637Y34639D01*
X908635Y34544D01*
G01X915512Y47244D02*
X1389354D01*
G01X976689Y222094D02*
X902405Y218171D01*
G01Y237829D02*
X976689Y233906D01*
G01X944417Y552309D02*
X1018701Y548386D01*
X1030512D01*
G02Y536575I0J-5905D01*
G01X1018701D01*
X944417Y532651D01*
G02Y552309I-519J9829D01*
G01D02*
G03Y532651I-519J-9829D01*
G01X1018701Y536575D01*
X1030512D01*
G03Y548386I0J5905D01*
G01X1018701D01*
X944417Y552309D01*
G01X944405Y532671D02*
G02Y552329I-520J9829D01*
G01X1018689Y536594D02*
X944405Y532671D01*
G01Y552329D02*
X1018689Y548406D01*
G01X980059Y139408D02*
Y-20675D01*
G01X976689Y233906D02*
X988500D01*
G01Y222094D02*
X976689D01*
G01X985577Y233182D02*
X955100Y665500D01*
G01X998809Y-115300D02*
Y-119950D01*
X986309D01*
Y-115300D01*
G01X998809Y-34700D02*
Y-30050D01*
X986309D01*
Y-34700D01*
G01X988500Y233906D02*
G02Y222094I0J-5906D01*
G01Y238000D02*
Y661175D01*
G01X983589Y240059D02*
X985577Y233182D01*
X986581Y240270D01*
X983589Y240059D01*
G01X1007250Y675200D02*
Y670550D01*
X994750D01*
Y675200D01*
G01X1007250Y755800D02*
Y760450D01*
X994750D01*
Y755800D01*
G01X1030500Y548406D02*
G02Y536594I0J-5906D01*
G01D02*
X1018689D01*
G01X1040500Y542500D02*
X1380475D01*
G01X1030330Y543708D02*
X1030435Y536550D01*
X1033272Y543123D01*
X1030330Y543708D01*
G01X1030435Y536550D02*
X1055100Y660500D01*
G01X1018689Y548406D02*
X1030500D01*
G01Y552500D02*
Y657775D01*
G01X1049250Y675350D02*
Y670700D01*
X1036750D01*
Y675350D01*
G01X1049250Y755950D02*
Y760600D01*
X1036750D01*
Y755950D01*
G01X1198850Y-114650D02*
Y-119300D01*
X1186350D01*
Y-114650D01*
G01X1226024Y164429D02*
Y35500D01*
X1180100Y-19500D01*
G01X1198850Y-34050D02*
Y-29400D01*
X1186350D01*
Y-34050D01*
G01X1178028Y0D02*
X1539489D01*
G01X1226024Y182736D02*
G02Y166122I0J-8307D01*
G02Y182736I0J8307D01*
G01Y166122D02*
G03Y182736I0J8307D01*
G03Y166122I0J-8307D01*
G01Y407736D02*
G02Y391122I0J-8307D01*
G02Y407736I0J8307D01*
G01Y391122D02*
G03Y407736I0J8307D01*
G03Y391122I0J-8307D01*
G01X1203212Y578740D02*
X1539489D01*
G01X1232284Y-594488D02*
X1291339D01*
Y-633858D01*
X1232284D01*
Y-594488D01*
G01X1233222Y-602538D02*
Y-599438D01*
X1234142D01*
X1234449Y-599593D01*
X1234679Y-599955D01*
X1234756Y-600368D01*
X1234679Y-600781D01*
X1234487Y-601091D01*
X1234142Y-601246D01*
X1233222D01*
G01X1237932Y-599696D02*
X1237702Y-599541D01*
X1237434Y-599438D01*
X1237127D01*
X1236782Y-599593D01*
X1236514Y-599851D01*
X1236322Y-600161D01*
X1236169Y-600678D01*
X1236131Y-601143D01*
X1236207Y-601608D01*
X1236322Y-601918D01*
X1236552Y-602228D01*
X1236821Y-602435D01*
X1237089Y-602538D01*
X1237357D01*
X1237626Y-602435D01*
X1237856Y-602280D01*
X1238047Y-602073D01*
G01X1240496Y-600885D02*
X1240649Y-600730D01*
X1240764Y-600471D01*
X1240841Y-600110D01*
X1240764Y-599800D01*
X1240611Y-599593D01*
X1240342Y-599438D01*
X1239307D01*
Y-602538D01*
X1240572D01*
X1240841Y-602331D01*
X1240994Y-602021D01*
X1241071Y-601660D01*
X1240994Y-601298D01*
X1240764Y-600988D01*
X1240496Y-600885D01*
X1239307D01*
G01X1245431Y-599438D02*
X1246389Y-602538D01*
X1247347Y-599438D01*
G01X1250256Y-602538D02*
X1248722D01*
Y-599438D01*
X1250256D01*
G01X1249642Y-600936D02*
X1248722D01*
G01X1251707Y-602538D02*
Y-599438D01*
X1253471Y-602538D01*
Y-599438D01*
G01X1254846Y-602538D02*
Y-599438D01*
X1255612D01*
X1255919Y-599593D01*
X1256149Y-599800D01*
X1256341Y-600110D01*
X1256494Y-600471D01*
X1256532Y-600988D01*
X1256494Y-601505D01*
X1256341Y-601866D01*
X1256149Y-602176D01*
X1255919Y-602383D01*
X1255612Y-602538D01*
X1254846D01*
G01X1258789D02*
X1258482Y-602486D01*
X1258214Y-602280D01*
X1257984Y-601970D01*
X1257831Y-601608D01*
X1257754Y-601195D01*
Y-600781D01*
X1257831Y-600368D01*
X1257984Y-600006D01*
X1258214Y-599696D01*
X1258482Y-599490D01*
X1258789Y-599438D01*
X1259096Y-599490D01*
X1259364Y-599696D01*
X1259594Y-600006D01*
X1259747Y-600368D01*
X1259824Y-600781D01*
Y-601195D01*
X1259747Y-601608D01*
X1259594Y-601970D01*
X1259364Y-602280D01*
X1259096Y-602486D01*
X1258789Y-602538D01*
G01X1261122D02*
Y-599438D01*
X1262081D01*
X1262387Y-599593D01*
X1262579Y-599800D01*
X1262656Y-600213D01*
X1262579Y-600626D01*
X1262349Y-600885D01*
X1262081Y-601040D01*
X1261122D01*
G01X1262081D02*
X1262656Y-602538D01*
G01X1241622Y-604838D02*
Y-607938D01*
X1243156D01*
G01X1245489D02*
X1245182Y-607886D01*
X1244914Y-607680D01*
X1244684Y-607370D01*
X1244531Y-607008D01*
X1244454Y-606595D01*
Y-606181D01*
X1244531Y-605768D01*
X1244684Y-605406D01*
X1244914Y-605096D01*
X1245182Y-604890D01*
X1245489Y-604838D01*
X1245796Y-604890D01*
X1246064Y-605096D01*
X1246294Y-605406D01*
X1246447Y-605768D01*
X1246524Y-606181D01*
Y-606595D01*
X1246447Y-607008D01*
X1246294Y-607370D01*
X1246064Y-607680D01*
X1245796Y-607886D01*
X1245489Y-607938D01*
G01X1248819Y-606388D02*
X1249586D01*
Y-607318D01*
X1249356Y-607628D01*
X1249087Y-607835D01*
X1248704Y-607938D01*
X1248321Y-607835D01*
X1248052Y-607628D01*
X1247822Y-607318D01*
X1247669Y-606956D01*
X1247592Y-606543D01*
Y-606181D01*
X1247669Y-605871D01*
X1247822Y-605510D01*
X1248052Y-605200D01*
X1248282Y-604993D01*
X1248589Y-604838D01*
X1248857D01*
X1249164Y-604941D01*
X1249394Y-605148D01*
G01X1251689Y-607938D02*
X1251382Y-607886D01*
X1251114Y-607680D01*
X1250884Y-607370D01*
X1250731Y-607008D01*
X1250654Y-606595D01*
Y-606181D01*
X1250731Y-605768D01*
X1250884Y-605406D01*
X1251114Y-605096D01*
X1251382Y-604890D01*
X1251689Y-604838D01*
X1251996Y-604890D01*
X1252264Y-605096D01*
X1252494Y-605406D01*
X1252647Y-605768D01*
X1252724Y-606181D01*
Y-606595D01*
X1252647Y-607008D01*
X1252494Y-607370D01*
X1252264Y-607680D01*
X1251996Y-607886D01*
X1251689Y-607938D01*
G01X1258908Y-96550D02*
Y-101200D01*
X1246408D01*
Y-96550D01*
G01X1258908Y-53150D02*
Y-48500D01*
X1246408D01*
Y-53150D01*
G01X1240158Y47480D02*
Y-17275D01*
G01X1227559Y57480D02*
G02X1252756I12599J0D01*
G02X1227559I-12598J0D01*
G01X1252756D02*
G03X1227559I-12598J0D01*
G03X1252756I12599J0D01*
G01X1236024Y174429D02*
X1350100D01*
Y195500D01*
X1383575D01*
G01X1221324Y355929D02*
X1260124D01*
Y217529D01*
X1221324D01*
Y355929D01*
G01X1236024Y399429D02*
X1380354D01*
G01X1226024Y409429D02*
Y657775D01*
G01X1227559Y521260D02*
G02X1252756I12599J0D01*
G02X1227559I-12598J0D01*
G01X1252756D02*
G03X1227559I-12598J0D01*
G03X1252756I12599J0D01*
G01X1244774Y675350D02*
Y670700D01*
X1232274D01*
Y675350D01*
G01X1244774Y755950D02*
Y760600D01*
X1232274D01*
Y755950D01*
G01X1250158Y57480D02*
X1370100D01*
Y90500D01*
X1389775D01*
G01X1266051Y358907D02*
X1259541Y355929D01*
X1266700Y355978D01*
X1266051Y358907D01*
G01X1259541Y355929D02*
X1300500Y365000D01*
G01X1250158Y521260D02*
X1313946D01*
X1336907Y482457D01*
X1383154Y482807D01*
G01X1291339Y494679D02*
Y785500D01*
G01X1284339Y774000D02*
X1291339Y775500D01*
X1284339Y777000D01*
Y774000D01*
G01X1400729Y130658D02*
X1396079D01*
Y143158D01*
X1400729D01*
G01X1394379Y380679D02*
X1389729D01*
Y393179D01*
X1394379D01*
G01X1400729Y464447D02*
X1396079D01*
Y476947D01*
X1400729D01*
G01X1394500Y523750D02*
X1389850D01*
Y536250D01*
X1394500D01*
G01X1419329Y28494D02*
X1414679D01*
Y40994D01*
X1419329D01*
G01X1407350Y71750D02*
X1402700D01*
Y84250D01*
X1407350D01*
G01Y176750D02*
X1402700D01*
Y189250D01*
X1407350D01*
G01X1450329Y28494D02*
X1454979D01*
Y40994D01*
X1450329D01*
G01X1463150Y71750D02*
X1467800D01*
Y84250D01*
X1463150D01*
G01X1468929Y130658D02*
X1473579D01*
Y143158D01*
X1468929D01*
G01X1463150Y176750D02*
X1467800D01*
Y189250D01*
X1463150D01*
G01X1474979Y380679D02*
X1479629D01*
Y393179D01*
X1474979D01*
G01X1468929Y464447D02*
X1473579D01*
Y476947D01*
X1468929D01*
G01X1475100Y523750D02*
X1479750D01*
Y536250D01*
X1475100D01*
G01X1529489Y249461D02*
Y0D01*
G01X1527989Y7000D02*
X1529489Y0D01*
X1530989Y7000D01*
X1527989D01*
G01X1548239Y279436D02*
Y274786D01*
X1535739D01*
Y279436D01*
G01X1548239Y322836D02*
Y327486D01*
X1535739D01*
Y322836D01*
G01X1529489Y352511D02*
Y578740D01*
G01X1530989Y571740D02*
X1529489Y578740D01*
X1527989Y571740D01*
X1530989D01*
G01X1866176Y-111991D02*
Y681209D01*
X2563676D01*
Y-111991D01*
X1866176D01*
G01Y-74191D02*
X2563676D01*
G01X1866176Y-36391D02*
X2563676D01*
G01X1866176Y1409D02*
X2563676D01*
G01X1866176Y39209D02*
X2563676D01*
G01X1866176Y77009D02*
X2563676D01*
G01X1866176Y114809D02*
X2563676D01*
G01X1866176Y152609D02*
X2563676D01*
G01X1866176Y190409D02*
X2563676D01*
G01X1866176Y228209D02*
X2563676D01*
G01X1866176Y266009D02*
X2563676D01*
G01X1866176Y303809D02*
X2563676D01*
G01X1866176Y341609D02*
X2563676D01*
G01X1860579Y383207D02*
Y412835D01*
X3064955D01*
Y383207D01*
X1860579D01*
G01X1866176Y379409D02*
X2563676D01*
G01X1866176Y417209D02*
X2563676D01*
G01X1866176Y455009D02*
X2563676D01*
G01X1866176Y492809D02*
X2563676D01*
G01X1866176Y530609D02*
X2563676D01*
G01X1866176Y568409D02*
X2563676D01*
G01X1866176Y631209D02*
X2563676D01*
G01X1866176Y606209D02*
X2563676D01*
G01X1866176Y656209D02*
X2563676D01*
G01X1956076Y631209D02*
Y-111991D01*
G01X2157576Y631209D02*
Y-111991D01*
G01X2359076Y631209D02*
Y-111991D01*
G01X2486176Y631209D02*
Y-111991D01*
G01X-297025Y-1013390D02*
Y1828909D01*
X3691357D01*
Y-1013390D01*
X-297025D01*
G01X-265031Y165442D02*
Y172942D01*
X-262697D01*
X-261951Y172567D01*
X-261484Y172067D01*
X-261297Y171067D01*
X-261484Y170067D01*
X-262044Y169442D01*
X-262697Y169067D01*
X-265031D01*
G01X-262697D02*
X-261297Y165442D01*
G01X-253797D02*
X-257531D01*
Y172942D01*
X-253797D01*
G01X-255291Y169317D02*
X-257531D01*
G01X-246111Y172317D02*
X-246671Y172692D01*
X-247324Y172942D01*
X-248071D01*
X-248911Y172567D01*
X-249564Y171942D01*
X-250031Y171192D01*
X-250404Y169942D01*
X-250497Y168817D01*
X-250311Y167692D01*
X-250031Y166942D01*
X-249471Y166192D01*
X-248817Y165692D01*
X-248164Y165442D01*
X-247511D01*
X-246857Y165692D01*
X-246297Y166067D01*
X-245831Y166567D01*
G01X-240664Y165442D02*
X-241411Y165567D01*
X-242064Y166067D01*
X-242624Y166817D01*
X-242997Y167692D01*
X-243184Y168692D01*
Y169692D01*
X-242997Y170692D01*
X-242624Y171567D01*
X-242064Y172317D01*
X-241411Y172817D01*
X-240664Y172942D01*
X-239917Y172817D01*
X-239264Y172317D01*
X-238704Y171567D01*
X-238331Y170692D01*
X-238144Y169692D01*
Y168692D01*
X-238331Y167692D01*
X-238704Y166817D01*
X-239264Y166067D01*
X-239917Y165567D01*
X-240664Y165442D01*
G01X-235591D02*
Y172942D01*
X-233164Y166692D01*
X-230737Y172942D01*
Y165442D01*
G01X-228091D02*
Y172942D01*
X-225664Y166692D01*
X-223237Y172942D01*
Y165442D01*
G01X-216297D02*
X-220031D01*
Y172942D01*
X-216297D01*
G01X-217791Y169317D02*
X-220031D01*
G01X-212811Y165442D02*
Y172942D01*
X-208517Y165442D01*
Y172942D01*
G01X-205217Y165442D02*
Y172942D01*
X-203351D01*
X-202604Y172567D01*
X-202044Y172067D01*
X-201577Y171317D01*
X-201204Y170442D01*
X-201111Y169192D01*
X-201204Y167942D01*
X-201577Y167067D01*
X-202044Y166317D01*
X-202604Y165817D01*
X-203351Y165442D01*
X-205217D01*
G01X-193797D02*
X-197531D01*
Y172942D01*
X-193797D01*
G01X-195291Y169317D02*
X-197531D01*
G01X-190217Y165442D02*
Y172942D01*
X-188351D01*
X-187604Y172567D01*
X-187044Y172067D01*
X-186577Y171317D01*
X-186204Y170442D01*
X-186111Y169192D01*
X-186204Y167942D01*
X-186577Y167067D01*
X-187044Y166317D01*
X-187604Y165817D01*
X-188351Y165442D01*
X-190217D01*
G01X-175217D02*
Y172942D01*
X-173351D01*
X-172604Y172567D01*
X-172044Y172067D01*
X-171577Y171317D01*
X-171204Y170442D01*
X-171111Y169192D01*
X-171204Y167942D01*
X-171577Y167067D01*
X-172044Y166317D01*
X-172604Y165817D01*
X-173351Y165442D01*
X-175217D01*
G01X-167531D02*
Y172942D01*
X-165197D01*
X-164451Y172567D01*
X-163984Y172067D01*
X-163797Y171067D01*
X-163984Y170067D01*
X-164544Y169442D01*
X-165197Y169067D01*
X-167531D01*
G01X-165197D02*
X-163797Y165442D01*
G01X-159284Y172942D02*
X-157044D01*
G01X-158164D02*
Y165442D01*
G01X-159284D02*
X-157044D01*
G01X-152531Y172942D02*
Y165442D01*
X-148797D01*
G01X-145031Y172942D02*
Y165442D01*
X-141297D01*
G01X-130124Y166442D02*
X-129377Y165817D01*
X-128537Y165442D01*
X-127791D01*
X-127044Y165817D01*
X-126484Y166442D01*
X-126204Y167317D01*
X-126391Y168192D01*
X-126857Y168942D01*
X-127697Y169442D01*
X-128817Y169692D01*
X-129471Y170192D01*
X-129751Y171067D01*
X-129564Y171942D01*
X-129097Y172567D01*
X-128444Y172942D01*
X-127791D01*
X-127137Y172692D01*
X-126577Y172067D01*
G01X-121784Y172942D02*
X-119544D01*
G01X-120664D02*
Y165442D01*
G01X-121784D02*
X-119544D01*
G01X-114937Y172942D02*
X-111391D01*
X-114937Y165442D01*
X-111391D01*
G01X-103797D02*
X-107531D01*
Y172942D01*
X-103797D01*
G01X-105291Y169317D02*
X-107531D01*
G01X-92437Y165442D02*
Y172942D01*
X-88891D01*
G01X-90197Y169317D02*
X-92437D01*
G01X-83164Y165442D02*
X-83911Y165567D01*
X-84564Y166067D01*
X-85124Y166817D01*
X-85497Y167692D01*
X-85684Y168692D01*
Y169692D01*
X-85497Y170692D01*
X-85124Y171567D01*
X-84564Y172317D01*
X-83911Y172817D01*
X-83164Y172942D01*
X-82417Y172817D01*
X-81764Y172317D01*
X-81204Y171567D01*
X-80831Y170692D01*
X-80644Y169692D01*
Y168692D01*
X-80831Y167692D01*
X-81204Y166817D01*
X-81764Y166067D01*
X-82417Y165567D01*
X-83164Y165442D01*
G01X-77531D02*
Y172942D01*
X-75197D01*
X-74451Y172567D01*
X-73984Y172067D01*
X-73797Y171067D01*
X-73984Y170067D01*
X-74544Y169442D01*
X-75197Y169067D01*
X-77531D01*
G01X-75197D02*
X-73797Y165442D01*
G01X-60664D02*
Y172942D01*
X-61784Y171442D01*
G01Y165442D02*
X-59544D01*
G01X-53164Y165192D02*
X-53351Y165317D01*
Y165567D01*
X-53164Y165692D01*
X-52977Y165567D01*
Y165317D01*
X-53164Y165192D01*
G01X-45664Y172942D02*
X-46411Y172692D01*
X-46971Y172067D01*
X-47344Y171317D01*
X-47624Y170317D01*
X-47717Y169192D01*
X-47624Y168067D01*
X-47344Y167067D01*
X-46971Y166317D01*
X-46411Y165692D01*
X-45664Y165442D01*
X-44917Y165692D01*
X-44357Y166317D01*
X-43984Y167067D01*
X-43704Y168067D01*
X-43611Y169192D01*
X-43704Y170317D01*
X-43984Y171317D01*
X-44357Y172067D01*
X-44917Y172692D01*
X-45664Y172942D01*
G01X-39937Y171692D02*
X-39377Y172442D01*
X-38724Y172817D01*
X-37977Y172942D01*
X-37044Y172692D01*
X-36391Y172067D01*
X-36204Y171317D01*
X-36297Y170567D01*
X-36671Y169942D01*
X-38537Y168692D01*
X-39377Y167817D01*
X-39937Y166567D01*
X-40124Y165442D01*
X-36204D01*
G01X-33091D02*
Y172942D01*
X-30664Y166692D01*
X-28237Y172942D01*
Y165442D01*
G01X-25591D02*
Y172942D01*
X-23164Y166692D01*
X-20737Y172942D01*
Y165442D01*
G01X-9937D02*
Y172942D01*
X-6391D01*
G01X-7697Y169317D02*
X-9937D01*
G01X-1784Y172942D02*
X456D01*
G01X-664D02*
Y165442D01*
G01X-1784D02*
X456D01*
G01X4689D02*
Y172942D01*
X8983Y165442D01*
Y172942D01*
G01X13216D02*
X15456D01*
G01X14336D02*
Y165442D01*
G01X13216D02*
X15456D01*
G01X19876Y166442D02*
X20623Y165817D01*
X21463Y165442D01*
X22209D01*
X22956Y165817D01*
X23516Y166442D01*
X23796Y167317D01*
X23609Y168192D01*
X23143Y168942D01*
X22303Y169442D01*
X21183Y169692D01*
X20529Y170192D01*
X20249Y171067D01*
X20436Y171942D01*
X20903Y172567D01*
X21556Y172942D01*
X22209D01*
X22863Y172692D01*
X23423Y172067D01*
G01X27376Y165442D02*
Y172942D01*
G01X31296D02*
Y165442D01*
G01Y169192D02*
X27376D01*
G01X38703Y165442D02*
X34969D01*
Y172942D01*
X38703D01*
G01X37209Y169317D02*
X34969D01*
G01X42283Y165442D02*
Y172942D01*
X44149D01*
X44896Y172567D01*
X45456Y172067D01*
X45923Y171317D01*
X46296Y170442D01*
X46389Y169192D01*
X46296Y167942D01*
X45923Y167067D01*
X45456Y166317D01*
X44896Y165817D01*
X44149Y165442D01*
X42283D01*
G01X57469D02*
Y172942D01*
X59709D01*
X60456Y172567D01*
X61016Y171692D01*
X61203Y170692D01*
X61016Y169692D01*
X60549Y168942D01*
X59709Y168567D01*
X57469D01*
G01X66836Y172942D02*
Y165442D01*
G01X64689Y172942D02*
X68983D01*
G01X72376Y165442D02*
Y172942D01*
G01X76296D02*
Y165442D01*
G01Y169192D02*
X72376D01*
G01X88216Y172942D02*
X90456D01*
G01X89336D02*
Y165442D01*
G01X88216D02*
X90456D01*
G01X94876Y166442D02*
X95623Y165817D01*
X96463Y165442D01*
X97209D01*
X97956Y165817D01*
X98516Y166442D01*
X98796Y167317D01*
X98609Y168192D01*
X98143Y168942D01*
X97303Y169442D01*
X96183Y169692D01*
X95529Y170192D01*
X95249Y171067D01*
X95436Y171942D01*
X95903Y172567D01*
X96556Y172942D01*
X97209D01*
X97863Y172692D01*
X98423Y172067D01*
G01X111836Y165442D02*
Y172942D01*
X110716Y171442D01*
G01Y165442D02*
X112956D01*
G01X119336Y165192D02*
X119149Y165317D01*
Y165567D01*
X119336Y165692D01*
X119523Y165567D01*
Y165317D01*
X119336Y165192D01*
G01X126836Y165442D02*
Y172942D01*
X125716Y171442D01*
G01Y165442D02*
X127956D01*
G01X132283Y166567D02*
X132843Y165942D01*
X133496Y165567D01*
X134336Y165442D01*
X135176Y165692D01*
X135829Y166192D01*
X136296Y167067D01*
X136389Y168067D01*
X136203Y169067D01*
X135736Y169692D01*
X135083Y170192D01*
X134429Y170317D01*
X133776Y170192D01*
X132936Y169692D01*
X133216Y172942D01*
X135736D01*
G01X140809Y167942D02*
X143049D01*
G01X141836Y169567D02*
Y166317D01*
G01X147656Y165192D02*
X151016Y172942D01*
G01X155623Y167942D02*
X158049D01*
G01X164336Y172942D02*
X163589Y172692D01*
X163029Y172067D01*
X162656Y171317D01*
X162376Y170317D01*
X162283Y169192D01*
X162376Y168067D01*
X162656Y167067D01*
X163029Y166317D01*
X163589Y165692D01*
X164336Y165442D01*
X165083Y165692D01*
X165643Y166317D01*
X166016Y167067D01*
X166296Y168067D01*
X166389Y169192D01*
X166296Y170317D01*
X166016Y171317D01*
X165643Y172067D01*
X165083Y172692D01*
X164336Y172942D01*
G01X171836Y165192D02*
X171649Y165317D01*
Y165567D01*
X171836Y165692D01*
X172023Y165567D01*
Y165317D01*
X171836Y165192D01*
G01X179336Y172942D02*
X178589Y172692D01*
X178029Y172067D01*
X177656Y171317D01*
X177376Y170317D01*
X177283Y169192D01*
X177376Y168067D01*
X177656Y167067D01*
X178029Y166317D01*
X178589Y165692D01*
X179336Y165442D01*
X180083Y165692D01*
X180643Y166317D01*
X181016Y167067D01*
X181296Y168067D01*
X181389Y169192D01*
X181296Y170317D01*
X181016Y171317D01*
X180643Y172067D01*
X180083Y172692D01*
X179336Y172942D01*
G01X185063Y171692D02*
X185623Y172442D01*
X186276Y172817D01*
X187023Y172942D01*
X187956Y172692D01*
X188609Y172067D01*
X188796Y171317D01*
X188703Y170567D01*
X188329Y169942D01*
X186463Y168692D01*
X185623Y167817D01*
X185063Y166567D01*
X184876Y165442D01*
X188796D01*
G01X192283Y166567D02*
X192843Y165942D01*
X193496Y165567D01*
X194336Y165442D01*
X195176Y165692D01*
X195829Y166192D01*
X196296Y167067D01*
X196389Y168067D01*
X196203Y169067D01*
X195736Y169692D01*
X195083Y170192D01*
X194429Y170317D01*
X193776Y170192D01*
X192936Y169692D01*
X193216Y172942D01*
X195736D01*
G01X199409Y165442D02*
Y172942D01*
X201836Y166692D01*
X204263Y172942D01*
Y165442D01*
G01X206909D02*
Y172942D01*
X209336Y166692D01*
X211763Y172942D01*
Y165442D01*
G01X-179440Y53494D02*
Y65994D01*
X-185175Y57036D01*
X-177425D01*
G01X-169210Y53494D02*
X-168900Y56202D01*
X-168435Y58494D01*
X-167815Y60577D01*
X-167040Y62869D01*
X-165800Y65994D01*
X-172000D01*
G01X-159445Y63911D02*
X-158515Y65160D01*
X-157430Y65786D01*
X-156190Y65994D01*
X-154640Y65577D01*
X-153555Y64536D01*
X-153245Y63286D01*
X-153400Y62035D01*
X-154020Y60994D01*
X-157120Y58911D01*
X-158515Y57452D01*
X-159445Y55369D01*
X-159755Y53494D01*
X-153245D01*
G01X-144100Y53077D02*
X-144410Y53286D01*
Y53702D01*
X-144100Y53911D01*
X-143790Y53702D01*
Y53286D01*
X-144100Y53077D01*
G01X-129840Y53494D02*
Y65994D01*
X-135575Y57036D01*
X-127825D01*
G01X-117440Y53494D02*
Y65994D01*
X-123175Y57036D01*
X-115425D01*
G01X-178045Y91391D02*
X-177115Y92640D01*
X-176030Y93266D01*
X-174790Y93474D01*
X-173240Y93057D01*
X-172155Y92016D01*
X-171845Y90766D01*
X-172000Y89515D01*
X-172620Y88474D01*
X-175720Y86391D01*
X-177115Y84932D01*
X-178045Y82849D01*
X-178355Y80974D01*
X-171845D01*
G01X-166110Y82849D02*
X-165180Y81807D01*
X-164095Y81182D01*
X-162700Y80974D01*
X-161305Y81391D01*
X-160220Y82224D01*
X-159445Y83682D01*
X-159290Y85349D01*
X-159600Y87016D01*
X-160375Y88057D01*
X-161460Y88891D01*
X-162545Y89099D01*
X-163630Y88891D01*
X-165025Y88057D01*
X-164560Y93474D01*
X-160375D01*
G01X-150300Y80557D02*
X-150610Y80766D01*
Y81182D01*
X-150300Y81391D01*
X-149990Y81182D01*
Y80766D01*
X-150300Y80557D01*
G01X-141310Y83474D02*
X-140380Y82015D01*
X-139140Y81182D01*
X-137745Y80974D01*
X-136505Y81182D01*
X-135265Y82224D01*
X-134490Y83474D01*
X-134335Y84724D01*
X-134645Y86182D01*
X-135730Y87224D01*
X-136815Y87641D01*
X-138210D01*
G01X-136815D02*
X-135885Y88266D01*
X-135110Y89307D01*
X-134800Y90557D01*
X-135110Y91807D01*
X-135885Y92849D01*
X-137280Y93474D01*
X-138675Y93266D01*
X-140070Y92432D01*
G01X-128910Y83474D02*
X-127980Y82015D01*
X-126740Y81182D01*
X-125345Y80974D01*
X-124105Y81182D01*
X-122865Y82224D01*
X-122090Y83474D01*
X-121935Y84724D01*
X-122245Y86182D01*
X-123330Y87224D01*
X-124415Y87641D01*
X-125810D01*
G01X-124415D02*
X-123485Y88266D01*
X-122710Y89307D01*
X-122400Y90557D01*
X-122710Y91807D01*
X-123485Y92849D01*
X-124880Y93474D01*
X-126275Y93266D01*
X-127670Y92432D01*
G01X-184085Y107432D02*
X-183000Y106391D01*
X-181760Y105974D01*
X-180520Y106391D01*
X-179435Y107640D01*
X-178660Y109516D01*
X-178350Y111391D01*
Y113682D01*
X-178660Y115557D01*
X-179435Y117224D01*
X-180365Y118057D01*
X-181450Y118474D01*
X-182690Y118057D01*
X-183620Y117224D01*
X-184240Y115974D01*
X-184550Y114307D01*
X-184240Y112849D01*
X-183465Y111391D01*
X-182535Y110557D01*
X-181450Y110349D01*
X-180210Y110765D01*
X-179280Y111807D01*
X-178350Y113682D01*
G01X-171685Y107432D02*
X-170600Y106391D01*
X-169360Y105974D01*
X-168120Y106391D01*
X-167035Y107640D01*
X-166260Y109516D01*
X-165950Y111391D01*
Y113682D01*
X-166260Y115557D01*
X-167035Y117224D01*
X-167965Y118057D01*
X-169050Y118474D01*
X-170290Y118057D01*
X-171220Y117224D01*
X-171840Y115974D01*
X-172150Y114307D01*
X-171840Y112849D01*
X-171065Y111391D01*
X-170135Y110557D01*
X-169050Y110349D01*
X-167810Y110765D01*
X-166880Y111807D01*
X-165950Y113682D01*
G01X-156960Y105974D02*
X-156650Y108682D01*
X-156185Y110974D01*
X-155565Y113057D01*
X-154790Y115349D01*
X-153550Y118474D01*
X-159750D01*
G01X-144250Y105557D02*
X-144560Y105766D01*
Y106182D01*
X-144250Y106391D01*
X-143940Y106182D01*
Y105766D01*
X-144250Y105557D01*
G01X-134795Y116391D02*
X-133865Y117640D01*
X-132780Y118266D01*
X-131540Y118474D01*
X-129990Y118057D01*
X-128905Y117016D01*
X-128595Y115766D01*
X-128750Y114515D01*
X-129370Y113474D01*
X-132470Y111391D01*
X-133865Y109932D01*
X-134795Y107849D01*
X-135105Y105974D01*
X-128595D01*
G01X-117590D02*
Y118474D01*
X-123325Y109516D01*
X-115575D01*
G01X-177960Y124250D02*
X-177030Y122791D01*
X-175790Y121958D01*
X-174395Y121750D01*
X-173155Y121958D01*
X-171915Y123000D01*
X-171140Y124250D01*
X-170985Y125500D01*
X-171295Y126958D01*
X-172380Y128000D01*
X-173465Y128417D01*
X-174860D01*
G01X-173465D02*
X-172535Y129042D01*
X-171760Y130083D01*
X-171450Y131333D01*
X-171760Y132583D01*
X-172535Y133625D01*
X-173930Y134250D01*
X-175325Y134042D01*
X-176720Y133208D01*
G01X-165095Y132167D02*
X-164165Y133416D01*
X-163080Y134042D01*
X-161840Y134250D01*
X-160290Y133833D01*
X-159205Y132792D01*
X-158895Y131542D01*
X-159050Y130291D01*
X-159670Y129250D01*
X-162770Y127167D01*
X-164165Y125708D01*
X-165095Y123625D01*
X-165405Y121750D01*
X-158895D01*
G01X-149750Y121333D02*
X-150060Y121542D01*
Y121958D01*
X-149750Y122167D01*
X-149440Y121958D01*
Y121542D01*
X-149750Y121333D01*
G01X-139985Y123208D02*
X-138900Y122167D01*
X-137660Y121750D01*
X-136420Y122167D01*
X-135335Y123416D01*
X-134560Y125292D01*
X-134250Y127167D01*
Y129458D01*
X-134560Y131333D01*
X-135335Y133000D01*
X-136265Y133833D01*
X-137350Y134250D01*
X-138590Y133833D01*
X-139520Y133000D01*
X-140140Y131750D01*
X-140450Y130083D01*
X-140140Y128625D01*
X-139365Y127167D01*
X-138435Y126333D01*
X-137350Y126125D01*
X-136110Y126541D01*
X-135180Y127583D01*
X-134250Y129458D01*
G01X-123090Y121750D02*
Y134250D01*
X-128825Y125292D01*
X-121075D01*
G01X-187100Y146750D02*
Y159250D01*
X-188960Y156750D01*
G01Y146750D02*
X-185240D01*
G01X-177645Y157167D02*
X-176715Y158416D01*
X-175630Y159042D01*
X-174390Y159250D01*
X-172840Y158833D01*
X-171755Y157792D01*
X-171445Y156542D01*
X-171600Y155291D01*
X-172220Y154250D01*
X-175320Y152167D01*
X-176715Y150708D01*
X-177645Y148625D01*
X-177955Y146750D01*
X-171445D01*
G01X-164935Y148208D02*
X-163850Y147167D01*
X-162610Y146750D01*
X-161370Y147167D01*
X-160285Y148416D01*
X-159510Y150292D01*
X-159200Y152167D01*
Y154458D01*
X-159510Y156333D01*
X-160285Y158000D01*
X-161215Y158833D01*
X-162300Y159250D01*
X-163540Y158833D01*
X-164470Y158000D01*
X-165090Y156750D01*
X-165400Y155083D01*
X-165090Y153625D01*
X-164315Y152167D01*
X-163385Y151333D01*
X-162300Y151125D01*
X-161060Y151541D01*
X-160130Y152583D01*
X-159200Y154458D01*
G01X-152845Y151958D02*
X-151760Y153417D01*
X-150830Y154250D01*
X-149590Y154667D01*
X-148505Y154250D01*
X-147730Y153417D01*
X-147110Y152167D01*
X-146955Y150708D01*
X-147110Y149458D01*
X-147730Y148208D01*
X-148660Y147167D01*
X-149745Y146750D01*
X-150985Y147167D01*
X-152070Y148416D01*
X-152690Y150292D01*
X-152845Y152375D01*
X-152535Y155083D01*
X-152070Y156542D01*
X-151295Y158000D01*
X-150210Y159042D01*
X-149125Y159250D01*
X-148040Y158833D01*
X-147265Y157792D01*
G01X-137500Y146333D02*
X-137810Y146542D01*
Y146958D01*
X-137500Y147167D01*
X-137190Y146958D01*
Y146542D01*
X-137500Y146333D01*
G01X-125100Y146750D02*
X-124015Y146958D01*
X-122775Y147583D01*
X-122000Y148625D01*
X-121690Y150083D01*
X-122000Y151541D01*
X-122930Y152792D01*
X-124325Y153417D01*
X-125875D01*
X-126805Y153833D01*
X-127580Y154875D01*
X-127890Y156333D01*
X-127425Y157792D01*
X-126340Y158833D01*
X-125100Y159250D01*
X-123860Y158833D01*
X-122775Y157792D01*
X-122310Y156333D01*
X-122620Y154875D01*
X-123395Y153833D01*
X-124325Y153417D01*
X-125875D01*
X-127270Y152792D01*
X-128200Y151541D01*
X-128510Y150083D01*
X-128200Y148625D01*
X-127425Y147583D01*
X-126185Y146958D01*
X-125100Y146750D01*
G01X-116110Y148625D02*
X-115180Y147583D01*
X-114095Y146958D01*
X-112700Y146750D01*
X-111305Y147167D01*
X-110220Y148000D01*
X-109445Y149458D01*
X-109290Y151125D01*
X-109600Y152792D01*
X-110375Y153833D01*
X-111460Y154667D01*
X-112545Y154875D01*
X-113630Y154667D01*
X-115025Y153833D01*
X-114560Y159250D01*
X-110375D01*
G01X-190445Y230840D02*
X-189515Y232089D01*
X-188430Y232715D01*
X-187190Y232923D01*
X-185640Y232506D01*
X-184555Y231465D01*
X-184245Y230215D01*
X-184400Y228964D01*
X-185020Y227923D01*
X-188120Y225840D01*
X-189515Y224381D01*
X-190445Y222298D01*
X-190755Y220423D01*
X-184245D01*
G01X-175100D02*
Y232923D01*
X-176960Y230423D01*
G01Y220423D02*
X-173240D01*
G01X-160840D02*
Y232923D01*
X-166575Y223965D01*
X-158825D01*
G01X-150300Y220423D02*
Y232923D01*
X-152160Y230423D01*
G01Y220423D02*
X-148440D01*
G01X-137900Y220006D02*
X-138210Y220215D01*
Y220631D01*
X-137900Y220840D01*
X-137590Y220631D01*
Y220215D01*
X-137900Y220006D01*
G01X-125810Y220423D02*
X-125500Y223131D01*
X-125035Y225423D01*
X-124415Y227506D01*
X-123640Y229798D01*
X-122400Y232923D01*
X-128600D01*
G01X-116510Y222923D02*
X-115580Y221464D01*
X-114340Y220631D01*
X-112945Y220423D01*
X-111705Y220631D01*
X-110465Y221673D01*
X-109690Y222923D01*
X-109535Y224173D01*
X-109845Y225631D01*
X-110930Y226673D01*
X-112015Y227090D01*
X-113410D01*
G01X-112015D02*
X-111085Y227715D01*
X-110310Y228756D01*
X-110000Y230006D01*
X-110310Y231256D01*
X-111085Y232298D01*
X-112480Y232923D01*
X-113875Y232715D01*
X-115270Y231881D01*
G01X-172160Y197298D02*
X-171230Y196256D01*
X-170145Y195631D01*
X-168750Y195423D01*
X-167355Y195840D01*
X-166270Y196673D01*
X-165495Y198131D01*
X-165340Y199798D01*
X-165650Y201465D01*
X-166425Y202506D01*
X-167510Y203340D01*
X-168595Y203548D01*
X-169680Y203340D01*
X-171075Y202506D01*
X-170610Y207923D01*
X-166425D01*
G01X-154490Y195423D02*
Y207923D01*
X-160225Y198965D01*
X-152475D01*
G01X-143950Y195006D02*
X-144260Y195215D01*
Y195631D01*
X-143950Y195840D01*
X-143640Y195631D01*
Y195215D01*
X-143950Y195006D01*
G01X-129690Y195423D02*
Y207923D01*
X-135425Y198965D01*
X-127675D01*
G01X-171385Y350424D02*
X-170300Y349383D01*
X-169060Y348966D01*
X-167820Y349383D01*
X-166735Y350632D01*
X-165960Y352508D01*
X-165650Y354383D01*
Y356674D01*
X-165960Y358549D01*
X-166735Y360216D01*
X-167665Y361049D01*
X-168750Y361466D01*
X-169990Y361049D01*
X-170920Y360216D01*
X-171540Y358966D01*
X-171850Y357299D01*
X-171540Y355841D01*
X-170765Y354383D01*
X-169835Y353549D01*
X-168750Y353341D01*
X-167510Y353757D01*
X-166580Y354799D01*
X-165650Y356674D01*
G01X-159760Y351466D02*
X-158830Y350007D01*
X-157590Y349174D01*
X-156195Y348966D01*
X-154955Y349174D01*
X-153715Y350216D01*
X-152940Y351466D01*
X-152785Y352716D01*
X-153095Y354174D01*
X-154180Y355216D01*
X-155265Y355633D01*
X-156660D01*
G01X-155265D02*
X-154335Y356258D01*
X-153560Y357299D01*
X-153250Y358549D01*
X-153560Y359799D01*
X-154335Y360841D01*
X-155730Y361466D01*
X-157125Y361258D01*
X-158520Y360424D01*
G01X-143950Y348549D02*
X-144260Y348758D01*
Y349174D01*
X-143950Y349383D01*
X-143640Y349174D01*
Y348758D01*
X-143950Y348549D01*
G01X-129690Y348966D02*
Y361466D01*
X-135425Y352508D01*
X-127675D01*
G01X-190910Y376466D02*
X-189980Y375007D01*
X-188740Y374174D01*
X-187345Y373966D01*
X-186105Y374174D01*
X-184865Y375216D01*
X-184090Y376466D01*
X-183935Y377716D01*
X-184245Y379174D01*
X-185330Y380216D01*
X-186415Y380633D01*
X-187810D01*
G01X-186415D02*
X-185485Y381258D01*
X-184710Y382299D01*
X-184400Y383549D01*
X-184710Y384799D01*
X-185485Y385841D01*
X-186880Y386466D01*
X-188275Y386258D01*
X-189670Y385424D01*
G01X-178045Y379174D02*
X-176960Y380633D01*
X-176030Y381466D01*
X-174790Y381883D01*
X-173705Y381466D01*
X-172930Y380633D01*
X-172310Y379383D01*
X-172155Y377924D01*
X-172310Y376674D01*
X-172930Y375424D01*
X-173860Y374383D01*
X-174945Y373966D01*
X-176185Y374383D01*
X-177270Y375632D01*
X-177890Y377508D01*
X-178045Y379591D01*
X-177735Y382299D01*
X-177270Y383758D01*
X-176495Y385216D01*
X-175410Y386258D01*
X-174325Y386466D01*
X-173240Y386049D01*
X-172465Y385008D01*
G01X-163010Y373966D02*
X-162700Y376674D01*
X-162235Y378966D01*
X-161615Y381049D01*
X-160840Y383341D01*
X-159600Y386466D01*
X-165800D01*
G01X-150610Y373966D02*
X-150300Y376674D01*
X-149835Y378966D01*
X-149215Y381049D01*
X-148440Y383341D01*
X-147200Y386466D01*
X-153400D01*
G01X-137900Y373549D02*
X-138210Y373758D01*
Y374174D01*
X-137900Y374383D01*
X-137590Y374174D01*
Y373758D01*
X-137900Y373549D01*
G01X-125500Y373966D02*
Y386466D01*
X-127360Y383966D01*
G01Y373966D02*
X-123640D01*
G01X-116045Y379174D02*
X-114960Y380633D01*
X-114030Y381466D01*
X-112790Y381883D01*
X-111705Y381466D01*
X-110930Y380633D01*
X-110310Y379383D01*
X-110155Y377924D01*
X-110310Y376674D01*
X-110930Y375424D01*
X-111860Y374383D01*
X-112945Y373966D01*
X-114185Y374383D01*
X-115270Y375632D01*
X-115890Y377508D01*
X-116045Y379591D01*
X-115735Y382299D01*
X-115270Y383758D01*
X-114495Y385216D01*
X-113410Y386258D01*
X-112325Y386466D01*
X-111240Y386049D01*
X-110465Y385008D01*
G01X-185790Y488455D02*
Y500955D01*
X-191525Y491997D01*
X-183775D01*
G01X-175250Y488455D02*
X-174165Y488663D01*
X-172925Y489288D01*
X-172150Y490330D01*
X-171840Y491788D01*
X-172150Y493246D01*
X-173080Y494497D01*
X-174475Y495122D01*
X-176025D01*
X-176955Y495538D01*
X-177730Y496580D01*
X-178040Y498038D01*
X-177575Y499497D01*
X-176490Y500538D01*
X-175250Y500955D01*
X-174010Y500538D01*
X-172925Y499497D01*
X-172460Y498038D01*
X-172770Y496580D01*
X-173545Y495538D01*
X-174475Y495122D01*
X-176025D01*
X-177420Y494497D01*
X-178350Y493246D01*
X-178660Y491788D01*
X-178350Y490330D01*
X-177575Y489288D01*
X-176335Y488663D01*
X-175250Y488455D01*
G01X-165795Y498872D02*
X-164865Y500121D01*
X-163780Y500747D01*
X-162540Y500955D01*
X-160990Y500538D01*
X-159905Y499497D01*
X-159595Y498247D01*
X-159750Y496996D01*
X-160370Y495955D01*
X-163470Y493872D01*
X-164865Y492413D01*
X-165795Y490330D01*
X-166105Y488455D01*
X-159595D01*
G01X-153395Y498872D02*
X-152465Y500121D01*
X-151380Y500747D01*
X-150140Y500955D01*
X-148590Y500538D01*
X-147505Y499497D01*
X-147195Y498247D01*
X-147350Y496996D01*
X-147970Y495955D01*
X-151070Y493872D01*
X-152465Y492413D01*
X-153395Y490330D01*
X-153705Y488455D01*
X-147195D01*
G01X-138050Y488038D02*
X-138360Y488247D01*
Y488663D01*
X-138050Y488872D01*
X-137740Y488663D01*
Y488247D01*
X-138050Y488038D01*
G01X-125650Y500955D02*
X-126890Y500538D01*
X-127820Y499497D01*
X-128440Y498247D01*
X-128905Y496580D01*
X-129060Y494705D01*
X-128905Y492830D01*
X-128440Y491163D01*
X-127820Y489913D01*
X-126890Y488872D01*
X-125650Y488455D01*
X-124410Y488872D01*
X-123480Y489913D01*
X-122860Y491163D01*
X-122395Y492830D01*
X-122240Y494705D01*
X-122395Y496580D01*
X-122860Y498247D01*
X-123480Y499497D01*
X-124410Y500538D01*
X-125650Y500955D01*
G01X-116660Y490330D02*
X-115730Y489288D01*
X-114645Y488663D01*
X-113250Y488455D01*
X-111855Y488872D01*
X-110770Y489705D01*
X-109995Y491163D01*
X-109840Y492830D01*
X-110150Y494497D01*
X-110925Y495538D01*
X-112010Y496372D01*
X-113095Y496580D01*
X-114180Y496372D01*
X-115575Y495538D01*
X-115110Y500955D01*
X-110925D01*
G01X-181300Y463455D02*
Y475955D01*
X-183160Y473455D01*
G01Y463455D02*
X-179440D01*
G01X-171845Y473872D02*
X-170915Y475121D01*
X-169830Y475747D01*
X-168590Y475955D01*
X-167040Y475538D01*
X-165955Y474497D01*
X-165645Y473247D01*
X-165800Y471996D01*
X-166420Y470955D01*
X-169520Y468872D01*
X-170915Y467413D01*
X-171845Y465330D01*
X-172155Y463455D01*
X-165645D01*
G01X-159445Y473872D02*
X-158515Y475121D01*
X-157430Y475747D01*
X-156190Y475955D01*
X-154640Y475538D01*
X-153555Y474497D01*
X-153245Y473247D01*
X-153400Y471996D01*
X-154020Y470955D01*
X-157120Y468872D01*
X-158515Y467413D01*
X-159445Y465330D01*
X-159755Y463455D01*
X-153245D01*
G01X-144100Y463038D02*
X-144410Y463247D01*
Y463663D01*
X-144100Y463872D01*
X-143790Y463663D01*
Y463247D01*
X-144100Y463038D01*
G01X-129840Y463455D02*
Y475955D01*
X-135575Y466997D01*
X-127825D01*
G01X-119300Y463455D02*
X-118215Y463663D01*
X-116975Y464288D01*
X-116200Y465330D01*
X-115890Y466788D01*
X-116200Y468246D01*
X-117130Y469497D01*
X-118525Y470122D01*
X-120075D01*
X-121005Y470538D01*
X-121780Y471580D01*
X-122090Y473038D01*
X-121625Y474497D01*
X-120540Y475538D01*
X-119300Y475955D01*
X-118060Y475538D01*
X-116975Y474497D01*
X-116510Y473038D01*
X-116820Y471580D01*
X-117595Y470538D01*
X-118525Y470122D01*
X-120075D01*
X-121470Y469497D01*
X-122400Y468246D01*
X-122710Y466788D01*
X-122400Y465330D01*
X-121625Y464288D01*
X-120385Y463663D01*
X-119300Y463455D01*
G01X-191910Y543558D02*
X-190980Y542516D01*
X-189895Y541891D01*
X-188500Y541683D01*
X-187105Y542100D01*
X-186020Y542933D01*
X-185245Y544391D01*
X-185090Y546058D01*
X-185400Y547725D01*
X-186175Y548766D01*
X-187260Y549600D01*
X-188345Y549808D01*
X-189430Y549600D01*
X-190825Y548766D01*
X-190360Y554183D01*
X-186175D01*
G01X-179510Y544183D02*
X-178580Y542724D01*
X-177340Y541891D01*
X-175945Y541683D01*
X-174705Y541891D01*
X-173465Y542933D01*
X-172690Y544183D01*
X-172535Y545433D01*
X-172845Y546891D01*
X-173930Y547933D01*
X-175015Y548350D01*
X-176410D01*
G01X-175015D02*
X-174085Y548975D01*
X-173310Y550016D01*
X-173000Y551266D01*
X-173310Y552516D01*
X-174085Y553558D01*
X-175480Y554183D01*
X-176875Y553975D01*
X-178270Y553141D01*
G01X-167110Y543558D02*
X-166180Y542516D01*
X-165095Y541891D01*
X-163700Y541683D01*
X-162305Y542100D01*
X-161220Y542933D01*
X-160445Y544391D01*
X-160290Y546058D01*
X-160600Y547725D01*
X-161375Y548766D01*
X-162460Y549600D01*
X-163545Y549808D01*
X-164630Y549600D01*
X-166025Y548766D01*
X-165560Y554183D01*
X-161375D01*
G01X-149440Y541683D02*
Y554183D01*
X-155175Y545225D01*
X-147425D01*
G01X-138900Y541266D02*
X-139210Y541475D01*
Y541891D01*
X-138900Y542100D01*
X-138590Y541891D01*
Y541475D01*
X-138900Y541266D01*
G01X-129910Y544183D02*
X-128980Y542724D01*
X-127740Y541891D01*
X-126345Y541683D01*
X-125105Y541891D01*
X-123865Y542933D01*
X-123090Y544183D01*
X-122935Y545433D01*
X-123245Y546891D01*
X-124330Y547933D01*
X-125415Y548350D01*
X-126810D01*
G01X-125415D02*
X-124485Y548975D01*
X-123710Y550016D01*
X-123400Y551266D01*
X-123710Y552516D01*
X-124485Y553558D01*
X-125880Y554183D01*
X-127275Y553975D01*
X-128670Y553141D01*
G01X-117510Y544183D02*
X-116580Y542724D01*
X-115340Y541891D01*
X-113945Y541683D01*
X-112705Y541891D01*
X-111465Y542933D01*
X-110690Y544183D01*
X-110535Y545433D01*
X-110845Y546891D01*
X-111930Y547933D01*
X-113015Y548350D01*
X-114410D01*
G01X-113015D02*
X-112085Y548975D01*
X-111310Y550016D01*
X-111000Y551266D01*
X-111310Y552516D01*
X-112085Y553558D01*
X-113480Y554183D01*
X-114875Y553975D01*
X-116270Y553141D01*
G01X-150300Y-6250D02*
X-151540Y-6667D01*
X-152470Y-7708D01*
X-153090Y-8958D01*
X-153555Y-10625D01*
X-153710Y-12500D01*
X-153555Y-14375D01*
X-153090Y-16042D01*
X-152470Y-17292D01*
X-151540Y-18333D01*
X-150300Y-18750D01*
X-149060Y-18333D01*
X-148130Y-17292D01*
X-147510Y-16042D01*
X-147045Y-14375D01*
X-146890Y-12500D01*
X-147045Y-10625D01*
X-147510Y-8958D01*
X-148130Y-7708D01*
X-149060Y-6667D01*
X-150300Y-6250D01*
G01X-150450Y18750D02*
X-151690Y18333D01*
X-152620Y17292D01*
X-153240Y16042D01*
X-153705Y14375D01*
X-153860Y12500D01*
X-153705Y10625D01*
X-153240Y8958D01*
X-152620Y7708D01*
X-151690Y6667D01*
X-150450Y6250D01*
X-149210Y6667D01*
X-148280Y7708D01*
X-147660Y8958D01*
X-147195Y10625D01*
X-147040Y12500D01*
X-147195Y14375D01*
X-147660Y16042D01*
X-148280Y17292D01*
X-149210Y18333D01*
X-150450Y18750D01*
G01X-156350Y28494D02*
Y40994D01*
X-158210Y38494D01*
G01Y28494D02*
X-154490D01*
G01X-146895Y38911D02*
X-145965Y40160D01*
X-144880Y40786D01*
X-143640Y40994D01*
X-142090Y40577D01*
X-141005Y39536D01*
X-140695Y38286D01*
X-140850Y37035D01*
X-141470Y35994D01*
X-144570Y33911D01*
X-145965Y32452D01*
X-146895Y30369D01*
X-147205Y28494D01*
X-140695D01*
G01X-163550Y516683D02*
Y529183D01*
X-165410Y526683D01*
G01Y516683D02*
X-161690D01*
G01X-154560Y519183D02*
X-153630Y517724D01*
X-152390Y516891D01*
X-150995Y516683D01*
X-149755Y516891D01*
X-148515Y517933D01*
X-147740Y519183D01*
X-147585Y520433D01*
X-147895Y521891D01*
X-148980Y522933D01*
X-150065Y523350D01*
X-151460D01*
G01X-150065D02*
X-149135Y523975D01*
X-148360Y525016D01*
X-148050Y526266D01*
X-148360Y527516D01*
X-149135Y528558D01*
X-150530Y529183D01*
X-151925Y528975D01*
X-153320Y528141D01*
G01X-141695Y521891D02*
X-140610Y523350D01*
X-139680Y524183D01*
X-138440Y524600D01*
X-137355Y524183D01*
X-136580Y523350D01*
X-135960Y522100D01*
X-135805Y520641D01*
X-135960Y519391D01*
X-136580Y518141D01*
X-137510Y517100D01*
X-138595Y516683D01*
X-139835Y517100D01*
X-140920Y518349D01*
X-141540Y520225D01*
X-141695Y522308D01*
X-141385Y525016D01*
X-140920Y526475D01*
X-140145Y527933D01*
X-139060Y528975D01*
X-137975Y529183D01*
X-136890Y528766D01*
X-136115Y527725D01*
G01X-18750Y-75150D02*
X-18333Y-76390D01*
X-17292Y-77320D01*
X-16042Y-77940D01*
X-14375Y-78405D01*
X-12500Y-78560D01*
X-10625Y-78405D01*
X-8958Y-77940D01*
X-7708Y-77320D01*
X-6667Y-76390D01*
X-6250Y-75150D01*
X-6667Y-73910D01*
X-7708Y-72980D01*
X-8958Y-72360D01*
X-10625Y-71895D01*
X-12500Y-71740D01*
X-14375Y-71895D01*
X-16042Y-72360D01*
X-17292Y-72980D01*
X-18333Y-73910D01*
X-18750Y-75150D01*
G01X6250Y-75000D02*
X6667Y-76240D01*
X7708Y-77170D01*
X8958Y-77790D01*
X10625Y-78255D01*
X12500Y-78410D01*
X14375Y-78255D01*
X16042Y-77790D01*
X17292Y-77170D01*
X18333Y-76240D01*
X18750Y-75000D01*
X18333Y-73760D01*
X17292Y-72830D01*
X16042Y-72210D01*
X14375Y-71745D01*
X12500Y-71590D01*
X10625Y-71745D01*
X8958Y-72210D01*
X7708Y-72830D01*
X6667Y-73760D01*
X6250Y-75000D01*
G01X8642Y686555D02*
X7183Y687640D01*
X6350Y688570D01*
X5933Y689810D01*
X6350Y690895D01*
X7183Y691670D01*
X8433Y692290D01*
X9892Y692445D01*
X11142Y692290D01*
X12392Y691670D01*
X13433Y690740D01*
X13850Y689655D01*
X13433Y688415D01*
X12184Y687330D01*
X10308Y686710D01*
X8225Y686555D01*
X5517Y686865D01*
X4058Y687330D01*
X2600Y688105D01*
X1558Y689190D01*
X1350Y690275D01*
X1767Y691360D01*
X2808Y692135D01*
G01X1350Y701900D02*
X1767Y700660D01*
X2808Y699730D01*
X4058Y699110D01*
X5725Y698645D01*
X7600Y698490D01*
X9475Y698645D01*
X11142Y699110D01*
X12392Y699730D01*
X13433Y700660D01*
X13850Y701900D01*
X13433Y703140D01*
X12392Y704070D01*
X11142Y704690D01*
X9475Y705155D01*
X7600Y705310D01*
X5725Y705155D01*
X4058Y704690D01*
X2808Y704070D01*
X1767Y703140D01*
X1350Y701900D01*
G01X8642Y711355D02*
X7183Y712440D01*
X6350Y713370D01*
X5933Y714610D01*
X6350Y715695D01*
X7183Y716470D01*
X8433Y717090D01*
X9892Y717245D01*
X11142Y717090D01*
X12392Y716470D01*
X13433Y715540D01*
X13850Y714455D01*
X13433Y713215D01*
X12184Y712130D01*
X10308Y711510D01*
X8225Y711355D01*
X5517Y711665D01*
X4058Y712130D01*
X2600Y712905D01*
X1558Y713990D01*
X1350Y715075D01*
X1767Y716160D01*
X2808Y716935D01*
G01X14267Y726700D02*
X14058Y726390D01*
X13642D01*
X13433Y726700D01*
X13642Y727010D01*
X14058D01*
X14267Y726700D01*
G01X11350Y735690D02*
X12809Y736620D01*
X13642Y737860D01*
X13850Y739255D01*
X13642Y740495D01*
X12600Y741735D01*
X11350Y742510D01*
X10100Y742665D01*
X8642Y742355D01*
X7600Y741270D01*
X7183Y740185D01*
Y738790D01*
G01Y740185D02*
X6558Y741115D01*
X5517Y741890D01*
X4267Y742200D01*
X3017Y741890D01*
X1975Y741115D01*
X1350Y739720D01*
X1558Y738325D01*
X2392Y736930D01*
G01X1350Y751500D02*
X1767Y750260D01*
X2808Y749330D01*
X4058Y748710D01*
X5725Y748245D01*
X7600Y748090D01*
X9475Y748245D01*
X11142Y748710D01*
X12392Y749330D01*
X13433Y750260D01*
X13850Y751500D01*
X13433Y752740D01*
X12392Y753670D01*
X11142Y754290D01*
X9475Y754755D01*
X7600Y754910D01*
X5725Y754755D01*
X4058Y754290D01*
X2808Y753670D01*
X1767Y752740D01*
X1350Y751500D01*
G01X16913Y-817022D02*
X18480D01*
Y-818912D01*
X18010Y-819542D01*
X17461Y-819962D01*
X16678Y-820172D01*
X15895Y-819962D01*
X15346Y-819542D01*
X14876Y-818912D01*
X14563Y-818177D01*
X14406Y-817337D01*
Y-816602D01*
X14563Y-815972D01*
X14876Y-815237D01*
X15346Y-814607D01*
X15816Y-814187D01*
X16443Y-813872D01*
X16991D01*
X17618Y-814082D01*
X18088Y-814502D01*
G01X21020Y-813872D02*
Y-818387D01*
X21333Y-819332D01*
X21960Y-819962D01*
X22743Y-820172D01*
X23526Y-819962D01*
X24153Y-819332D01*
X24466Y-818387D01*
Y-813872D01*
G01X28103D02*
X29983D01*
G01X29043D02*
Y-820172D01*
G01X28103D02*
X29983D01*
G01X33698Y-819332D02*
X34325Y-819857D01*
X35030Y-820172D01*
X35656D01*
X36283Y-819857D01*
X36753Y-819332D01*
X36988Y-818597D01*
X36831Y-817862D01*
X36440Y-817232D01*
X35735Y-816812D01*
X34795Y-816602D01*
X34246Y-816182D01*
X34011Y-815447D01*
X34168Y-814712D01*
X34560Y-814187D01*
X35108Y-813872D01*
X35656D01*
X36205Y-814082D01*
X36675Y-814607D01*
G01X39998Y-820172D02*
Y-813872D01*
G01X43288D02*
Y-820172D01*
G01Y-817022D02*
X39998D01*
G01X45985Y-820172D02*
X47943Y-813872D01*
X49901Y-820172D01*
G01X49196Y-817967D02*
X46690D01*
G01X52441Y-820172D02*
Y-813872D01*
X56045Y-820172D01*
Y-813872D01*
G01X65120Y-820172D02*
Y-813872D01*
X66686D01*
X67313Y-814187D01*
X67783Y-814607D01*
X68175Y-815237D01*
X68488Y-815972D01*
X68566Y-817022D01*
X68488Y-818072D01*
X68175Y-818807D01*
X67783Y-819437D01*
X67313Y-819857D01*
X66686Y-820172D01*
X65120D01*
G01X72203Y-813872D02*
X74083D01*
G01X73143D02*
Y-820172D01*
G01X72203D02*
X74083D01*
G01X77798Y-819332D02*
X78425Y-819857D01*
X79130Y-820172D01*
X79756D01*
X80383Y-819857D01*
X80853Y-819332D01*
X81088Y-818597D01*
X80931Y-817862D01*
X80540Y-817232D01*
X79835Y-816812D01*
X78895Y-816602D01*
X78346Y-816182D01*
X78111Y-815447D01*
X78268Y-814712D01*
X78660Y-814187D01*
X79208Y-813872D01*
X79756D01*
X80305Y-814082D01*
X80775Y-814607D01*
G01X85743Y-813872D02*
Y-820172D01*
G01X83941Y-813872D02*
X87545D01*
G01X92043Y-820382D02*
X91886Y-820277D01*
Y-820067D01*
X92043Y-819962D01*
X92200Y-820067D01*
Y-820277D01*
X92043Y-820382D01*
G01X98186Y-821327D02*
X98500Y-819962D01*
G01X104643Y-813872D02*
Y-820172D01*
G01X102841Y-813872D02*
X106445D01*
G01X108985Y-820172D02*
X110943Y-813872D01*
X112901Y-820172D01*
G01X112196Y-817967D02*
X109690D01*
G01X117243Y-820172D02*
X116616Y-820067D01*
X116068Y-819647D01*
X115598Y-819017D01*
X115285Y-818282D01*
X115128Y-817442D01*
Y-816602D01*
X115285Y-815762D01*
X115598Y-815027D01*
X116068Y-814397D01*
X116616Y-813977D01*
X117243Y-813872D01*
X117870Y-813977D01*
X118418Y-814397D01*
X118888Y-815027D01*
X119201Y-815762D01*
X119358Y-816602D01*
Y-817442D01*
X119201Y-818282D01*
X118888Y-819017D01*
X118418Y-819647D01*
X117870Y-820067D01*
X117243Y-820172D01*
G01X123543D02*
Y-817337D01*
X121976Y-813872D01*
G01X125110D02*
X123543Y-817337D01*
G01X128120Y-813872D02*
Y-818387D01*
X128433Y-819332D01*
X129060Y-819962D01*
X129843Y-820172D01*
X130626Y-819962D01*
X131253Y-819332D01*
X131566Y-818387D01*
Y-813872D01*
G01X134185Y-820172D02*
X136143Y-813872D01*
X138101Y-820172D01*
G01X137396Y-817967D02*
X134890D01*
G01X140641Y-820172D02*
Y-813872D01*
X144245Y-820172D01*
Y-813872D01*
G01X18166Y-824397D02*
X17696Y-824082D01*
X17148Y-823872D01*
X16521D01*
X15816Y-824187D01*
X15268Y-824712D01*
X14876Y-825342D01*
X14563Y-826392D01*
X14485Y-827337D01*
X14641Y-828282D01*
X14876Y-828912D01*
X15346Y-829542D01*
X15895Y-829962D01*
X16443Y-830172D01*
X16991D01*
X17540Y-829962D01*
X18010Y-829647D01*
X18401Y-829227D01*
G01X21803Y-823872D02*
X23683D01*
G01X22743D02*
Y-830172D01*
G01X21803D02*
X23683D01*
G01X29043Y-823872D02*
Y-830172D01*
G01X27241Y-823872D02*
X30845D01*
G01X35343Y-830172D02*
Y-827337D01*
X33776Y-823872D01*
G01X36910D02*
X35343Y-827337D01*
G01X46220Y-828912D02*
X46690Y-829647D01*
X47316Y-830067D01*
X48021Y-830172D01*
X48648Y-830067D01*
X49275Y-829542D01*
X49666Y-828912D01*
X49745Y-828282D01*
X49588Y-827547D01*
X49040Y-827022D01*
X48491Y-826812D01*
X47786D01*
G01X48491D02*
X48961Y-826497D01*
X49353Y-825972D01*
X49510Y-825342D01*
X49353Y-824712D01*
X48961Y-824187D01*
X48256Y-823872D01*
X47551Y-823977D01*
X46846Y-824397D01*
G01X52520Y-828912D02*
X52990Y-829647D01*
X53616Y-830067D01*
X54321Y-830172D01*
X54948Y-830067D01*
X55575Y-829542D01*
X55966Y-828912D01*
X56045Y-828282D01*
X55888Y-827547D01*
X55340Y-827022D01*
X54791Y-826812D01*
X54086D01*
G01X54791D02*
X55261Y-826497D01*
X55653Y-825972D01*
X55810Y-825342D01*
X55653Y-824712D01*
X55261Y-824187D01*
X54556Y-823872D01*
X53851Y-823977D01*
X53146Y-824397D01*
G01X58820Y-828912D02*
X59290Y-829647D01*
X59916Y-830067D01*
X60621Y-830172D01*
X61248Y-830067D01*
X61875Y-829542D01*
X62266Y-828912D01*
X62345Y-828282D01*
X62188Y-827547D01*
X61640Y-827022D01*
X61091Y-826812D01*
X60386D01*
G01X61091D02*
X61561Y-826497D01*
X61953Y-825972D01*
X62110Y-825342D01*
X61953Y-824712D01*
X61561Y-824187D01*
X60856Y-823872D01*
X60151Y-823977D01*
X59446Y-824397D01*
G01X66686Y-830172D02*
X66843Y-828807D01*
X67078Y-827652D01*
X67391Y-826602D01*
X67783Y-825447D01*
X68410Y-823872D01*
X65276D01*
G01X72986Y-830172D02*
X73143Y-828807D01*
X73378Y-827652D01*
X73691Y-826602D01*
X74083Y-825447D01*
X74710Y-823872D01*
X71576D01*
G01X79286Y-831327D02*
X79600Y-829962D01*
G01X85743Y-823872D02*
Y-830172D01*
G01X83941Y-823872D02*
X87545D01*
G01X90085Y-830172D02*
X92043Y-823872D01*
X94001Y-830172D01*
G01X93296Y-827967D02*
X90790D01*
G01X97403Y-823872D02*
X99283D01*
G01X98343D02*
Y-830172D01*
G01X97403D02*
X99283D01*
G01X102293Y-823872D02*
X103390Y-830172D01*
X104643Y-823872D01*
X105896Y-830172D01*
X106993Y-823872D01*
G01X108985Y-830172D02*
X110943Y-823872D01*
X112901Y-830172D01*
G01X112196Y-827967D02*
X109690D01*
G01X115441Y-830172D02*
Y-823872D01*
X119045Y-830172D01*
Y-823872D01*
G01X129451Y-832272D02*
X128668Y-831222D01*
X128276Y-830172D01*
Y-825972D01*
X128668Y-824922D01*
X129451Y-823872D01*
G01X140876Y-830172D02*
Y-823872D01*
X142835D01*
X143461Y-824187D01*
X143853Y-824607D01*
X144010Y-825447D01*
X143853Y-826287D01*
X143383Y-826812D01*
X142835Y-827127D01*
X140876D01*
G01X142835D02*
X144010Y-830172D01*
G01X148743Y-830382D02*
X148586Y-830277D01*
Y-830067D01*
X148743Y-829962D01*
X148900Y-830067D01*
Y-830277D01*
X148743Y-830382D01*
G01X155043Y-830172D02*
X154416Y-830067D01*
X153868Y-829647D01*
X153398Y-829017D01*
X153085Y-828282D01*
X152928Y-827442D01*
Y-826602D01*
X153085Y-825762D01*
X153398Y-825027D01*
X153868Y-824397D01*
X154416Y-823977D01*
X155043Y-823872D01*
X155670Y-823977D01*
X156218Y-824397D01*
X156688Y-825027D01*
X157001Y-825762D01*
X157158Y-826602D01*
Y-827442D01*
X157001Y-828282D01*
X156688Y-829017D01*
X156218Y-829647D01*
X155670Y-830067D01*
X155043Y-830172D01*
G01X161343Y-830382D02*
X161186Y-830277D01*
Y-830067D01*
X161343Y-829962D01*
X161500Y-830067D01*
Y-830277D01*
X161343Y-830382D01*
G01X169366Y-824397D02*
X168896Y-824082D01*
X168348Y-823872D01*
X167721D01*
X167016Y-824187D01*
X166468Y-824712D01*
X166076Y-825342D01*
X165763Y-826392D01*
X165685Y-827337D01*
X165841Y-828282D01*
X166076Y-828912D01*
X166546Y-829542D01*
X167095Y-829962D01*
X167643Y-830172D01*
X168191D01*
X168740Y-829962D01*
X169210Y-829647D01*
X169601Y-829227D01*
G01X173943Y-830382D02*
X173786Y-830277D01*
Y-830067D01*
X173943Y-829962D01*
X174100Y-830067D01*
Y-830277D01*
X173943Y-830382D01*
G01X180635Y-832272D02*
X181418Y-831222D01*
X181810Y-830172D01*
Y-825972D01*
X181418Y-824922D01*
X180635Y-823872D01*
G01X38743Y-799472D02*
X36223Y-799055D01*
X34018Y-797389D01*
X32128Y-794889D01*
X30868Y-791972D01*
X30238Y-788639D01*
Y-785305D01*
X30868Y-781972D01*
X32128Y-779055D01*
X34018Y-776556D01*
X36223Y-774889D01*
X38743Y-774472D01*
X41263Y-774889D01*
X43468Y-776556D01*
X45358Y-779055D01*
X46618Y-781972D01*
X47248Y-785305D01*
Y-788639D01*
X46618Y-791972D01*
X45358Y-794889D01*
X43468Y-797389D01*
X41263Y-799055D01*
X38743Y-799472D01*
G01X41263Y-792805D02*
X45043Y-799472D01*
G01X58588Y-782806D02*
Y-794472D01*
X59848Y-797389D01*
X61738Y-799055D01*
X63943Y-799472D01*
X66148Y-799055D01*
X68038Y-797389D01*
X69298Y-794472D01*
G01Y-799472D02*
Y-782806D01*
G01X94813Y-799472D02*
Y-782806D01*
G01Y-785722D02*
X93553Y-784056D01*
X91663Y-783222D01*
X89458Y-782806D01*
X87253Y-783639D01*
X85363Y-785305D01*
X84103Y-787806D01*
X83473Y-791139D01*
X84103Y-794472D01*
X85363Y-796973D01*
X87253Y-798639D01*
X89458Y-799472D01*
X91663Y-799055D01*
X93553Y-797806D01*
X94813Y-796139D01*
G01X108988Y-799472D02*
Y-782806D01*
G01Y-786972D02*
X110248Y-784889D01*
X112138Y-783222D01*
X114658Y-782806D01*
X116863Y-783222D01*
X118753Y-784889D01*
X119698Y-787806D01*
Y-799472D01*
G01X139543Y-774472D02*
Y-799472D01*
G01X135133Y-782806D02*
X143953D01*
G01X170413Y-799472D02*
Y-782806D01*
G01Y-785722D02*
X169153Y-784056D01*
X167263Y-783222D01*
X165058Y-782806D01*
X162853Y-783639D01*
X160963Y-785305D01*
X159703Y-787806D01*
X159073Y-791139D01*
X159703Y-794472D01*
X160963Y-796973D01*
X162853Y-798639D01*
X165058Y-799472D01*
X167263Y-799055D01*
X169153Y-797806D01*
X170413Y-796139D01*
G01X14641Y-810172D02*
Y-803872D01*
X18245Y-810172D01*
Y-803872D01*
G01X22743Y-810172D02*
X22116Y-810067D01*
X21568Y-809647D01*
X21098Y-809017D01*
X20785Y-808282D01*
X20628Y-807442D01*
Y-806602D01*
X20785Y-805762D01*
X21098Y-805027D01*
X21568Y-804397D01*
X22116Y-803977D01*
X22743Y-803872D01*
X23370Y-803977D01*
X23918Y-804397D01*
X24388Y-805027D01*
X24701Y-805762D01*
X24858Y-806602D01*
Y-807442D01*
X24701Y-808282D01*
X24388Y-809017D01*
X23918Y-809647D01*
X23370Y-810067D01*
X22743Y-810172D01*
G01X29043Y-810382D02*
X28886Y-810277D01*
Y-810067D01*
X29043Y-809962D01*
X29200Y-810067D01*
Y-810277D01*
X29043Y-810382D01*
G01X33855Y-804922D02*
X34325Y-804292D01*
X34873Y-803977D01*
X35500Y-803872D01*
X36283Y-804082D01*
X36831Y-804607D01*
X36988Y-805237D01*
X36910Y-805867D01*
X36596Y-806392D01*
X35030Y-807442D01*
X34325Y-808177D01*
X33855Y-809227D01*
X33698Y-810172D01*
X36988D01*
G01X41643D02*
Y-803872D01*
X40703Y-805132D01*
G01Y-810172D02*
X42583D01*
G01X47943D02*
Y-803872D01*
X47003Y-805132D01*
G01Y-810172D02*
X48883D01*
G01X54086Y-811327D02*
X54400Y-809962D01*
G01X58193Y-803872D02*
X59290Y-810172D01*
X60543Y-803872D01*
X61796Y-810172D01*
X62893Y-803872D01*
G01X68410Y-810172D02*
X65276D01*
Y-803872D01*
X68410D01*
G01X67156Y-806917D02*
X65276D01*
G01X71341Y-810172D02*
Y-803872D01*
X74945Y-810172D01*
Y-803872D01*
G01X77798Y-810172D02*
Y-803872D01*
G01X81088D02*
Y-810172D01*
G01Y-807022D02*
X77798D01*
G01X84020Y-803872D02*
Y-808387D01*
X84333Y-809332D01*
X84960Y-809962D01*
X85743Y-810172D01*
X86526Y-809962D01*
X87153Y-809332D01*
X87466Y-808387D01*
Y-803872D01*
G01X90085Y-810172D02*
X92043Y-803872D01*
X94001Y-810172D01*
G01X93296Y-807967D02*
X90790D01*
G01X103155Y-804922D02*
X103625Y-804292D01*
X104173Y-803977D01*
X104800Y-803872D01*
X105583Y-804082D01*
X106131Y-804607D01*
X106288Y-805237D01*
X106210Y-805867D01*
X105896Y-806392D01*
X104330Y-807442D01*
X103625Y-808177D01*
X103155Y-809227D01*
X102998Y-810172D01*
X106288D01*
G01X109141D02*
Y-803872D01*
X112745Y-810172D01*
Y-803872D01*
G01X115520Y-810172D02*
Y-803872D01*
X117086D01*
X117713Y-804187D01*
X118183Y-804607D01*
X118575Y-805237D01*
X118888Y-805972D01*
X118966Y-807022D01*
X118888Y-808072D01*
X118575Y-808807D01*
X118183Y-809437D01*
X117713Y-809857D01*
X117086Y-810172D01*
X115520D01*
G01X128276D02*
Y-803872D01*
X130235D01*
X130861Y-804187D01*
X131253Y-804607D01*
X131410Y-805447D01*
X131253Y-806287D01*
X130783Y-806812D01*
X130235Y-807127D01*
X128276D01*
G01X130235D02*
X131410Y-810172D01*
G01X134420D02*
Y-803872D01*
X135986D01*
X136613Y-804187D01*
X137083Y-804607D01*
X137475Y-805237D01*
X137788Y-805972D01*
X137866Y-807022D01*
X137788Y-808072D01*
X137475Y-808807D01*
X137083Y-809437D01*
X136613Y-809857D01*
X135986Y-810172D01*
X134420D01*
G01X142443Y-810382D02*
X142286Y-810277D01*
Y-810067D01*
X142443Y-809962D01*
X142600Y-810067D01*
Y-810277D01*
X142443Y-810382D01*
G01X50617Y623168D02*
Y620068D01*
X49697D01*
X49390Y620223D01*
X49160Y620585D01*
X49083Y620998D01*
X49160Y621411D01*
X49352Y621721D01*
X49697Y621876D01*
X50617D01*
G01X45907Y620326D02*
X46137Y620171D01*
X46405Y620068D01*
X46712D01*
X47057Y620223D01*
X47325Y620481D01*
X47517Y620791D01*
X47670Y621308D01*
X47708Y621773D01*
X47632Y622238D01*
X47517Y622548D01*
X47287Y622858D01*
X47018Y623065D01*
X46750Y623168D01*
X46482D01*
X46213Y623065D01*
X45983Y622910D01*
X45792Y622703D01*
G01X43343Y621515D02*
X43190Y621360D01*
X43075Y621101D01*
X42998Y620740D01*
X43075Y620430D01*
X43228Y620223D01*
X43497Y620068D01*
X44532D01*
Y623168D01*
X43267D01*
X42998Y622961D01*
X42845Y622651D01*
X42768Y622290D01*
X42845Y621928D01*
X43075Y621618D01*
X43343Y621515D01*
X44532D01*
G01X38408Y620068D02*
X37450Y623168D01*
X36492Y620068D01*
G01X33583Y623168D02*
X35117D01*
Y620068D01*
X33583D01*
G01X34197Y621566D02*
X35117D01*
G01X32132Y623168D02*
Y620068D01*
X30368Y623168D01*
Y620068D01*
G01X28993Y623168D02*
Y620068D01*
X28227D01*
X27920Y620223D01*
X27690Y620430D01*
X27498Y620740D01*
X27345Y621101D01*
X27307Y621618D01*
X27345Y622135D01*
X27498Y622496D01*
X27690Y622806D01*
X27920Y623013D01*
X28227Y623168D01*
X28993D01*
G01X25050D02*
X25357Y623116D01*
X25625Y622910D01*
X25855Y622600D01*
X26008Y622238D01*
X26085Y621825D01*
Y621411D01*
X26008Y620998D01*
X25855Y620636D01*
X25625Y620326D01*
X25357Y620120D01*
X25050Y620068D01*
X24743Y620120D01*
X24475Y620326D01*
X24245Y620636D01*
X24092Y620998D01*
X24015Y621411D01*
Y621825D01*
X24092Y622238D01*
X24245Y622600D01*
X24475Y622910D01*
X24743Y623116D01*
X25050Y623168D01*
G01X22717D02*
Y620068D01*
X21758D01*
X21452Y620223D01*
X21260Y620430D01*
X21183Y620843D01*
X21260Y621256D01*
X21490Y621515D01*
X21758Y621670D01*
X22717D01*
G01X21758D02*
X21183Y623168D01*
G01X42217Y625468D02*
Y628568D01*
X40683D01*
G01X38350D02*
X38657Y628516D01*
X38925Y628310D01*
X39155Y628000D01*
X39308Y627638D01*
X39385Y627225D01*
Y626811D01*
X39308Y626398D01*
X39155Y626036D01*
X38925Y625726D01*
X38657Y625520D01*
X38350Y625468D01*
X38043Y625520D01*
X37775Y625726D01*
X37545Y626036D01*
X37392Y626398D01*
X37315Y626811D01*
Y627225D01*
X37392Y627638D01*
X37545Y628000D01*
X37775Y628310D01*
X38043Y628516D01*
X38350Y628568D01*
G01X35020Y627018D02*
X34253D01*
Y627948D01*
X34483Y628258D01*
X34752Y628465D01*
X35135Y628568D01*
X35518Y628465D01*
X35787Y628258D01*
X36017Y627948D01*
X36170Y627586D01*
X36247Y627173D01*
Y626811D01*
X36170Y626501D01*
X36017Y626140D01*
X35787Y625830D01*
X35557Y625623D01*
X35250Y625468D01*
X34982D01*
X34675Y625571D01*
X34445Y625778D01*
G01X32150Y628568D02*
X32457Y628516D01*
X32725Y628310D01*
X32955Y628000D01*
X33108Y627638D01*
X33185Y627225D01*
Y626811D01*
X33108Y626398D01*
X32955Y626036D01*
X32725Y625726D01*
X32457Y625520D01*
X32150Y625468D01*
X31843Y625520D01*
X31575Y625726D01*
X31345Y626036D01*
X31192Y626398D01*
X31115Y626811D01*
Y627225D01*
X31192Y627638D01*
X31345Y628000D01*
X31575Y628310D01*
X31843Y628516D01*
X32150Y628568D01*
G01X38850Y702050D02*
X26350D01*
X28850Y700190D01*
G01X38850D02*
Y703910D01*
G01X36975Y711040D02*
X38017Y711970D01*
X38642Y713055D01*
X38850Y714450D01*
X38433Y715845D01*
X37600Y716930D01*
X36142Y717705D01*
X34475Y717860D01*
X32808Y717550D01*
X31767Y716775D01*
X30933Y715690D01*
X30725Y714605D01*
X30933Y713520D01*
X31767Y712125D01*
X26350Y712590D01*
Y716775D01*
G01X39267Y726850D02*
X39058Y726540D01*
X38642D01*
X38433Y726850D01*
X38642Y727160D01*
X39058D01*
X39267Y726850D01*
G01X38850Y741110D02*
X26350D01*
X35308Y735375D01*
Y743125D01*
G01X48850Y-105500D02*
X36350D01*
X38850Y-107360D01*
G01X48850D02*
Y-103640D01*
G01X47392Y-95735D02*
X48433Y-94650D01*
X48850Y-93410D01*
X48433Y-92170D01*
X47184Y-91085D01*
X45308Y-90310D01*
X43433Y-90000D01*
X41142D01*
X39267Y-90310D01*
X37600Y-91085D01*
X36767Y-92015D01*
X36350Y-93100D01*
X36767Y-94340D01*
X37600Y-95270D01*
X38850Y-95890D01*
X40517Y-96200D01*
X41975Y-95890D01*
X43433Y-95115D01*
X44267Y-94185D01*
X44475Y-93100D01*
X44059Y-91860D01*
X43017Y-90930D01*
X41142Y-90000D01*
G01X47392Y-83335D02*
X48433Y-82250D01*
X48850Y-81010D01*
X48433Y-79770D01*
X47184Y-78685D01*
X45308Y-77910D01*
X43433Y-77600D01*
X41142D01*
X39267Y-77910D01*
X37600Y-78685D01*
X36767Y-79615D01*
X36350Y-80700D01*
X36767Y-81940D01*
X37600Y-82870D01*
X38850Y-83490D01*
X40517Y-83800D01*
X41975Y-83490D01*
X43433Y-82715D01*
X44267Y-81785D01*
X44475Y-80700D01*
X44059Y-79460D01*
X43017Y-78530D01*
X41142Y-77600D01*
G01X49267Y-68300D02*
X49058Y-68610D01*
X48642D01*
X48433Y-68300D01*
X48642Y-67990D01*
X49058D01*
X49267Y-68300D01*
G01X38433Y-58845D02*
X37184Y-57915D01*
X36558Y-56830D01*
X36350Y-55590D01*
X36767Y-54040D01*
X37808Y-52955D01*
X39058Y-52645D01*
X40309Y-52800D01*
X41350Y-53420D01*
X43433Y-56520D01*
X44892Y-57915D01*
X46975Y-58845D01*
X48850Y-59155D01*
Y-52645D01*
G01X38433Y-46445D02*
X37184Y-45515D01*
X36558Y-44430D01*
X36350Y-43190D01*
X36767Y-41640D01*
X37808Y-40555D01*
X39058Y-40245D01*
X40309Y-40400D01*
X41350Y-41020D01*
X43433Y-44120D01*
X44892Y-45515D01*
X46975Y-46445D01*
X48850Y-46755D01*
Y-40245D01*
G01X71975Y-96360D02*
X73017Y-95430D01*
X73642Y-94345D01*
X73850Y-92950D01*
X73433Y-91555D01*
X72600Y-90470D01*
X71142Y-89695D01*
X69475Y-89540D01*
X67808Y-89850D01*
X66767Y-90625D01*
X65933Y-91710D01*
X65725Y-92795D01*
X65933Y-93880D01*
X66767Y-95275D01*
X61350Y-94810D01*
Y-90625D01*
G01X74267Y-80550D02*
X74058Y-80860D01*
X73642D01*
X73433Y-80550D01*
X73642Y-80240D01*
X74058D01*
X74267Y-80550D01*
G01X61350Y-68150D02*
X61767Y-69390D01*
X62808Y-70320D01*
X64058Y-70940D01*
X65725Y-71405D01*
X67600Y-71560D01*
X69475Y-71405D01*
X71142Y-70940D01*
X72392Y-70320D01*
X73433Y-69390D01*
X73850Y-68150D01*
X73433Y-66910D01*
X72392Y-65980D01*
X71142Y-65360D01*
X69475Y-64895D01*
X67600Y-64740D01*
X65725Y-64895D01*
X64058Y-65360D01*
X62808Y-65980D01*
X61767Y-66910D01*
X61350Y-68150D01*
G01X68642Y-58695D02*
X67183Y-57610D01*
X66350Y-56680D01*
X65933Y-55440D01*
X66350Y-54355D01*
X67183Y-53580D01*
X68433Y-52960D01*
X69892Y-52805D01*
X71142Y-52960D01*
X72392Y-53580D01*
X73433Y-54510D01*
X73850Y-55595D01*
X73433Y-56835D01*
X72184Y-57920D01*
X70308Y-58540D01*
X68225Y-58695D01*
X65517Y-58385D01*
X64058Y-57920D01*
X62600Y-57145D01*
X61558Y-56060D01*
X61350Y-54975D01*
X61767Y-53890D01*
X62808Y-53115D01*
G01X63850Y689350D02*
X63642Y690435D01*
X63017Y691675D01*
X61975Y692450D01*
X60517Y692760D01*
X59059Y692450D01*
X57808Y691520D01*
X57183Y690125D01*
Y688575D01*
X56767Y687645D01*
X55725Y686870D01*
X54267Y686560D01*
X52808Y687025D01*
X51767Y688110D01*
X51350Y689350D01*
X51767Y690590D01*
X52808Y691675D01*
X54267Y692140D01*
X55725Y691830D01*
X56767Y691055D01*
X57183Y690125D01*
Y688575D01*
X57808Y687180D01*
X59059Y686250D01*
X60517Y685940D01*
X61975Y686250D01*
X63017Y687025D01*
X63642Y688265D01*
X63850Y689350D01*
G01X53433Y698805D02*
X52184Y699735D01*
X51558Y700820D01*
X51350Y702060D01*
X51767Y703610D01*
X52808Y704695D01*
X54058Y705005D01*
X55309Y704850D01*
X56350Y704230D01*
X58433Y701130D01*
X59892Y699735D01*
X61975Y698805D01*
X63850Y698495D01*
Y705005D01*
G01Y713840D02*
X61142Y714150D01*
X58850Y714615D01*
X56767Y715235D01*
X54475Y716010D01*
X51350Y717250D01*
Y711050D01*
G01X64267Y726550D02*
X64058Y726240D01*
X63642D01*
X63433Y726550D01*
X63642Y726860D01*
X64058D01*
X64267Y726550D01*
G01X62392Y736315D02*
X63433Y737400D01*
X63850Y738640D01*
X63433Y739880D01*
X62184Y740965D01*
X60308Y741740D01*
X58433Y742050D01*
X56142D01*
X54267Y741740D01*
X52600Y740965D01*
X51767Y740035D01*
X51350Y738950D01*
X51767Y737710D01*
X52600Y736780D01*
X53850Y736160D01*
X55517Y735850D01*
X56975Y736160D01*
X58433Y736935D01*
X59267Y737865D01*
X59475Y738950D01*
X59059Y740190D01*
X58017Y741120D01*
X56142Y742050D01*
G01X61975Y747940D02*
X63017Y748870D01*
X63642Y749955D01*
X63850Y751350D01*
X63433Y752745D01*
X62600Y753830D01*
X61142Y754605D01*
X59475Y754760D01*
X57808Y754450D01*
X56767Y753675D01*
X55933Y752590D01*
X55725Y751505D01*
X55933Y750420D01*
X56767Y749025D01*
X51350Y749490D01*
Y753675D01*
G01X78433Y692755D02*
X77184Y693685D01*
X76558Y694770D01*
X76350Y696010D01*
X76767Y697560D01*
X77808Y698645D01*
X79058Y698955D01*
X80309Y698800D01*
X81350Y698180D01*
X83433Y695080D01*
X84892Y693685D01*
X86975Y692755D01*
X88850Y692445D01*
Y698955D01*
G01Y708100D02*
X76350D01*
X78850Y706240D01*
G01X88850D02*
Y709960D01*
G01X89267Y720500D02*
X89058Y720190D01*
X88642D01*
X88433Y720500D01*
X88642Y720810D01*
X89058D01*
X89267Y720500D01*
G01X76350Y732900D02*
X76767Y731660D01*
X77808Y730730D01*
X79058Y730110D01*
X80725Y729645D01*
X82600Y729490D01*
X84475Y729645D01*
X86142Y730110D01*
X87392Y730730D01*
X88433Y731660D01*
X88850Y732900D01*
X88433Y734140D01*
X87392Y735070D01*
X86142Y735690D01*
X84475Y736155D01*
X82600Y736310D01*
X80725Y736155D01*
X79058Y735690D01*
X77808Y735070D01*
X76767Y734140D01*
X76350Y732900D01*
G01X86350Y741890D02*
X87809Y742820D01*
X88642Y744060D01*
X88850Y745455D01*
X88642Y746695D01*
X87600Y747935D01*
X86350Y748710D01*
X85100Y748865D01*
X83642Y748555D01*
X82600Y747470D01*
X82183Y746385D01*
Y744990D01*
G01Y746385D02*
X81558Y747315D01*
X80517Y748090D01*
X79267Y748400D01*
X78017Y748090D01*
X76975Y747315D01*
X76350Y745920D01*
X76558Y744525D01*
X77392Y743130D01*
G01X123850Y-58867D02*
X116350D01*
Y-56627D01*
X116725Y-55880D01*
X117600Y-55320D01*
X118600Y-55133D01*
X119600Y-55320D01*
X120350Y-55787D01*
X120725Y-56627D01*
Y-58867D01*
G01X116350Y-49500D02*
X123850D01*
G01X116350Y-51647D02*
Y-47353D01*
G01X123850Y-43960D02*
X116350D01*
G01Y-40040D02*
X123850D01*
G01X120100D02*
Y-43960D01*
G01X113850Y683300D02*
X101350D01*
X103850Y681440D01*
G01X113850D02*
Y685160D01*
G01X101350Y695700D02*
X101767Y694460D01*
X102808Y693530D01*
X104058Y692910D01*
X105725Y692445D01*
X107600Y692290D01*
X109475Y692445D01*
X111142Y692910D01*
X112392Y693530D01*
X113433Y694460D01*
X113850Y695700D01*
X113433Y696940D01*
X112392Y697870D01*
X111142Y698490D01*
X109475Y698955D01*
X107600Y699110D01*
X105725Y698955D01*
X104058Y698490D01*
X102808Y697870D01*
X101767Y696940D01*
X101350Y695700D01*
G01X113850Y708100D02*
X113642Y709185D01*
X113017Y710425D01*
X111975Y711200D01*
X110517Y711510D01*
X109059Y711200D01*
X107808Y710270D01*
X107183Y708875D01*
Y707325D01*
X106767Y706395D01*
X105725Y705620D01*
X104267Y705310D01*
X102808Y705775D01*
X101767Y706860D01*
X101350Y708100D01*
X101767Y709340D01*
X102808Y710425D01*
X104267Y710890D01*
X105725Y710580D01*
X106767Y709805D01*
X107183Y708875D01*
Y707325D01*
X107808Y705930D01*
X109059Y705000D01*
X110517Y704690D01*
X111975Y705000D01*
X113017Y705775D01*
X113642Y707015D01*
X113850Y708100D01*
G01Y720500D02*
X113642Y721585D01*
X113017Y722825D01*
X111975Y723600D01*
X110517Y723910D01*
X109059Y723600D01*
X107808Y722670D01*
X107183Y721275D01*
Y719725D01*
X106767Y718795D01*
X105725Y718020D01*
X104267Y717710D01*
X102808Y718175D01*
X101767Y719260D01*
X101350Y720500D01*
X101767Y721740D01*
X102808Y722825D01*
X104267Y723290D01*
X105725Y722980D01*
X106767Y722205D01*
X107183Y721275D01*
Y719725D01*
X107808Y718330D01*
X109059Y717400D01*
X110517Y717090D01*
X111975Y717400D01*
X113017Y718175D01*
X113642Y719415D01*
X113850Y720500D01*
G01X114267Y732900D02*
X114058Y732590D01*
X113642D01*
X113433Y732900D01*
X113642Y733210D01*
X114058D01*
X114267Y732900D01*
G01X111975Y741890D02*
X113017Y742820D01*
X113642Y743905D01*
X113850Y745300D01*
X113433Y746695D01*
X112600Y747780D01*
X111142Y748555D01*
X109475Y748710D01*
X107808Y748400D01*
X106767Y747625D01*
X105933Y746540D01*
X105725Y745455D01*
X105933Y744370D01*
X106767Y742975D01*
X101350Y743440D01*
Y747625D01*
G01X113850Y757700D02*
X113642Y758785D01*
X113017Y760025D01*
X111975Y760800D01*
X110517Y761110D01*
X109059Y760800D01*
X107808Y759870D01*
X107183Y758475D01*
Y756925D01*
X106767Y755995D01*
X105725Y755220D01*
X104267Y754910D01*
X102808Y755375D01*
X101767Y756460D01*
X101350Y757700D01*
X101767Y758940D01*
X102808Y760025D01*
X104267Y760490D01*
X105725Y760180D01*
X106767Y759405D01*
X107183Y758475D01*
Y756925D01*
X107808Y755530D01*
X109059Y754600D01*
X110517Y754290D01*
X111975Y754600D01*
X113017Y755375D01*
X113642Y756615D01*
X113850Y757700D01*
G01X128433Y692905D02*
X127184Y693835D01*
X126558Y694920D01*
X126350Y696160D01*
X126767Y697710D01*
X127808Y698795D01*
X129058Y699105D01*
X130309Y698950D01*
X131350Y698330D01*
X133433Y695230D01*
X134892Y693835D01*
X136975Y692905D01*
X138850Y692595D01*
Y699105D01*
G01Y707940D02*
X136142Y708250D01*
X133850Y708715D01*
X131767Y709335D01*
X129475Y710110D01*
X126350Y711350D01*
Y705150D01*
G01X139267Y720650D02*
X139058Y720340D01*
X138642D01*
X138433Y720650D01*
X138642Y720960D01*
X139058D01*
X139267Y720650D01*
G01X133642Y730105D02*
X132183Y731190D01*
X131350Y732120D01*
X130933Y733360D01*
X131350Y734445D01*
X132183Y735220D01*
X133433Y735840D01*
X134892Y735995D01*
X136142Y735840D01*
X137392Y735220D01*
X138433Y734290D01*
X138850Y733205D01*
X138433Y731965D01*
X137184Y730880D01*
X135308Y730260D01*
X133225Y730105D01*
X130517Y730415D01*
X129058Y730880D01*
X127600Y731655D01*
X126558Y732740D01*
X126350Y733825D01*
X126767Y734910D01*
X127808Y735685D01*
G01X136975Y742040D02*
X138017Y742970D01*
X138642Y744055D01*
X138850Y745450D01*
X138433Y746845D01*
X137600Y747930D01*
X136142Y748705D01*
X134475Y748860D01*
X132808Y748550D01*
X131767Y747775D01*
X130933Y746690D01*
X130725Y745605D01*
X130933Y744520D01*
X131767Y743125D01*
X126350Y743590D01*
Y747775D01*
G01X163850Y683300D02*
X151350D01*
X153850Y681440D01*
G01X163850D02*
Y685160D01*
G01Y695700D02*
X151350D01*
X153850Y693840D01*
G01X163850D02*
Y697560D01*
G01Y708100D02*
X163642Y709185D01*
X163017Y710425D01*
X161975Y711200D01*
X160517Y711510D01*
X159059Y711200D01*
X157808Y710270D01*
X157183Y708875D01*
Y707325D01*
X156767Y706395D01*
X155725Y705620D01*
X154267Y705310D01*
X152808Y705775D01*
X151767Y706860D01*
X151350Y708100D01*
X151767Y709340D01*
X152808Y710425D01*
X154267Y710890D01*
X155725Y710580D01*
X156767Y709805D01*
X157183Y708875D01*
Y707325D01*
X157808Y705930D01*
X159059Y705000D01*
X160517Y704690D01*
X161975Y705000D01*
X163017Y705775D01*
X163642Y707015D01*
X163850Y708100D01*
G01Y720500D02*
X151350D01*
X153850Y718640D01*
G01X163850D02*
Y722360D01*
G01X164267Y732900D02*
X164058Y732590D01*
X163642D01*
X163433Y732900D01*
X163642Y733210D01*
X164058D01*
X164267Y732900D01*
G01X163850Y745300D02*
X151350D01*
X153850Y743440D01*
G01X163850D02*
Y747160D01*
G01Y757700D02*
X151350D01*
X153850Y755840D01*
G01X163850D02*
Y759560D01*
G01X186350Y711040D02*
X187809Y711970D01*
X188642Y713210D01*
X188850Y714605D01*
X188642Y715845D01*
X187600Y717085D01*
X186350Y717860D01*
X185100Y718015D01*
X183642Y717705D01*
X182600Y716620D01*
X182183Y715535D01*
Y714140D01*
G01Y715535D02*
X181558Y716465D01*
X180517Y717240D01*
X179267Y717550D01*
X178017Y717240D01*
X176975Y716465D01*
X176350Y715070D01*
X176558Y713675D01*
X177392Y712280D01*
G01X176350Y726850D02*
X176767Y725610D01*
X177808Y724680D01*
X179058Y724060D01*
X180725Y723595D01*
X182600Y723440D01*
X184475Y723595D01*
X186142Y724060D01*
X187392Y724680D01*
X188433Y725610D01*
X188850Y726850D01*
X188433Y728090D01*
X187392Y729020D01*
X186142Y729640D01*
X184475Y730105D01*
X182600Y730260D01*
X180725Y730105D01*
X179058Y729640D01*
X177808Y729020D01*
X176767Y728090D01*
X176350Y726850D01*
G01X210093Y-779172D02*
Y-787172D01*
X214093D01*
G01X221893D02*
Y-781839D01*
G01Y-782772D02*
X221493Y-782239D01*
X220893Y-781972D01*
X220193Y-781839D01*
X219493Y-782105D01*
X218893Y-782639D01*
X218493Y-783439D01*
X218293Y-784505D01*
X218493Y-785572D01*
X218893Y-786372D01*
X219493Y-786905D01*
X220193Y-787172D01*
X220893Y-787039D01*
X221493Y-786639D01*
X221893Y-786106D01*
G01X225993Y-789572D02*
X226593Y-789839D01*
X227393Y-789572D01*
X227893Y-789039D01*
X228293Y-788372D01*
X228893Y-786239D01*
X230193Y-781839D01*
G01X226993D02*
X228893Y-786239D01*
G01X234593Y-783572D02*
X237793D01*
X237493Y-782639D01*
X236993Y-782105D01*
X236293Y-781839D01*
X235593Y-781972D01*
X234993Y-782372D01*
X234593Y-783305D01*
X234393Y-784106D01*
Y-784905D01*
X234593Y-785705D01*
X235093Y-786505D01*
X235693Y-787039D01*
X236393Y-787172D01*
X237093Y-786905D01*
X237793Y-786106D01*
G01X242693Y-787172D02*
Y-781839D01*
G01Y-782905D02*
X243193Y-782372D01*
X243693Y-781972D01*
X244393Y-781839D01*
X244893Y-781972D01*
X245493Y-782372D01*
G01X203850Y616133D02*
X196350D01*
Y618373D01*
X196725Y619120D01*
X197600Y619680D01*
X198600Y619867D01*
X199600Y619680D01*
X200350Y619213D01*
X200725Y618373D01*
Y616133D01*
G01X196350Y625500D02*
X203850D01*
G01X196350Y623353D02*
Y627647D01*
G01X203850Y631040D02*
X196350D01*
G01Y634960D02*
X203850D01*
G01X200100D02*
Y631040D01*
G01X229193Y-829172D02*
X232993D01*
X229193Y-837172D01*
X232993D01*
G01X239093Y-831839D02*
Y-837172D01*
G01Y-829705D02*
X238893Y-829572D01*
Y-829305D01*
X239093Y-829172D01*
X239293Y-829305D01*
Y-829572D01*
X239093Y-829705D01*
G01X245793Y-834505D02*
X248393D01*
G01X253093Y-837172D02*
Y-829172D01*
X255493D01*
X256293Y-829572D01*
X256893Y-830505D01*
X257093Y-831572D01*
X256893Y-832639D01*
X256393Y-833439D01*
X255493Y-833839D01*
X253093D01*
G01X263093Y-831839D02*
Y-837172D01*
G01Y-829705D02*
X262893Y-829572D01*
Y-829305D01*
X263093Y-829172D01*
X263293Y-829305D01*
Y-829572D01*
X263093Y-829705D01*
G01X269393Y-837172D02*
Y-831839D01*
G01Y-833172D02*
X269793Y-832505D01*
X270393Y-831972D01*
X271193Y-831839D01*
X271893Y-831972D01*
X272493Y-832505D01*
X272793Y-833439D01*
Y-837172D01*
G01X277693Y-839172D02*
X278393Y-839705D01*
X279193Y-839839D01*
X279893Y-839705D01*
X280493Y-839039D01*
X280893Y-838105D01*
Y-831839D01*
G01Y-832905D02*
X280493Y-832372D01*
X279893Y-831972D01*
X279193Y-831839D01*
X278393Y-832105D01*
X277893Y-832639D01*
X277493Y-833572D01*
X277293Y-834505D01*
X277393Y-835305D01*
X277793Y-836239D01*
X278393Y-836905D01*
X279193Y-837172D01*
X279793Y-837039D01*
X280493Y-836505D01*
X280893Y-835972D01*
G01X234193Y-812172D02*
Y-804172D01*
X237993D01*
G01X236593Y-808039D02*
X234193D01*
G01X241593Y-812172D02*
X244093Y-804172D01*
X246593Y-812172D01*
G01X245693Y-809372D02*
X242493D01*
G01X252893Y-807905D02*
X253293Y-807505D01*
X253593Y-806839D01*
X253793Y-805905D01*
X253593Y-805105D01*
X253193Y-804572D01*
X252493Y-804172D01*
X249793D01*
Y-812172D01*
X253093D01*
X253793Y-811639D01*
X254193Y-810839D01*
X254393Y-809905D01*
X254193Y-808972D01*
X253593Y-808172D01*
X252893Y-807905D01*
X249793D01*
G01X232585Y-115145D02*
X231336Y-114215D01*
X230710Y-113130D01*
X230502Y-111890D01*
X230919Y-110340D01*
X231960Y-109255D01*
X233210Y-108945D01*
X234461Y-109100D01*
X235502Y-109720D01*
X237585Y-112820D01*
X239044Y-114215D01*
X241127Y-115145D01*
X243002Y-115455D01*
Y-108945D01*
G01Y-97940D02*
X230502D01*
X239460Y-103675D01*
Y-95925D01*
G01X241544Y-90035D02*
X242585Y-88950D01*
X243002Y-87710D01*
X242585Y-86470D01*
X241336Y-85385D01*
X239460Y-84610D01*
X237585Y-84300D01*
X235294D01*
X233419Y-84610D01*
X231752Y-85385D01*
X230919Y-86315D01*
X230502Y-87400D01*
X230919Y-88640D01*
X231752Y-89570D01*
X233002Y-90190D01*
X234669Y-90500D01*
X236127Y-90190D01*
X237585Y-89415D01*
X238419Y-88485D01*
X238627Y-87400D01*
X238211Y-86160D01*
X237169Y-85230D01*
X235294Y-84300D01*
G01X232585Y-77945D02*
X231336Y-77015D01*
X230710Y-75930D01*
X230502Y-74690D01*
X230919Y-73140D01*
X231960Y-72055D01*
X233210Y-71745D01*
X234461Y-71900D01*
X235502Y-72520D01*
X237585Y-75620D01*
X239044Y-77015D01*
X241127Y-77945D01*
X243002Y-78255D01*
Y-71745D01*
G01X243419Y-62600D02*
X243210Y-62910D01*
X242794D01*
X242585Y-62600D01*
X242794Y-62290D01*
X243210D01*
X243419Y-62600D01*
G01X241127Y-53610D02*
X242169Y-52680D01*
X242794Y-51595D01*
X243002Y-50200D01*
X242585Y-48805D01*
X241752Y-47720D01*
X240294Y-46945D01*
X238627Y-46790D01*
X236960Y-47100D01*
X235919Y-47875D01*
X235085Y-48960D01*
X234877Y-50045D01*
X235085Y-51130D01*
X235919Y-52525D01*
X230502Y-52060D01*
Y-47875D01*
G01X232585Y-40745D02*
X231336Y-39815D01*
X230710Y-38730D01*
X230502Y-37490D01*
X230919Y-35940D01*
X231960Y-34855D01*
X233210Y-34545D01*
X234461Y-34700D01*
X235502Y-35320D01*
X237585Y-38420D01*
X239044Y-39815D01*
X241127Y-40745D01*
X243002Y-41055D01*
Y-34545D01*
G01X262794Y-102595D02*
X261335Y-101510D01*
X260502Y-100580D01*
X260085Y-99340D01*
X260502Y-98255D01*
X261335Y-97480D01*
X262585Y-96860D01*
X264044Y-96705D01*
X265294Y-96860D01*
X266544Y-97480D01*
X267585Y-98410D01*
X268002Y-99495D01*
X267585Y-100735D01*
X266336Y-101820D01*
X264460Y-102440D01*
X262377Y-102595D01*
X259669Y-102285D01*
X258210Y-101820D01*
X256752Y-101045D01*
X255710Y-99960D01*
X255502Y-98875D01*
X255919Y-97790D01*
X256960Y-97015D01*
G01X265502Y-90660D02*
X266961Y-89730D01*
X267794Y-88490D01*
X268002Y-87095D01*
X267794Y-85855D01*
X266752Y-84615D01*
X265502Y-83840D01*
X264252Y-83685D01*
X262794Y-83995D01*
X261752Y-85080D01*
X261335Y-86165D01*
Y-87560D01*
G01Y-86165D02*
X260710Y-85235D01*
X259669Y-84460D01*
X258419Y-84150D01*
X257169Y-84460D01*
X256127Y-85235D01*
X255502Y-86630D01*
X255710Y-88025D01*
X256544Y-89420D01*
G01X268419Y-74850D02*
X268210Y-75160D01*
X267794D01*
X267585Y-74850D01*
X267794Y-74540D01*
X268210D01*
X268419Y-74850D01*
G01X265502Y-65860D02*
X266961Y-64930D01*
X267794Y-63690D01*
X268002Y-62295D01*
X267794Y-61055D01*
X266752Y-59815D01*
X265502Y-59040D01*
X264252Y-58885D01*
X262794Y-59195D01*
X261752Y-60280D01*
X261335Y-61365D01*
Y-62760D01*
G01Y-61365D02*
X260710Y-60435D01*
X259669Y-59660D01*
X258419Y-59350D01*
X257169Y-59660D01*
X256127Y-60435D01*
X255502Y-61830D01*
X255710Y-63225D01*
X256544Y-64620D01*
G01X268002Y-50050D02*
X255502D01*
X258002Y-51910D01*
G01X268002D02*
Y-48190D01*
G01X336693Y-830505D02*
X337293Y-829705D01*
X337993Y-829305D01*
X338793Y-829172D01*
X339793Y-829439D01*
X340493Y-830105D01*
X340693Y-830905D01*
X340593Y-831706D01*
X340193Y-832372D01*
X338193Y-833705D01*
X337293Y-834639D01*
X336693Y-835972D01*
X336493Y-837172D01*
X340693D01*
G01X346593Y-829172D02*
X345793Y-829439D01*
X345193Y-830105D01*
X344793Y-830905D01*
X344493Y-831972D01*
X344393Y-833172D01*
X344493Y-834372D01*
X344793Y-835439D01*
X345193Y-836239D01*
X345793Y-836905D01*
X346593Y-837172D01*
X347393Y-836905D01*
X347993Y-836239D01*
X348393Y-835439D01*
X348693Y-834372D01*
X348793Y-833172D01*
X348693Y-831972D01*
X348393Y-830905D01*
X347993Y-830105D01*
X347393Y-829439D01*
X346593Y-829172D01*
G01X352693Y-830505D02*
X353293Y-829705D01*
X353993Y-829305D01*
X354793Y-829172D01*
X355793Y-829439D01*
X356493Y-830105D01*
X356693Y-830905D01*
X356593Y-831706D01*
X356193Y-832372D01*
X354193Y-833705D01*
X353293Y-834639D01*
X352693Y-835972D01*
X352493Y-837172D01*
X356693D01*
G01X360693Y-830505D02*
X361293Y-829705D01*
X361993Y-829305D01*
X362793Y-829172D01*
X363793Y-829439D01*
X364493Y-830105D01*
X364693Y-830905D01*
X364593Y-831706D01*
X364193Y-832372D01*
X362193Y-833705D01*
X361293Y-834639D01*
X360693Y-835972D01*
X360493Y-837172D01*
X364693D01*
G01X368793Y-837439D02*
X372393Y-829172D01*
G01X378593Y-837172D02*
Y-829172D01*
X377393Y-830772D01*
G01Y-837172D02*
X379793D01*
G01X384693Y-830505D02*
X385293Y-829705D01*
X385993Y-829305D01*
X386793Y-829172D01*
X387793Y-829439D01*
X388493Y-830105D01*
X388693Y-830905D01*
X388593Y-831706D01*
X388193Y-832372D01*
X386193Y-833705D01*
X385293Y-834639D01*
X384693Y-835972D01*
X384493Y-837172D01*
X388693D01*
G01X392793Y-837439D02*
X396393Y-829172D01*
G01X402593D02*
X401793Y-829439D01*
X401193Y-830105D01*
X400793Y-830905D01*
X400493Y-831972D01*
X400393Y-833172D01*
X400493Y-834372D01*
X400793Y-835439D01*
X401193Y-836239D01*
X401793Y-836905D01*
X402593Y-837172D01*
X403393Y-836905D01*
X403993Y-836239D01*
X404393Y-835439D01*
X404693Y-834372D01*
X404793Y-833172D01*
X404693Y-831972D01*
X404393Y-830905D01*
X403993Y-830105D01*
X403393Y-829439D01*
X402593Y-829172D01*
G01X408693Y-830505D02*
X409293Y-829705D01*
X409993Y-829305D01*
X410793Y-829172D01*
X411793Y-829439D01*
X412493Y-830105D01*
X412693Y-830905D01*
X412593Y-831706D01*
X412193Y-832372D01*
X410193Y-833705D01*
X409293Y-834639D01*
X408693Y-835972D01*
X408493Y-837172D01*
X412693D01*
G01X336393Y-814672D02*
Y-806672D01*
X338393D01*
X339193Y-807072D01*
X339793Y-807605D01*
X340293Y-808405D01*
X340693Y-809339D01*
X340793Y-810672D01*
X340693Y-812005D01*
X340293Y-812939D01*
X339793Y-813739D01*
X339193Y-814272D01*
X338393Y-814672D01*
X336393D01*
G01X344093D02*
X346593Y-806672D01*
X349093Y-814672D01*
G01X348193Y-811872D02*
X344993D01*
G01X354593Y-806672D02*
X353793Y-806939D01*
X353193Y-807605D01*
X352793Y-808405D01*
X352493Y-809472D01*
X352393Y-810672D01*
X352493Y-811872D01*
X352793Y-812939D01*
X353193Y-813739D01*
X353793Y-814405D01*
X354593Y-814672D01*
X355393Y-814405D01*
X355993Y-813739D01*
X356393Y-812939D01*
X356693Y-811872D01*
X356793Y-810672D01*
X356693Y-809472D01*
X356393Y-808405D01*
X355993Y-807605D01*
X355393Y-806939D01*
X354593Y-806672D01*
G01X360693Y-814672D02*
Y-806672D01*
X364493D01*
G01X363093Y-810539D02*
X360693D01*
G01X370593Y-806672D02*
X369793Y-806939D01*
X369193Y-807605D01*
X368793Y-808405D01*
X368493Y-809472D01*
X368393Y-810672D01*
X368493Y-811872D01*
X368793Y-812939D01*
X369193Y-813739D01*
X369793Y-814405D01*
X370593Y-814672D01*
X371393Y-814405D01*
X371993Y-813739D01*
X372393Y-812939D01*
X372693Y-811872D01*
X372793Y-810672D01*
X372693Y-809472D01*
X372393Y-808405D01*
X371993Y-807605D01*
X371393Y-806939D01*
X370593Y-806672D01*
G01X378593D02*
Y-814672D01*
G01X376293Y-806672D02*
X380893D01*
G01X384593Y-814672D02*
Y-806672D01*
X386993D01*
X387793Y-807072D01*
X388393Y-808005D01*
X388593Y-809072D01*
X388393Y-810139D01*
X387893Y-810939D01*
X386993Y-811339D01*
X384593D01*
G01X395393Y-810405D02*
X395793Y-810005D01*
X396093Y-809339D01*
X396293Y-808405D01*
X396093Y-807605D01*
X395693Y-807072D01*
X394993Y-806672D01*
X392293D01*
Y-814672D01*
X395593D01*
X396293Y-814139D01*
X396693Y-813339D01*
X396893Y-812405D01*
X396693Y-811472D01*
X396093Y-810672D01*
X395393Y-810405D01*
X392293D01*
G01X400093Y-814672D02*
X402593Y-806672D01*
X405093Y-814672D01*
G01X404193Y-811872D02*
X400993D01*
G01X408693Y-814672D02*
Y-806672D01*
X412493D01*
G01X411093Y-810539D02*
X408693D01*
G01X418593Y-806672D02*
X417793Y-806939D01*
X417193Y-807605D01*
X416793Y-808405D01*
X416493Y-809472D01*
X416393Y-810672D01*
X416493Y-811872D01*
X416793Y-812939D01*
X417193Y-813739D01*
X417793Y-814405D01*
X418593Y-814672D01*
X419393Y-814405D01*
X419993Y-813739D01*
X420393Y-812939D01*
X420693Y-811872D01*
X420793Y-810672D01*
X420693Y-809472D01*
X420393Y-808405D01*
X419993Y-807605D01*
X419393Y-806939D01*
X418593Y-806672D01*
G01X356693Y-787172D02*
Y-779172D01*
X360493D01*
G01X359093Y-783039D02*
X356693D01*
G01X366593Y-779172D02*
X365793Y-779439D01*
X365193Y-780105D01*
X364793Y-780905D01*
X364493Y-781972D01*
X364393Y-783172D01*
X364493Y-784372D01*
X364793Y-785439D01*
X365193Y-786239D01*
X365793Y-786905D01*
X366593Y-787172D01*
X367393Y-786905D01*
X367993Y-786239D01*
X368393Y-785439D01*
X368693Y-784372D01*
X368793Y-783172D01*
X368693Y-781972D01*
X368393Y-780905D01*
X367993Y-780105D01*
X367393Y-779439D01*
X366593Y-779172D01*
G01X374593D02*
Y-787172D01*
G01X372293Y-779172D02*
X376893D01*
G01X379593Y-789839D02*
X385593D01*
G01X388593Y-787172D02*
Y-779172D01*
X390993D01*
X391793Y-779572D01*
X392393Y-780505D01*
X392593Y-781572D01*
X392393Y-782639D01*
X391893Y-783439D01*
X390993Y-783839D01*
X388593D01*
G01X396393Y-787172D02*
Y-779172D01*
X398393D01*
X399193Y-779572D01*
X399793Y-780105D01*
X400293Y-780905D01*
X400693Y-781839D01*
X400793Y-783172D01*
X400693Y-784505D01*
X400293Y-785439D01*
X399793Y-786239D01*
X399193Y-786772D01*
X398393Y-787172D01*
X396393D01*
G01X407393Y-782905D02*
X407793Y-782505D01*
X408093Y-781839D01*
X408293Y-780905D01*
X408093Y-780105D01*
X407693Y-779572D01*
X406993Y-779172D01*
X404293D01*
Y-787172D01*
X407593D01*
X408293Y-786639D01*
X408693Y-785839D01*
X408893Y-784905D01*
X408693Y-783972D01*
X408093Y-783172D01*
X407393Y-782905D01*
X404293D01*
G01X411593Y-789839D02*
X417593D01*
G01X424793Y-779839D02*
X424193Y-779439D01*
X423493Y-779172D01*
X422693D01*
X421793Y-779572D01*
X421093Y-780239D01*
X420593Y-781039D01*
X420193Y-782372D01*
X420093Y-783572D01*
X420293Y-784772D01*
X420593Y-785572D01*
X421193Y-786372D01*
X421893Y-786905D01*
X422593Y-787172D01*
X423293D01*
X423993Y-786905D01*
X424593Y-786505D01*
X425093Y-785972D01*
G01X430593Y-787172D02*
X429793Y-787039D01*
X429093Y-786505D01*
X428493Y-785705D01*
X428093Y-784772D01*
X427893Y-783705D01*
Y-782639D01*
X428093Y-781572D01*
X428493Y-780639D01*
X429093Y-779839D01*
X429793Y-779305D01*
X430593Y-779172D01*
X431393Y-779305D01*
X432093Y-779839D01*
X432693Y-780639D01*
X433093Y-781572D01*
X433293Y-782639D01*
Y-783705D01*
X433093Y-784772D01*
X432693Y-785705D01*
X432093Y-786505D01*
X431393Y-787039D01*
X430593Y-787172D01*
G01X436293D02*
Y-779172D01*
X440893Y-787172D01*
Y-779172D01*
G01X444093D02*
X446593Y-787172D01*
X449093Y-779172D01*
G01X456593Y-787172D02*
X452593D01*
Y-779172D01*
X456593D01*
G01X454993Y-783039D02*
X452593D01*
G01X460593Y-787172D02*
Y-779172D01*
X463093D01*
X463893Y-779572D01*
X464393Y-780105D01*
X464593Y-781172D01*
X464393Y-782239D01*
X463793Y-782905D01*
X463093Y-783305D01*
X460593D01*
G01X463093D02*
X464593Y-787172D01*
G01X470593Y-779172D02*
Y-787172D01*
G01X468293Y-779172D02*
X472893D01*
G01X480593Y-787172D02*
X476593D01*
Y-779172D01*
X480593D01*
G01X478993Y-783039D02*
X476593D01*
G01X484593Y-787172D02*
Y-779172D01*
X487093D01*
X487893Y-779572D01*
X488393Y-780105D01*
X488593Y-781172D01*
X488393Y-782239D01*
X487793Y-782905D01*
X487093Y-783305D01*
X484593D01*
G01X487093D02*
X488593Y-787172D01*
G01X425093Y-840172D02*
Y-832172D01*
X423893Y-833772D01*
G01Y-840172D02*
X426293D01*
G01X431193Y-836839D02*
X431893Y-835905D01*
X432493Y-835372D01*
X433293Y-835105D01*
X433993Y-835372D01*
X434493Y-835905D01*
X434893Y-836705D01*
X434993Y-837639D01*
X434893Y-838439D01*
X434493Y-839239D01*
X433893Y-839905D01*
X433193Y-840172D01*
X432393Y-839905D01*
X431693Y-839106D01*
X431293Y-837905D01*
X431193Y-836572D01*
X431393Y-834839D01*
X431693Y-833905D01*
X432193Y-832972D01*
X432893Y-832305D01*
X433593Y-832172D01*
X434293Y-832439D01*
X434793Y-833105D01*
G01X441093Y-840439D02*
X440893Y-840305D01*
Y-840039D01*
X441093Y-839905D01*
X441293Y-840039D01*
Y-840305D01*
X441093Y-840439D01*
G01X447193Y-836839D02*
X447893Y-835905D01*
X448493Y-835372D01*
X449293Y-835105D01*
X449993Y-835372D01*
X450493Y-835905D01*
X450893Y-836705D01*
X450993Y-837639D01*
X450893Y-838439D01*
X450493Y-839239D01*
X449893Y-839905D01*
X449193Y-840172D01*
X448393Y-839905D01*
X447693Y-839106D01*
X447293Y-837905D01*
X447193Y-836572D01*
X447393Y-834839D01*
X447693Y-833905D01*
X448193Y-832972D01*
X448893Y-832305D01*
X449593Y-832172D01*
X450293Y-832439D01*
X450793Y-833105D01*
G01X470093Y-840172D02*
Y-832172D01*
X468893Y-833772D01*
G01Y-840172D02*
X471293D01*
G01X477893D02*
X478093Y-838439D01*
X478393Y-836972D01*
X478793Y-835639D01*
X479293Y-834172D01*
X480093Y-832172D01*
X476093D01*
G01X486093Y-840439D02*
X485893Y-840305D01*
Y-840039D01*
X486093Y-839905D01*
X486293Y-840039D01*
Y-840305D01*
X486093Y-840439D01*
G01X492193Y-833505D02*
X492793Y-832705D01*
X493493Y-832305D01*
X494293Y-832172D01*
X495293Y-832439D01*
X495993Y-833105D01*
X496193Y-833905D01*
X496093Y-834706D01*
X495693Y-835372D01*
X493693Y-836705D01*
X492793Y-837639D01*
X492193Y-838972D01*
X491993Y-840172D01*
X496193D01*
G01X490193Y-815172D02*
Y-807172D01*
X493993D01*
G01X492593Y-811039D02*
X490193D01*
G01X498850Y-53867D02*
X491350D01*
Y-51627D01*
X491725Y-50880D01*
X492600Y-50320D01*
X493600Y-50133D01*
X494600Y-50320D01*
X495350Y-50787D01*
X495725Y-51627D01*
Y-53867D01*
G01X491350Y-44500D02*
X498850D01*
G01X491350Y-46647D02*
Y-42353D01*
G01X498850Y-38960D02*
X491350D01*
G01Y-35040D02*
X498850D01*
G01X495100D02*
Y-38960D01*
G01X521127Y-115760D02*
X522169Y-114830D01*
X522794Y-113745D01*
X523002Y-112350D01*
X522585Y-110955D01*
X521752Y-109870D01*
X520294Y-109095D01*
X518627Y-108940D01*
X516960Y-109250D01*
X515919Y-110025D01*
X515085Y-111110D01*
X514877Y-112195D01*
X515085Y-113280D01*
X515919Y-114675D01*
X510502Y-114210D01*
Y-110025D01*
G01X512585Y-102895D02*
X511336Y-101965D01*
X510710Y-100880D01*
X510502Y-99640D01*
X510919Y-98090D01*
X511960Y-97005D01*
X513210Y-96695D01*
X514461Y-96850D01*
X515502Y-97470D01*
X517585Y-100570D01*
X519044Y-101965D01*
X521127Y-102895D01*
X523002Y-103205D01*
Y-96695D01*
G01X521544Y-90185D02*
X522585Y-89100D01*
X523002Y-87860D01*
X522585Y-86620D01*
X521336Y-85535D01*
X519460Y-84760D01*
X517585Y-84450D01*
X515294D01*
X513419Y-84760D01*
X511752Y-85535D01*
X510919Y-86465D01*
X510502Y-87550D01*
X510919Y-88790D01*
X511752Y-89720D01*
X513002Y-90340D01*
X514669Y-90650D01*
X516127Y-90340D01*
X517585Y-89565D01*
X518419Y-88635D01*
X518627Y-87550D01*
X518211Y-86310D01*
X517169Y-85380D01*
X515294Y-84450D01*
G01X512585Y-78095D02*
X511336Y-77165D01*
X510710Y-76080D01*
X510502Y-74840D01*
X510919Y-73290D01*
X511960Y-72205D01*
X513210Y-71895D01*
X514461Y-72050D01*
X515502Y-72670D01*
X517585Y-75770D01*
X519044Y-77165D01*
X521127Y-78095D01*
X523002Y-78405D01*
Y-71895D01*
G01X523419Y-62750D02*
X523210Y-63060D01*
X522794D01*
X522585Y-62750D01*
X522794Y-62440D01*
X523210D01*
X523419Y-62750D01*
G01X521127Y-53760D02*
X522169Y-52830D01*
X522794Y-51745D01*
X523002Y-50350D01*
X522585Y-48955D01*
X521752Y-47870D01*
X520294Y-47095D01*
X518627Y-46940D01*
X516960Y-47250D01*
X515919Y-48025D01*
X515085Y-49110D01*
X514877Y-50195D01*
X515085Y-51280D01*
X515919Y-52675D01*
X510502Y-52210D01*
Y-48025D01*
G01X512585Y-40895D02*
X511336Y-39965D01*
X510710Y-38880D01*
X510502Y-37640D01*
X510919Y-36090D01*
X511960Y-35005D01*
X513210Y-34695D01*
X514461Y-34850D01*
X515502Y-35470D01*
X517585Y-38570D01*
X519044Y-39965D01*
X521127Y-40895D01*
X523002Y-41205D01*
Y-34695D01*
G01X548002Y-106000D02*
X535502D01*
X538002Y-107860D01*
G01X548002D02*
Y-104140D01*
G01X545502Y-97010D02*
X546961Y-96080D01*
X547794Y-94840D01*
X548002Y-93445D01*
X547794Y-92205D01*
X546752Y-90965D01*
X545502Y-90190D01*
X544252Y-90035D01*
X542794Y-90345D01*
X541752Y-91430D01*
X541335Y-92515D01*
Y-93910D01*
G01Y-92515D02*
X540710Y-91585D01*
X539669Y-90810D01*
X538419Y-90500D01*
X537169Y-90810D01*
X536127Y-91585D01*
X535502Y-92980D01*
X535710Y-94375D01*
X536544Y-95770D01*
G01X548002Y-79340D02*
X535502D01*
X544460Y-85075D01*
Y-77325D01*
G01X548419Y-68800D02*
X548210Y-69110D01*
X547794D01*
X547585Y-68800D01*
X547794Y-68490D01*
X548210D01*
X548419Y-68800D01*
G01X548002Y-54540D02*
X535502D01*
X544460Y-60275D01*
Y-52525D01*
G01X545502Y-47410D02*
X546961Y-46480D01*
X547794Y-45240D01*
X548002Y-43845D01*
X547794Y-42605D01*
X546752Y-41365D01*
X545502Y-40590D01*
X544252Y-40435D01*
X542794Y-40745D01*
X541752Y-41830D01*
X541335Y-42915D01*
Y-44310D01*
G01Y-42915D02*
X540710Y-41985D01*
X539669Y-41210D01*
X538419Y-40900D01*
X537169Y-41210D01*
X536127Y-41985D01*
X535502Y-43380D01*
X535710Y-44775D01*
X536544Y-46170D01*
G01X569363Y74342D02*
Y81842D01*
X571697D01*
X572443Y81467D01*
X572910Y80967D01*
X573097Y79967D01*
X572910Y78967D01*
X572350Y78342D01*
X571697Y77967D01*
X569363D01*
G01X571697D02*
X573097Y74342D01*
G01X580597D02*
X576863D01*
Y81842D01*
X580597D01*
G01X579103Y78217D02*
X576863D01*
G01X588283Y81217D02*
X587723Y81592D01*
X587070Y81842D01*
X586323D01*
X585483Y81467D01*
X584830Y80842D01*
X584363Y80092D01*
X583990Y78842D01*
X583897Y77717D01*
X584083Y76592D01*
X584363Y75842D01*
X584923Y75092D01*
X585577Y74592D01*
X586230Y74342D01*
X586883D01*
X587537Y74592D01*
X588097Y74967D01*
X588563Y75467D01*
G01X593730Y74342D02*
X592983Y74467D01*
X592330Y74967D01*
X591770Y75717D01*
X591397Y76592D01*
X591210Y77592D01*
Y78592D01*
X591397Y79592D01*
X591770Y80467D01*
X592330Y81217D01*
X592983Y81717D01*
X593730Y81842D01*
X594477Y81717D01*
X595130Y81217D01*
X595690Y80467D01*
X596063Y79592D01*
X596250Y78592D01*
Y77592D01*
X596063Y76592D01*
X595690Y75717D01*
X595130Y74967D01*
X594477Y74467D01*
X593730Y74342D01*
G01X598803D02*
Y81842D01*
X601230Y75592D01*
X603657Y81842D01*
Y74342D01*
G01X606303D02*
Y81842D01*
X608730Y75592D01*
X611157Y81842D01*
Y74342D01*
G01X618097D02*
X614363D01*
Y81842D01*
X618097D01*
G01X616603Y78217D02*
X614363D01*
G01X621583Y74342D02*
Y81842D01*
X625877Y74342D01*
Y81842D01*
G01X629177Y74342D02*
Y81842D01*
X631043D01*
X631790Y81467D01*
X632350Y80967D01*
X632817Y80217D01*
X633190Y79342D01*
X633283Y78092D01*
X633190Y76842D01*
X632817Y75967D01*
X632350Y75217D01*
X631790Y74717D01*
X631043Y74342D01*
X629177D01*
G01X640597D02*
X636863D01*
Y81842D01*
X640597D01*
G01X639103Y78217D02*
X636863D01*
G01X644177Y74342D02*
Y81842D01*
X646043D01*
X646790Y81467D01*
X647350Y80967D01*
X647817Y80217D01*
X648190Y79342D01*
X648283Y78092D01*
X648190Y76842D01*
X647817Y75967D01*
X647350Y75217D01*
X646790Y74717D01*
X646043Y74342D01*
X644177D01*
G01X659177D02*
Y81842D01*
X661043D01*
X661790Y81467D01*
X662350Y80967D01*
X662817Y80217D01*
X663190Y79342D01*
X663283Y78092D01*
X663190Y76842D01*
X662817Y75967D01*
X662350Y75217D01*
X661790Y74717D01*
X661043Y74342D01*
X659177D01*
G01X666863D02*
Y81842D01*
X669197D01*
X669943Y81467D01*
X670410Y80967D01*
X670597Y79967D01*
X670410Y78967D01*
X669850Y78342D01*
X669197Y77967D01*
X666863D01*
G01X669197D02*
X670597Y74342D01*
G01X675110Y81842D02*
X677350D01*
G01X676230D02*
Y74342D01*
G01X675110D02*
X677350D01*
G01X681863Y81842D02*
Y74342D01*
X685597D01*
G01X689363Y81842D02*
Y74342D01*
X693097D01*
G01X704270Y75342D02*
X705017Y74717D01*
X705857Y74342D01*
X706603D01*
X707350Y74717D01*
X707910Y75342D01*
X708190Y76217D01*
X708003Y77092D01*
X707537Y77842D01*
X706697Y78342D01*
X705577Y78592D01*
X704923Y79092D01*
X704643Y79967D01*
X704830Y80842D01*
X705297Y81467D01*
X705950Y81842D01*
X706603D01*
X707257Y81592D01*
X707817Y80967D01*
G01X712610Y81842D02*
X714850D01*
G01X713730D02*
Y74342D01*
G01X712610D02*
X714850D01*
G01X719457Y81842D02*
X723003D01*
X719457Y74342D01*
X723003D01*
G01X730597D02*
X726863D01*
Y81842D01*
X730597D01*
G01X729103Y78217D02*
X726863D01*
G01X741957Y74342D02*
Y81842D01*
X745503D01*
G01X744197Y78217D02*
X741957D01*
G01X751230Y74342D02*
X750483Y74467D01*
X749830Y74967D01*
X749270Y75717D01*
X748897Y76592D01*
X748710Y77592D01*
Y78592D01*
X748897Y79592D01*
X749270Y80467D01*
X749830Y81217D01*
X750483Y81717D01*
X751230Y81842D01*
X751977Y81717D01*
X752630Y81217D01*
X753190Y80467D01*
X753563Y79592D01*
X753750Y78592D01*
Y77592D01*
X753563Y76592D01*
X753190Y75717D01*
X752630Y74967D01*
X751977Y74467D01*
X751230Y74342D01*
G01X756863D02*
Y81842D01*
X759197D01*
X759943Y81467D01*
X760410Y80967D01*
X760597Y79967D01*
X760410Y78967D01*
X759850Y78342D01*
X759197Y77967D01*
X756863D01*
G01X759197D02*
X760597Y74342D01*
G01X773730D02*
Y81842D01*
X772610Y80342D01*
G01Y74342D02*
X774850D01*
G01X781230Y74092D02*
X781043Y74217D01*
Y74467D01*
X781230Y74592D01*
X781417Y74467D01*
Y74217D01*
X781230Y74092D01*
G01X788730Y81842D02*
X787983Y81592D01*
X787423Y80967D01*
X787050Y80217D01*
X786770Y79217D01*
X786677Y78092D01*
X786770Y76967D01*
X787050Y75967D01*
X787423Y75217D01*
X787983Y74592D01*
X788730Y74342D01*
X789477Y74592D01*
X790037Y75217D01*
X790410Y75967D01*
X790690Y76967D01*
X790783Y78092D01*
X790690Y79217D01*
X790410Y80217D01*
X790037Y80967D01*
X789477Y81592D01*
X788730Y81842D01*
G01X794457Y80592D02*
X795017Y81342D01*
X795670Y81717D01*
X796417Y81842D01*
X797350Y81592D01*
X798003Y80967D01*
X798190Y80217D01*
X798097Y79467D01*
X797723Y78842D01*
X795857Y77592D01*
X795017Y76717D01*
X794457Y75467D01*
X794270Y74342D01*
X798190D01*
G01X801303D02*
Y81842D01*
X803730Y75592D01*
X806157Y81842D01*
Y74342D01*
G01X808803D02*
Y81842D01*
X811230Y75592D01*
X813657Y81842D01*
Y74342D01*
G01X824457D02*
Y81842D01*
X828003D01*
G01X826697Y78217D02*
X824457D01*
G01X832610Y81842D02*
X834850D01*
G01X833730D02*
Y74342D01*
G01X832610D02*
X834850D01*
G01X839083D02*
Y81842D01*
X843377Y74342D01*
Y81842D01*
G01X847610D02*
X849850D01*
G01X848730D02*
Y74342D01*
G01X847610D02*
X849850D01*
G01X854270Y75342D02*
X855017Y74717D01*
X855857Y74342D01*
X856603D01*
X857350Y74717D01*
X857910Y75342D01*
X858190Y76217D01*
X858003Y77092D01*
X857537Y77842D01*
X856697Y78342D01*
X855577Y78592D01*
X854923Y79092D01*
X854643Y79967D01*
X854830Y80842D01*
X855297Y81467D01*
X855950Y81842D01*
X856603D01*
X857257Y81592D01*
X857817Y80967D01*
G01X861770Y74342D02*
Y81842D01*
G01X865690D02*
Y74342D01*
G01Y78092D02*
X861770D01*
G01X873097Y74342D02*
X869363D01*
Y81842D01*
X873097D01*
G01X871603Y78217D02*
X869363D01*
G01X876677Y74342D02*
Y81842D01*
X878543D01*
X879290Y81467D01*
X879850Y80967D01*
X880317Y80217D01*
X880690Y79342D01*
X880783Y78092D01*
X880690Y76842D01*
X880317Y75967D01*
X879850Y75217D01*
X879290Y74717D01*
X878543Y74342D01*
X876677D01*
G01X891863D02*
Y81842D01*
X894103D01*
X894850Y81467D01*
X895410Y80592D01*
X895597Y79592D01*
X895410Y78592D01*
X894943Y77842D01*
X894103Y77467D01*
X891863D01*
G01X901230Y81842D02*
Y74342D01*
G01X899083Y81842D02*
X903377D01*
G01X906770Y74342D02*
Y81842D01*
G01X910690D02*
Y74342D01*
G01Y78092D02*
X906770D01*
G01X922610Y81842D02*
X924850D01*
G01X923730D02*
Y74342D01*
G01X922610D02*
X924850D01*
G01X929270Y75342D02*
X930017Y74717D01*
X930857Y74342D01*
X931603D01*
X932350Y74717D01*
X932910Y75342D01*
X933190Y76217D01*
X933003Y77092D01*
X932537Y77842D01*
X931697Y78342D01*
X930577Y78592D01*
X929923Y79092D01*
X929643Y79967D01*
X929830Y80842D01*
X930297Y81467D01*
X930950Y81842D01*
X931603D01*
X932257Y81592D01*
X932817Y80967D01*
G01X946230Y74342D02*
Y81842D01*
X945110Y80342D01*
G01Y74342D02*
X947350D01*
G01X953730Y74092D02*
X953543Y74217D01*
Y74467D01*
X953730Y74592D01*
X953917Y74467D01*
Y74217D01*
X953730Y74092D01*
G01X961230Y74342D02*
Y81842D01*
X960110Y80342D01*
G01Y74342D02*
X962350D01*
G01X966677Y75467D02*
X967237Y74842D01*
X967890Y74467D01*
X968730Y74342D01*
X969570Y74592D01*
X970223Y75092D01*
X970690Y75967D01*
X970783Y76967D01*
X970597Y77967D01*
X970130Y78592D01*
X969477Y79092D01*
X968823Y79217D01*
X968170Y79092D01*
X967330Y78592D01*
X967610Y81842D01*
X970130D01*
G01X975203Y76842D02*
X977443D01*
G01X976230Y78467D02*
Y75217D01*
G01X982050Y74092D02*
X985410Y81842D01*
G01X990017Y76842D02*
X992443D01*
G01X998730Y81842D02*
X997983Y81592D01*
X997423Y80967D01*
X997050Y80217D01*
X996770Y79217D01*
X996677Y78092D01*
X996770Y76967D01*
X997050Y75967D01*
X997423Y75217D01*
X997983Y74592D01*
X998730Y74342D01*
X999477Y74592D01*
X1000037Y75217D01*
X1000410Y75967D01*
X1000690Y76967D01*
X1000783Y78092D01*
X1000690Y79217D01*
X1000410Y80217D01*
X1000037Y80967D01*
X999477Y81592D01*
X998730Y81842D01*
G01X1006230Y74092D02*
X1006043Y74217D01*
Y74467D01*
X1006230Y74592D01*
X1006417Y74467D01*
Y74217D01*
X1006230Y74092D01*
G01X1013730Y81842D02*
X1012983Y81592D01*
X1012423Y80967D01*
X1012050Y80217D01*
X1011770Y79217D01*
X1011677Y78092D01*
X1011770Y76967D01*
X1012050Y75967D01*
X1012423Y75217D01*
X1012983Y74592D01*
X1013730Y74342D01*
X1014477Y74592D01*
X1015037Y75217D01*
X1015410Y75967D01*
X1015690Y76967D01*
X1015783Y78092D01*
X1015690Y79217D01*
X1015410Y80217D01*
X1015037Y80967D01*
X1014477Y81592D01*
X1013730Y81842D01*
G01X1019457Y80592D02*
X1020017Y81342D01*
X1020670Y81717D01*
X1021417Y81842D01*
X1022350Y81592D01*
X1023003Y80967D01*
X1023190Y80217D01*
X1023097Y79467D01*
X1022723Y78842D01*
X1020857Y77592D01*
X1020017Y76717D01*
X1019457Y75467D01*
X1019270Y74342D01*
X1023190D01*
G01X1026677Y75467D02*
X1027237Y74842D01*
X1027890Y74467D01*
X1028730Y74342D01*
X1029570Y74592D01*
X1030223Y75092D01*
X1030690Y75967D01*
X1030783Y76967D01*
X1030597Y77967D01*
X1030130Y78592D01*
X1029477Y79092D01*
X1028823Y79217D01*
X1028170Y79092D01*
X1027330Y78592D01*
X1027610Y81842D01*
X1030130D01*
G01X1033803Y74342D02*
Y81842D01*
X1036230Y75592D01*
X1038657Y81842D01*
Y74342D01*
G01X1041303D02*
Y81842D01*
X1043730Y75592D01*
X1046157Y81842D01*
Y74342D01*
G01X592911Y43374D02*
Y35874D01*
X596645D01*
G01X602278D02*
X601531Y35999D01*
X600878Y36499D01*
X600318Y37249D01*
X599945Y38124D01*
X599758Y39124D01*
Y40124D01*
X599945Y41124D01*
X600318Y41999D01*
X600878Y42749D01*
X601531Y43249D01*
X602278Y43374D01*
X603025Y43249D01*
X603678Y42749D01*
X604238Y41999D01*
X604611Y41124D01*
X604798Y40124D01*
Y39124D01*
X604611Y38124D01*
X604238Y37249D01*
X603678Y36499D01*
X603025Y35999D01*
X602278Y35874D01*
G01X610338Y39624D02*
X612205D01*
Y37374D01*
X611645Y36624D01*
X610991Y36124D01*
X610058Y35874D01*
X609125Y36124D01*
X608471Y36624D01*
X607911Y37374D01*
X607538Y38249D01*
X607351Y39249D01*
Y40124D01*
X607538Y40874D01*
X607911Y41749D01*
X608471Y42499D01*
X609031Y42999D01*
X609778Y43374D01*
X610431D01*
X611178Y43124D01*
X611738Y42624D01*
G01X617278Y35874D02*
X616531Y35999D01*
X615878Y36499D01*
X615318Y37249D01*
X614945Y38124D01*
X614758Y39124D01*
Y40124D01*
X614945Y41124D01*
X615318Y41999D01*
X615878Y42749D01*
X616531Y43249D01*
X617278Y43374D01*
X618025Y43249D01*
X618678Y42749D01*
X619238Y41999D01*
X619611Y41124D01*
X619798Y40124D01*
Y39124D01*
X619611Y38124D01*
X619238Y37249D01*
X618678Y36499D01*
X618025Y35999D01*
X617278Y35874D01*
G01X570411Y51622D02*
Y59122D01*
X572651D01*
X573398Y58747D01*
X573958Y57872D01*
X574145Y56872D01*
X573958Y55872D01*
X573491Y55122D01*
X572651Y54747D01*
X570411D01*
G01X581831Y58497D02*
X581271Y58872D01*
X580618Y59122D01*
X579871D01*
X579031Y58747D01*
X578378Y58122D01*
X577911Y57372D01*
X577538Y56122D01*
X577445Y54997D01*
X577631Y53872D01*
X577911Y53122D01*
X578471Y52372D01*
X579125Y51872D01*
X579778Y51622D01*
X580431D01*
X581085Y51872D01*
X581645Y52247D01*
X582111Y52747D01*
G01X588025Y55622D02*
X588398Y55997D01*
X588678Y56622D01*
X588865Y57497D01*
X588678Y58247D01*
X588305Y58747D01*
X587651Y59122D01*
X585131D01*
Y51622D01*
X588211D01*
X588865Y52122D01*
X589238Y52872D01*
X589425Y53747D01*
X589238Y54622D01*
X588678Y55372D01*
X588025Y55622D01*
X585131D01*
G01X599945Y59122D02*
X602278Y51622D01*
X604611Y59122D01*
G01X611645Y51622D02*
X607911D01*
Y59122D01*
X611645D01*
G01X610151Y55497D02*
X607911D01*
G01X615131Y51622D02*
Y59122D01*
X619425Y51622D01*
Y59122D01*
G01X622725Y51622D02*
Y59122D01*
X624591D01*
X625338Y58747D01*
X625898Y58247D01*
X626365Y57497D01*
X626738Y56622D01*
X626831Y55372D01*
X626738Y54122D01*
X626365Y53247D01*
X625898Y52497D01*
X625338Y51997D01*
X624591Y51622D01*
X622725D01*
G01X632278D02*
X631531Y51747D01*
X630878Y52247D01*
X630318Y52997D01*
X629945Y53872D01*
X629758Y54872D01*
Y55872D01*
X629945Y56872D01*
X630318Y57747D01*
X630878Y58497D01*
X631531Y58997D01*
X632278Y59122D01*
X633025Y58997D01*
X633678Y58497D01*
X634238Y57747D01*
X634611Y56872D01*
X634798Y55872D01*
Y54872D01*
X634611Y53872D01*
X634238Y52997D01*
X633678Y52247D01*
X633025Y51747D01*
X632278Y51622D01*
G01X637911D02*
Y59122D01*
X640245D01*
X640991Y58747D01*
X641458Y58247D01*
X641645Y57247D01*
X641458Y56247D01*
X640898Y55622D01*
X640245Y55247D01*
X637911D01*
G01X640245D02*
X641645Y51622D01*
G01X621700Y781750D02*
Y794250D01*
X619840Y791750D01*
G01Y781750D02*
X623560D01*
G01X631155Y792167D02*
X632085Y793416D01*
X633170Y794042D01*
X634410Y794250D01*
X635960Y793833D01*
X637045Y792792D01*
X637355Y791542D01*
X637200Y790291D01*
X636580Y789250D01*
X633480Y787167D01*
X632085Y785708D01*
X631155Y783625D01*
X630845Y781750D01*
X637355D01*
G01X643865Y783208D02*
X644950Y782167D01*
X646190Y781750D01*
X647430Y782167D01*
X648515Y783416D01*
X649290Y785292D01*
X649600Y787167D01*
Y789458D01*
X649290Y791333D01*
X648515Y793000D01*
X647585Y793833D01*
X646500Y794250D01*
X645260Y793833D01*
X644330Y793000D01*
X643710Y791750D01*
X643400Y790083D01*
X643710Y788625D01*
X644485Y787167D01*
X645415Y786333D01*
X646500Y786125D01*
X647740Y786541D01*
X648670Y787583D01*
X649600Y789458D01*
G01X658900Y781750D02*
Y794250D01*
X657040Y791750D01*
G01Y781750D02*
X660760D01*
G01X667890Y784250D02*
X668820Y782791D01*
X670060Y781958D01*
X671455Y781750D01*
X672695Y781958D01*
X673935Y783000D01*
X674710Y784250D01*
X674865Y785500D01*
X674555Y786958D01*
X673470Y788000D01*
X672385Y788417D01*
X670990D01*
G01X672385D02*
X673315Y789042D01*
X674090Y790083D01*
X674400Y791333D01*
X674090Y792583D01*
X673315Y793625D01*
X671920Y794250D01*
X670525Y794042D01*
X669130Y793208D01*
G01X683700Y781333D02*
X683390Y781542D01*
Y781958D01*
X683700Y782167D01*
X684010Y781958D01*
Y781542D01*
X683700Y781333D01*
G01X692690Y784250D02*
X693620Y782791D01*
X694860Y781958D01*
X696255Y781750D01*
X697495Y781958D01*
X698735Y783000D01*
X699510Y784250D01*
X699665Y785500D01*
X699355Y786958D01*
X698270Y788000D01*
X697185Y788417D01*
X695790D01*
G01X697185D02*
X698115Y789042D01*
X698890Y790083D01*
X699200Y791333D01*
X698890Y792583D01*
X698115Y793625D01*
X696720Y794250D01*
X695325Y794042D01*
X693930Y793208D01*
G01X705865Y783208D02*
X706950Y782167D01*
X708190Y781750D01*
X709430Y782167D01*
X710515Y783416D01*
X711290Y785292D01*
X711600Y787167D01*
Y789458D01*
X711290Y791333D01*
X710515Y793000D01*
X709585Y793833D01*
X708500Y794250D01*
X707260Y793833D01*
X706330Y793000D01*
X705710Y791750D01*
X705400Y790083D01*
X705710Y788625D01*
X706485Y787167D01*
X707415Y786333D01*
X708500Y786125D01*
X709740Y786541D01*
X710670Y787583D01*
X711600Y789458D01*
G01X653601Y-115295D02*
X652142Y-114210D01*
X651309Y-113280D01*
X650892Y-112040D01*
X651309Y-110955D01*
X652142Y-110180D01*
X653392Y-109560D01*
X654851Y-109405D01*
X656101Y-109560D01*
X657351Y-110180D01*
X658392Y-111110D01*
X658809Y-112195D01*
X658392Y-113435D01*
X657143Y-114520D01*
X655267Y-115140D01*
X653184Y-115295D01*
X650476Y-114985D01*
X649017Y-114520D01*
X647559Y-113745D01*
X646517Y-112660D01*
X646309Y-111575D01*
X646726Y-110490D01*
X647767Y-109715D01*
G01X653601Y-102895D02*
X652142Y-101810D01*
X651309Y-100880D01*
X650892Y-99640D01*
X651309Y-98555D01*
X652142Y-97780D01*
X653392Y-97160D01*
X654851Y-97005D01*
X656101Y-97160D01*
X657351Y-97780D01*
X658392Y-98710D01*
X658809Y-99795D01*
X658392Y-101035D01*
X657143Y-102120D01*
X655267Y-102740D01*
X653184Y-102895D01*
X650476Y-102585D01*
X649017Y-102120D01*
X647559Y-101345D01*
X646517Y-100260D01*
X646309Y-99175D01*
X646726Y-98090D01*
X647767Y-97315D01*
G01X656934Y-90960D02*
X657976Y-90030D01*
X658601Y-88945D01*
X658809Y-87550D01*
X658392Y-86155D01*
X657559Y-85070D01*
X656101Y-84295D01*
X654434Y-84140D01*
X652767Y-84450D01*
X651726Y-85225D01*
X650892Y-86310D01*
X650684Y-87395D01*
X650892Y-88480D01*
X651726Y-89875D01*
X646309Y-89410D01*
Y-85225D01*
G01Y-75150D02*
X646726Y-76390D01*
X647767Y-77320D01*
X649017Y-77940D01*
X650684Y-78405D01*
X652559Y-78560D01*
X654434Y-78405D01*
X656101Y-77940D01*
X657351Y-77320D01*
X658392Y-76390D01*
X658809Y-75150D01*
X658392Y-73910D01*
X657351Y-72980D01*
X656101Y-72360D01*
X654434Y-71895D01*
X652559Y-71740D01*
X650684Y-71895D01*
X649017Y-72360D01*
X647767Y-72980D01*
X646726Y-73910D01*
X646309Y-75150D01*
G01X659226Y-62750D02*
X659017Y-63060D01*
X658601D01*
X658392Y-62750D01*
X658601Y-62440D01*
X659017D01*
X659226Y-62750D01*
G01X656934Y-53760D02*
X657976Y-52830D01*
X658601Y-51745D01*
X658809Y-50350D01*
X658392Y-48955D01*
X657559Y-47870D01*
X656101Y-47095D01*
X654434Y-46940D01*
X652767Y-47250D01*
X651726Y-48025D01*
X650892Y-49110D01*
X650684Y-50195D01*
X650892Y-51280D01*
X651726Y-52675D01*
X646309Y-52210D01*
Y-48025D01*
G01X657351Y-40585D02*
X658392Y-39500D01*
X658809Y-38260D01*
X658392Y-37020D01*
X657143Y-35935D01*
X655267Y-35160D01*
X653392Y-34850D01*
X651101D01*
X649226Y-35160D01*
X647559Y-35935D01*
X646726Y-36865D01*
X646309Y-37950D01*
X646726Y-39190D01*
X647559Y-40120D01*
X648809Y-40740D01*
X650476Y-41050D01*
X651934Y-40740D01*
X653392Y-39965D01*
X654226Y-39035D01*
X654434Y-37950D01*
X654018Y-36710D01*
X652976Y-35780D01*
X651101Y-34850D01*
G01X649440Y759250D02*
X650370Y757791D01*
X651610Y756958D01*
X653005Y756750D01*
X654245Y756958D01*
X655485Y758000D01*
X656260Y759250D01*
X656415Y760500D01*
X656105Y761958D01*
X655020Y763000D01*
X653935Y763417D01*
X652540D01*
G01X653935D02*
X654865Y764042D01*
X655640Y765083D01*
X655950Y766333D01*
X655640Y767583D01*
X654865Y768625D01*
X653470Y769250D01*
X652075Y769042D01*
X650680Y768208D01*
G01X662305Y767167D02*
X663235Y768416D01*
X664320Y769042D01*
X665560Y769250D01*
X667110Y768833D01*
X668195Y767792D01*
X668505Y766542D01*
X668350Y765291D01*
X667730Y764250D01*
X664630Y762167D01*
X663235Y760708D01*
X662305Y758625D01*
X661995Y756750D01*
X668505D01*
G01X677650D02*
X678735Y756958D01*
X679975Y757583D01*
X680750Y758625D01*
X681060Y760083D01*
X680750Y761541D01*
X679820Y762792D01*
X678425Y763417D01*
X676875D01*
X675945Y763833D01*
X675170Y764875D01*
X674860Y766333D01*
X675325Y767792D01*
X676410Y768833D01*
X677650Y769250D01*
X678890Y768833D01*
X679975Y767792D01*
X680440Y766333D01*
X680130Y764875D01*
X679355Y763833D01*
X678425Y763417D01*
X676875D01*
X675480Y762792D01*
X674550Y761541D01*
X674240Y760083D01*
X674550Y758625D01*
X675325Y757583D01*
X676565Y756958D01*
X677650Y756750D01*
G01X683809Y-106000D02*
X671309D01*
X673809Y-107860D01*
G01X683809D02*
Y-104140D01*
G01X678601Y-96545D02*
X677142Y-95460D01*
X676309Y-94530D01*
X675892Y-93290D01*
X676309Y-92205D01*
X677142Y-91430D01*
X678392Y-90810D01*
X679851Y-90655D01*
X681101Y-90810D01*
X682351Y-91430D01*
X683392Y-92360D01*
X683809Y-93445D01*
X683392Y-94685D01*
X682143Y-95770D01*
X680267Y-96390D01*
X678184Y-96545D01*
X675476Y-96235D01*
X674017Y-95770D01*
X672559Y-94995D01*
X671517Y-93910D01*
X671309Y-92825D01*
X671726Y-91740D01*
X672767Y-90965D01*
G01X683809Y-81200D02*
X683601Y-80115D01*
X682976Y-78875D01*
X681934Y-78100D01*
X680476Y-77790D01*
X679018Y-78100D01*
X677767Y-79030D01*
X677142Y-80425D01*
Y-81975D01*
X676726Y-82905D01*
X675684Y-83680D01*
X674226Y-83990D01*
X672767Y-83525D01*
X671726Y-82440D01*
X671309Y-81200D01*
X671726Y-79960D01*
X672767Y-78875D01*
X674226Y-78410D01*
X675684Y-78720D01*
X676726Y-79495D01*
X677142Y-80425D01*
Y-81975D01*
X677767Y-83370D01*
X679018Y-84300D01*
X680476Y-84610D01*
X681934Y-84300D01*
X682976Y-83525D01*
X683601Y-82285D01*
X683809Y-81200D01*
G01X684226Y-68800D02*
X684017Y-69110D01*
X683601D01*
X683392Y-68800D01*
X683601Y-68490D01*
X684017D01*
X684226Y-68800D01*
G01X682351Y-59035D02*
X683392Y-57950D01*
X683809Y-56710D01*
X683392Y-55470D01*
X682143Y-54385D01*
X680267Y-53610D01*
X678392Y-53300D01*
X676101D01*
X674226Y-53610D01*
X672559Y-54385D01*
X671726Y-55315D01*
X671309Y-56400D01*
X671726Y-57640D01*
X672559Y-58570D01*
X673809Y-59190D01*
X675476Y-59500D01*
X676934Y-59190D01*
X678392Y-58415D01*
X679226Y-57485D01*
X679434Y-56400D01*
X679018Y-55160D01*
X677976Y-54230D01*
X676101Y-53300D01*
G01X673392Y-46945D02*
X672143Y-46015D01*
X671517Y-44930D01*
X671309Y-43690D01*
X671726Y-42140D01*
X672767Y-41055D01*
X674017Y-40745D01*
X675268Y-40900D01*
X676309Y-41520D01*
X678392Y-44620D01*
X679851Y-46015D01*
X681934Y-46945D01*
X683809Y-47255D01*
Y-40745D01*
G01X871260Y678150D02*
X871052Y679235D01*
X870427Y680475D01*
X869385Y681250D01*
X867927Y681560D01*
X866469Y681250D01*
X865218Y680320D01*
X864593Y678925D01*
Y677375D01*
X864177Y676445D01*
X863135Y675670D01*
X861677Y675360D01*
X860218Y675825D01*
X859177Y676910D01*
X858760Y678150D01*
X859177Y679390D01*
X860218Y680475D01*
X861677Y680940D01*
X863135Y680630D01*
X864177Y679855D01*
X864593Y678925D01*
Y677375D01*
X865218Y675980D01*
X866469Y675050D01*
X867927Y674740D01*
X869385Y675050D01*
X870427Y675825D01*
X871052Y677065D01*
X871260Y678150D01*
G01Y690240D02*
X868552Y690550D01*
X866260Y691015D01*
X864177Y691635D01*
X861885Y692410D01*
X858760Y693650D01*
Y687450D01*
G01X871260Y702640D02*
X868552Y702950D01*
X866260Y703415D01*
X864177Y704035D01*
X861885Y704810D01*
X858760Y706050D01*
Y699850D01*
G01X869385Y711940D02*
X870427Y712870D01*
X871052Y713955D01*
X871260Y715350D01*
X870843Y716745D01*
X870010Y717830D01*
X868552Y718605D01*
X866885Y718760D01*
X865218Y718450D01*
X864177Y717675D01*
X863343Y716590D01*
X863135Y715505D01*
X863343Y714420D01*
X864177Y713025D01*
X858760Y713490D01*
Y717675D01*
G01X871677Y727750D02*
X871468Y727440D01*
X871052D01*
X870843Y727750D01*
X871052Y728060D01*
X871468D01*
X871677Y727750D01*
G01X871260Y740150D02*
X858760D01*
X861260Y738290D01*
G01X871260D02*
Y742010D01*
G01X858760Y752550D02*
X859177Y751310D01*
X860218Y750380D01*
X861468Y749760D01*
X863135Y749295D01*
X865010Y749140D01*
X866885Y749295D01*
X868552Y749760D01*
X869802Y750380D01*
X870843Y751310D01*
X871260Y752550D01*
X870843Y753790D01*
X869802Y754720D01*
X868552Y755340D01*
X866885Y755805D01*
X865010Y755960D01*
X863135Y755805D01*
X861468Y755340D01*
X860218Y754720D01*
X859177Y753790D01*
X858760Y752550D01*
G01X885843Y681555D02*
X884594Y682485D01*
X883968Y683570D01*
X883760Y684810D01*
X884177Y686360D01*
X885218Y687445D01*
X886468Y687755D01*
X887719Y687600D01*
X888760Y686980D01*
X890843Y683880D01*
X892302Y682485D01*
X894385Y681555D01*
X896260Y681245D01*
Y687755D01*
G01X885843Y693955D02*
X884594Y694885D01*
X883968Y695970D01*
X883760Y697210D01*
X884177Y698760D01*
X885218Y699845D01*
X886468Y700155D01*
X887719Y700000D01*
X888760Y699380D01*
X890843Y696280D01*
X892302Y694885D01*
X894385Y693955D01*
X896260Y693645D01*
Y700155D01*
G01X885843Y706355D02*
X884594Y707285D01*
X883968Y708370D01*
X883760Y709610D01*
X884177Y711160D01*
X885218Y712245D01*
X886468Y712555D01*
X887719Y712400D01*
X888760Y711780D01*
X890843Y708680D01*
X892302Y707285D01*
X894385Y706355D01*
X896260Y706045D01*
Y712555D01*
G01X896677Y721700D02*
X896468Y721390D01*
X896052D01*
X895843Y721700D01*
X896052Y722010D01*
X896468D01*
X896677Y721700D01*
G01X896260Y734100D02*
X896052Y735185D01*
X895427Y736425D01*
X894385Y737200D01*
X892927Y737510D01*
X891469Y737200D01*
X890218Y736270D01*
X889593Y734875D01*
Y733325D01*
X889177Y732395D01*
X888135Y731620D01*
X886677Y731310D01*
X885218Y731775D01*
X884177Y732860D01*
X883760Y734100D01*
X884177Y735340D01*
X885218Y736425D01*
X886677Y736890D01*
X888135Y736580D01*
X889177Y735805D01*
X889593Y734875D01*
Y733325D01*
X890218Y731930D01*
X891469Y731000D01*
X892927Y730690D01*
X894385Y731000D01*
X895427Y731775D01*
X896052Y733015D01*
X896260Y734100D01*
G01X894802Y743865D02*
X895843Y744950D01*
X896260Y746190D01*
X895843Y747430D01*
X894594Y748515D01*
X892718Y749290D01*
X890843Y749600D01*
X888552D01*
X886677Y749290D01*
X885010Y748515D01*
X884177Y747585D01*
X883760Y746500D01*
X884177Y745260D01*
X885010Y744330D01*
X886260Y743710D01*
X887927Y743400D01*
X889385Y743710D01*
X890843Y744485D01*
X891677Y745415D01*
X891885Y746500D01*
X891469Y747740D01*
X890427Y748670D01*
X888552Y749600D01*
G01X908850Y-53867D02*
X901350D01*
Y-51627D01*
X901725Y-50880D01*
X902600Y-50320D01*
X903600Y-50133D01*
X904600Y-50320D01*
X905350Y-50787D01*
X905725Y-51627D01*
Y-53867D01*
G01X901350Y-44500D02*
X908850D01*
G01X901350Y-46647D02*
Y-42353D01*
G01X908850Y-38960D02*
X901350D01*
G01Y-35040D02*
X908850D01*
G01X905100D02*
Y-38960D01*
G01X958850Y671133D02*
X951350D01*
Y673373D01*
X951725Y674120D01*
X952600Y674680D01*
X953600Y674867D01*
X954600Y674680D01*
X955350Y674213D01*
X955725Y673373D01*
Y671133D01*
G01X951350Y680500D02*
X958850D01*
G01X951350Y678353D02*
Y682647D01*
G01X958850Y686040D02*
X951350D01*
G01Y689960D02*
X958850D01*
G01X955100D02*
Y686040D01*
G01X972351Y-114985D02*
X973392Y-113900D01*
X973809Y-112660D01*
X973392Y-111420D01*
X972143Y-110335D01*
X970267Y-109560D01*
X968392Y-109250D01*
X966101D01*
X964226Y-109560D01*
X962559Y-110335D01*
X961726Y-111265D01*
X961309Y-112350D01*
X961726Y-113590D01*
X962559Y-114520D01*
X963809Y-115140D01*
X965476Y-115450D01*
X966934Y-115140D01*
X968392Y-114365D01*
X969226Y-113435D01*
X969434Y-112350D01*
X969018Y-111110D01*
X967976Y-110180D01*
X966101Y-109250D01*
G01X973809Y-99950D02*
X973601Y-98865D01*
X972976Y-97625D01*
X971934Y-96850D01*
X970476Y-96540D01*
X969018Y-96850D01*
X967767Y-97780D01*
X967142Y-99175D01*
Y-100725D01*
X966726Y-101655D01*
X965684Y-102430D01*
X964226Y-102740D01*
X962767Y-102275D01*
X961726Y-101190D01*
X961309Y-99950D01*
X961726Y-98710D01*
X962767Y-97625D01*
X964226Y-97160D01*
X965684Y-97470D01*
X966726Y-98245D01*
X967142Y-99175D01*
Y-100725D01*
X967767Y-102120D01*
X969018Y-103050D01*
X970476Y-103360D01*
X971934Y-103050D01*
X972976Y-102275D01*
X973601Y-101035D01*
X973809Y-99950D01*
G01X961309Y-87550D02*
X961726Y-88790D01*
X962767Y-89720D01*
X964017Y-90340D01*
X965684Y-90805D01*
X967559Y-90960D01*
X969434Y-90805D01*
X971101Y-90340D01*
X972351Y-89720D01*
X973392Y-88790D01*
X973809Y-87550D01*
X973392Y-86310D01*
X972351Y-85380D01*
X971101Y-84760D01*
X969434Y-84295D01*
X967559Y-84140D01*
X965684Y-84295D01*
X964017Y-84760D01*
X962767Y-85380D01*
X961726Y-86310D01*
X961309Y-87550D01*
G01Y-75150D02*
X961726Y-76390D01*
X962767Y-77320D01*
X964017Y-77940D01*
X965684Y-78405D01*
X967559Y-78560D01*
X969434Y-78405D01*
X971101Y-77940D01*
X972351Y-77320D01*
X973392Y-76390D01*
X973809Y-75150D01*
X973392Y-73910D01*
X972351Y-72980D01*
X971101Y-72360D01*
X969434Y-71895D01*
X967559Y-71740D01*
X965684Y-71895D01*
X964017Y-72360D01*
X962767Y-72980D01*
X961726Y-73910D01*
X961309Y-75150D01*
G01X974226Y-62750D02*
X974017Y-63060D01*
X973601D01*
X973392Y-62750D01*
X973601Y-62440D01*
X974017D01*
X974226Y-62750D01*
G01X971934Y-53760D02*
X972976Y-52830D01*
X973601Y-51745D01*
X973809Y-50350D01*
X973392Y-48955D01*
X972559Y-47870D01*
X971101Y-47095D01*
X969434Y-46940D01*
X967767Y-47250D01*
X966726Y-48025D01*
X965892Y-49110D01*
X965684Y-50195D01*
X965892Y-51280D01*
X966726Y-52675D01*
X961309Y-52210D01*
Y-48025D01*
G01X972351Y-40585D02*
X973392Y-39500D01*
X973809Y-38260D01*
X973392Y-37020D01*
X972143Y-35935D01*
X970267Y-35160D01*
X968392Y-34850D01*
X966101D01*
X964226Y-35160D01*
X962559Y-35935D01*
X961726Y-36865D01*
X961309Y-37950D01*
X961726Y-39190D01*
X962559Y-40120D01*
X963809Y-40740D01*
X965476Y-41050D01*
X966934Y-40740D01*
X968392Y-39965D01*
X969226Y-39035D01*
X969434Y-37950D01*
X969018Y-36710D01*
X967976Y-35780D01*
X966101Y-34850D01*
G01X980792Y675515D02*
X981833Y676600D01*
X982250Y677840D01*
X981833Y679080D01*
X980584Y680165D01*
X978708Y680940D01*
X976833Y681250D01*
X974542D01*
X972667Y680940D01*
X971000Y680165D01*
X970167Y679235D01*
X969750Y678150D01*
X970167Y676910D01*
X971000Y675980D01*
X972250Y675360D01*
X973917Y675050D01*
X975375Y675360D01*
X976833Y676135D01*
X977667Y677065D01*
X977875Y678150D01*
X977459Y679390D01*
X976417Y680320D01*
X974542Y681250D01*
G01X982250Y690550D02*
X982042Y691635D01*
X981417Y692875D01*
X980375Y693650D01*
X978917Y693960D01*
X977459Y693650D01*
X976208Y692720D01*
X975583Y691325D01*
Y689775D01*
X975167Y688845D01*
X974125Y688070D01*
X972667Y687760D01*
X971208Y688225D01*
X970167Y689310D01*
X969750Y690550D01*
X970167Y691790D01*
X971208Y692875D01*
X972667Y693340D01*
X974125Y693030D01*
X975167Y692255D01*
X975583Y691325D01*
Y689775D01*
X976208Y688380D01*
X977459Y687450D01*
X978917Y687140D01*
X980375Y687450D01*
X981417Y688225D01*
X982042Y689465D01*
X982250Y690550D01*
G01Y702950D02*
X982042Y704035D01*
X981417Y705275D01*
X980375Y706050D01*
X978917Y706360D01*
X977459Y706050D01*
X976208Y705120D01*
X975583Y703725D01*
Y702175D01*
X975167Y701245D01*
X974125Y700470D01*
X972667Y700160D01*
X971208Y700625D01*
X970167Y701710D01*
X969750Y702950D01*
X970167Y704190D01*
X971208Y705275D01*
X972667Y705740D01*
X974125Y705430D01*
X975167Y704655D01*
X975583Y703725D01*
Y702175D01*
X976208Y700780D01*
X977459Y699850D01*
X978917Y699540D01*
X980375Y699850D01*
X981417Y700625D01*
X982042Y701865D01*
X982250Y702950D01*
G01X980375Y711940D02*
X981417Y712870D01*
X982042Y713955D01*
X982250Y715350D01*
X981833Y716745D01*
X981000Y717830D01*
X979542Y718605D01*
X977875Y718760D01*
X976208Y718450D01*
X975167Y717675D01*
X974333Y716590D01*
X974125Y715505D01*
X974333Y714420D01*
X975167Y713025D01*
X969750Y713490D01*
Y717675D01*
G01X982667Y727750D02*
X982458Y727440D01*
X982042D01*
X981833Y727750D01*
X982042Y728060D01*
X982458D01*
X982667Y727750D01*
G01X969750Y740150D02*
X970167Y738910D01*
X971208Y737980D01*
X972458Y737360D01*
X974125Y736895D01*
X976000Y736740D01*
X977875Y736895D01*
X979542Y737360D01*
X980792Y737980D01*
X981833Y738910D01*
X982250Y740150D01*
X981833Y741390D01*
X980792Y742320D01*
X979542Y742940D01*
X977875Y743405D01*
X976000Y743560D01*
X974125Y743405D01*
X972458Y742940D01*
X971208Y742320D01*
X970167Y741390D01*
X969750Y740150D01*
G01Y752550D02*
X970167Y751310D01*
X971208Y750380D01*
X972458Y749760D01*
X974125Y749295D01*
X976000Y749140D01*
X977875Y749295D01*
X979542Y749760D01*
X980792Y750380D01*
X981833Y751310D01*
X982250Y752550D01*
X981833Y753790D01*
X980792Y754720D01*
X979542Y755340D01*
X977875Y755805D01*
X976000Y755960D01*
X974125Y755805D01*
X972458Y755340D01*
X971208Y754720D01*
X970167Y753790D01*
X969750Y752550D01*
G01X988392Y-108945D02*
X987143Y-108015D01*
X986517Y-106930D01*
X986309Y-105690D01*
X986726Y-104140D01*
X987767Y-103055D01*
X989017Y-102745D01*
X990268Y-102900D01*
X991309Y-103520D01*
X993392Y-106620D01*
X994851Y-108015D01*
X996934Y-108945D01*
X998809Y-109255D01*
Y-102745D01*
G01Y-91740D02*
X986309D01*
X995267Y-97475D01*
Y-89725D01*
G01X998809Y-81200D02*
X998601Y-80115D01*
X997976Y-78875D01*
X996934Y-78100D01*
X995476Y-77790D01*
X994018Y-78100D01*
X992767Y-79030D01*
X992142Y-80425D01*
Y-81975D01*
X991726Y-82905D01*
X990684Y-83680D01*
X989226Y-83990D01*
X987767Y-83525D01*
X986726Y-82440D01*
X986309Y-81200D01*
X986726Y-79960D01*
X987767Y-78875D01*
X989226Y-78410D01*
X990684Y-78720D01*
X991726Y-79495D01*
X992142Y-80425D01*
Y-81975D01*
X992767Y-83370D01*
X994018Y-84300D01*
X995476Y-84610D01*
X996934Y-84300D01*
X997976Y-83525D01*
X998601Y-82285D01*
X998809Y-81200D01*
G01X999226Y-68800D02*
X999017Y-69110D01*
X998601D01*
X998392Y-68800D01*
X998601Y-68490D01*
X999017D01*
X999226Y-68800D01*
G01X997351Y-59035D02*
X998392Y-57950D01*
X998809Y-56710D01*
X998392Y-55470D01*
X997143Y-54385D01*
X995267Y-53610D01*
X993392Y-53300D01*
X991101D01*
X989226Y-53610D01*
X987559Y-54385D01*
X986726Y-55315D01*
X986309Y-56400D01*
X986726Y-57640D01*
X987559Y-58570D01*
X988809Y-59190D01*
X990476Y-59500D01*
X991934Y-59190D01*
X993392Y-58415D01*
X994226Y-57485D01*
X994434Y-56400D01*
X994018Y-55160D01*
X992976Y-54230D01*
X991101Y-53300D01*
G01X996309Y-47410D02*
X997768Y-46480D01*
X998601Y-45240D01*
X998809Y-43845D01*
X998601Y-42605D01*
X997559Y-41365D01*
X996309Y-40590D01*
X995059Y-40435D01*
X993601Y-40745D01*
X992559Y-41830D01*
X992142Y-42915D01*
Y-44310D01*
G01Y-42915D02*
X991517Y-41985D01*
X990476Y-41210D01*
X989226Y-40900D01*
X987976Y-41210D01*
X986934Y-41985D01*
X986309Y-43380D01*
X986517Y-44775D01*
X987351Y-46170D01*
G01X996833Y681555D02*
X995584Y682485D01*
X994958Y683570D01*
X994750Y684810D01*
X995167Y686360D01*
X996208Y687445D01*
X997458Y687755D01*
X998709Y687600D01*
X999750Y686980D01*
X1001833Y683880D01*
X1003292Y682485D01*
X1005375Y681555D01*
X1007250Y681245D01*
Y687755D01*
G01X1005375Y693490D02*
X1006417Y694420D01*
X1007042Y695505D01*
X1007250Y696900D01*
X1006833Y698295D01*
X1006000Y699380D01*
X1004542Y700155D01*
X1002875Y700310D01*
X1001208Y700000D01*
X1000167Y699225D01*
X999333Y698140D01*
X999125Y697055D01*
X999333Y695970D01*
X1000167Y694575D01*
X994750Y695040D01*
Y699225D01*
G01X1007250Y709300D02*
X994750D01*
X997250Y707440D01*
G01X1007250D02*
Y711160D01*
G01X1007667Y721700D02*
X1007458Y721390D01*
X1007042D01*
X1006833Y721700D01*
X1007042Y722010D01*
X1007458D01*
X1007667Y721700D01*
G01X994750Y734100D02*
X995167Y732860D01*
X996208Y731930D01*
X997458Y731310D01*
X999125Y730845D01*
X1001000Y730690D01*
X1002875Y730845D01*
X1004542Y731310D01*
X1005792Y731930D01*
X1006833Y732860D01*
X1007250Y734100D01*
X1006833Y735340D01*
X1005792Y736270D01*
X1004542Y736890D01*
X1002875Y737355D01*
X1001000Y737510D01*
X999125Y737355D01*
X997458Y736890D01*
X996208Y736270D01*
X995167Y735340D01*
X994750Y734100D01*
G01X1007250Y746500D02*
X1007042Y747585D01*
X1006417Y748825D01*
X1005375Y749600D01*
X1003917Y749910D01*
X1002459Y749600D01*
X1001208Y748670D01*
X1000583Y747275D01*
Y745725D01*
X1000167Y744795D01*
X999125Y744020D01*
X997667Y743710D01*
X996208Y744175D01*
X995167Y745260D01*
X994750Y746500D01*
X995167Y747740D01*
X996208Y748825D01*
X997667Y749290D01*
X999125Y748980D01*
X1000167Y748205D01*
X1000583Y747275D01*
Y745725D01*
X1001208Y744330D01*
X1002459Y743400D01*
X1003917Y743090D01*
X1005375Y743400D01*
X1006417Y744175D01*
X1007042Y745415D01*
X1007250Y746500D01*
G01X1024250Y672100D02*
X1011750D01*
X1014250Y670240D01*
G01X1024250D02*
Y673960D01*
G01X1011750Y684500D02*
X1012167Y683260D01*
X1013208Y682330D01*
X1014458Y681710D01*
X1016125Y681245D01*
X1018000Y681090D01*
X1019875Y681245D01*
X1021542Y681710D01*
X1022792Y682330D01*
X1023833Y683260D01*
X1024250Y684500D01*
X1023833Y685740D01*
X1022792Y686670D01*
X1021542Y687290D01*
X1019875Y687755D01*
X1018000Y687910D01*
X1016125Y687755D01*
X1014458Y687290D01*
X1013208Y686670D01*
X1012167Y685740D01*
X1011750Y684500D01*
G01X1021750Y693490D02*
X1023209Y694420D01*
X1024042Y695660D01*
X1024250Y697055D01*
X1024042Y698295D01*
X1023000Y699535D01*
X1021750Y700310D01*
X1020500Y700465D01*
X1019042Y700155D01*
X1018000Y699070D01*
X1017583Y697985D01*
Y696590D01*
G01Y697985D02*
X1016958Y698915D01*
X1015917Y699690D01*
X1014667Y700000D01*
X1013417Y699690D01*
X1012375Y698915D01*
X1011750Y697520D01*
X1011958Y696125D01*
X1012792Y694730D01*
G01X1011750Y709300D02*
X1012167Y708060D01*
X1013208Y707130D01*
X1014458Y706510D01*
X1016125Y706045D01*
X1018000Y705890D01*
X1019875Y706045D01*
X1021542Y706510D01*
X1022792Y707130D01*
X1023833Y708060D01*
X1024250Y709300D01*
X1023833Y710540D01*
X1022792Y711470D01*
X1021542Y712090D01*
X1019875Y712555D01*
X1018000Y712710D01*
X1016125Y712555D01*
X1014458Y712090D01*
X1013208Y711470D01*
X1012167Y710540D01*
X1011750Y709300D01*
G01X1022375Y718290D02*
X1023417Y719220D01*
X1024042Y720305D01*
X1024250Y721700D01*
X1023833Y723095D01*
X1023000Y724180D01*
X1021542Y724955D01*
X1019875Y725110D01*
X1018208Y724800D01*
X1017167Y724025D01*
X1016333Y722940D01*
X1016125Y721855D01*
X1016333Y720770D01*
X1017167Y719375D01*
X1011750Y719840D01*
Y724025D01*
G01X1024667Y734100D02*
X1024458Y733790D01*
X1024042D01*
X1023833Y734100D01*
X1024042Y734410D01*
X1024458D01*
X1024667Y734100D01*
G01X1011750Y746500D02*
X1012167Y745260D01*
X1013208Y744330D01*
X1014458Y743710D01*
X1016125Y743245D01*
X1018000Y743090D01*
X1019875Y743245D01*
X1021542Y743710D01*
X1022792Y744330D01*
X1023833Y745260D01*
X1024250Y746500D01*
X1023833Y747740D01*
X1022792Y748670D01*
X1021542Y749290D01*
X1019875Y749755D01*
X1018000Y749910D01*
X1016125Y749755D01*
X1014458Y749290D01*
X1013208Y748670D01*
X1012167Y747740D01*
X1011750Y746500D01*
G01Y758900D02*
X1012167Y757660D01*
X1013208Y756730D01*
X1014458Y756110D01*
X1016125Y755645D01*
X1018000Y755490D01*
X1019875Y755645D01*
X1021542Y756110D01*
X1022792Y756730D01*
X1023833Y757660D01*
X1024250Y758900D01*
X1023833Y760140D01*
X1022792Y761070D01*
X1021542Y761690D01*
X1019875Y762155D01*
X1018000Y762310D01*
X1016125Y762155D01*
X1014458Y761690D01*
X1013208Y761070D01*
X1012167Y760140D01*
X1011750Y758900D01*
G01X1038833Y681705D02*
X1037584Y682635D01*
X1036958Y683720D01*
X1036750Y684960D01*
X1037167Y686510D01*
X1038208Y687595D01*
X1039458Y687905D01*
X1040709Y687750D01*
X1041750Y687130D01*
X1043833Y684030D01*
X1045292Y682635D01*
X1047375Y681705D01*
X1049250Y681395D01*
Y687905D01*
G01X1044042Y694105D02*
X1042583Y695190D01*
X1041750Y696120D01*
X1041333Y697360D01*
X1041750Y698445D01*
X1042583Y699220D01*
X1043833Y699840D01*
X1045292Y699995D01*
X1046542Y699840D01*
X1047792Y699220D01*
X1048833Y698290D01*
X1049250Y697205D01*
X1048833Y695965D01*
X1047584Y694880D01*
X1045708Y694260D01*
X1043625Y694105D01*
X1040917Y694415D01*
X1039458Y694880D01*
X1038000Y695655D01*
X1036958Y696740D01*
X1036750Y697825D01*
X1037167Y698910D01*
X1038208Y699685D01*
G01X1049250Y709450D02*
X1036750D01*
X1039250Y707590D01*
G01X1049250D02*
Y711310D01*
G01X1049667Y721850D02*
X1049458Y721540D01*
X1049042D01*
X1048833Y721850D01*
X1049042Y722160D01*
X1049458D01*
X1049667Y721850D01*
G01X1049250Y733940D02*
X1046542Y734250D01*
X1044250Y734715D01*
X1042167Y735335D01*
X1039875Y736110D01*
X1036750Y737350D01*
Y731150D01*
G01X1047375Y743240D02*
X1048417Y744170D01*
X1049042Y745255D01*
X1049250Y746650D01*
X1048833Y748045D01*
X1048000Y749130D01*
X1046542Y749905D01*
X1044875Y750060D01*
X1043208Y749750D01*
X1042167Y748975D01*
X1041333Y747890D01*
X1041125Y746805D01*
X1041333Y745720D01*
X1042167Y744325D01*
X1036750Y744790D01*
Y748975D01*
G01X1063850Y671133D02*
X1056350D01*
Y673373D01*
X1056725Y674120D01*
X1057600Y674680D01*
X1058600Y674867D01*
X1059600Y674680D01*
X1060350Y674213D01*
X1060725Y673373D01*
Y671133D01*
G01X1056350Y680500D02*
X1063850D01*
G01X1056350Y678353D02*
Y682647D01*
G01X1063850Y686040D02*
X1056350D01*
G01Y689960D02*
X1063850D01*
G01X1060100D02*
Y686040D01*
G01X1173850Y-117900D02*
X1161350D01*
X1163850Y-119760D01*
G01X1173850D02*
Y-116040D01*
G01X1163433Y-108445D02*
X1162184Y-107515D01*
X1161558Y-106430D01*
X1161350Y-105190D01*
X1161767Y-103640D01*
X1162808Y-102555D01*
X1164058Y-102245D01*
X1165309Y-102400D01*
X1166350Y-103020D01*
X1168433Y-106120D01*
X1169892Y-107515D01*
X1171975Y-108445D01*
X1173850Y-108755D01*
Y-102245D01*
G01X1163433Y-96045D02*
X1162184Y-95115D01*
X1161558Y-94030D01*
X1161350Y-92790D01*
X1161767Y-91240D01*
X1162808Y-90155D01*
X1164058Y-89845D01*
X1165309Y-90000D01*
X1166350Y-90620D01*
X1168433Y-93720D01*
X1169892Y-95115D01*
X1171975Y-96045D01*
X1173850Y-96355D01*
Y-89845D01*
G01X1168642Y-83645D02*
X1167183Y-82560D01*
X1166350Y-81630D01*
X1165933Y-80390D01*
X1166350Y-79305D01*
X1167183Y-78530D01*
X1168433Y-77910D01*
X1169892Y-77755D01*
X1171142Y-77910D01*
X1172392Y-78530D01*
X1173433Y-79460D01*
X1173850Y-80545D01*
X1173433Y-81785D01*
X1172184Y-82870D01*
X1170308Y-83490D01*
X1168225Y-83645D01*
X1165517Y-83335D01*
X1164058Y-82870D01*
X1162600Y-82095D01*
X1161558Y-81010D01*
X1161350Y-79925D01*
X1161767Y-78840D01*
X1162808Y-78065D01*
G01X1161350Y-68300D02*
X1161767Y-69540D01*
X1162808Y-70470D01*
X1164058Y-71090D01*
X1165725Y-71555D01*
X1167600Y-71710D01*
X1169475Y-71555D01*
X1171142Y-71090D01*
X1172392Y-70470D01*
X1173433Y-69540D01*
X1173850Y-68300D01*
X1173433Y-67060D01*
X1172392Y-66130D01*
X1171142Y-65510D01*
X1169475Y-65045D01*
X1167600Y-64890D01*
X1165725Y-65045D01*
X1164058Y-65510D01*
X1162808Y-66130D01*
X1161767Y-67060D01*
X1161350Y-68300D01*
G01X1174267Y-55900D02*
X1174058Y-56210D01*
X1173642D01*
X1173433Y-55900D01*
X1173642Y-55590D01*
X1174058D01*
X1174267Y-55900D01*
G01X1163433Y-46445D02*
X1162184Y-45515D01*
X1161558Y-44430D01*
X1161350Y-43190D01*
X1161767Y-41640D01*
X1162808Y-40555D01*
X1164058Y-40245D01*
X1165309Y-40400D01*
X1166350Y-41020D01*
X1168433Y-44120D01*
X1169892Y-45515D01*
X1171975Y-46445D01*
X1173850Y-46755D01*
Y-40245D01*
G01Y-29240D02*
X1161350D01*
X1170308Y-34975D01*
Y-27225D01*
G01X1196350Y-108760D02*
X1197809Y-107830D01*
X1198642Y-106590D01*
X1198850Y-105195D01*
X1198642Y-103955D01*
X1197600Y-102715D01*
X1196350Y-101940D01*
X1195100Y-101785D01*
X1193642Y-102095D01*
X1192600Y-103180D01*
X1192183Y-104265D01*
Y-105660D01*
G01Y-104265D02*
X1191558Y-103335D01*
X1190517Y-102560D01*
X1189267Y-102250D01*
X1188017Y-102560D01*
X1186975Y-103335D01*
X1186350Y-104730D01*
X1186558Y-106125D01*
X1187392Y-107520D01*
G01X1198850Y-92950D02*
X1186350D01*
X1188850Y-94810D01*
G01X1198850D02*
Y-91090D01*
G01Y-80550D02*
X1186350D01*
X1188850Y-82410D01*
G01X1198850D02*
Y-78690D01*
G01X1199267Y-68150D02*
X1199058Y-68460D01*
X1198642D01*
X1198433Y-68150D01*
X1198642Y-67840D01*
X1199058D01*
X1199267Y-68150D01*
G01X1198850Y-53890D02*
X1186350D01*
X1195308Y-59625D01*
Y-51875D01*
G01X1198850Y-43350D02*
X1186350D01*
X1188850Y-45210D01*
G01X1198850D02*
Y-41490D01*
G01X1219774Y672100D02*
X1207274D01*
X1209774Y670240D01*
G01X1219774D02*
Y673960D01*
G01X1209357Y681555D02*
X1208108Y682485D01*
X1207482Y683570D01*
X1207274Y684810D01*
X1207691Y686360D01*
X1208732Y687445D01*
X1209982Y687755D01*
X1211233Y687600D01*
X1212274Y686980D01*
X1214357Y683880D01*
X1215816Y682485D01*
X1217899Y681555D01*
X1219774Y681245D01*
Y687755D01*
G01X1209357Y693955D02*
X1208108Y694885D01*
X1207482Y695970D01*
X1207274Y697210D01*
X1207691Y698760D01*
X1208732Y699845D01*
X1209982Y700155D01*
X1211233Y700000D01*
X1212274Y699380D01*
X1214357Y696280D01*
X1215816Y694885D01*
X1217899Y693955D01*
X1219774Y693645D01*
Y700155D01*
G01X1214566Y706355D02*
X1213107Y707440D01*
X1212274Y708370D01*
X1211857Y709610D01*
X1212274Y710695D01*
X1213107Y711470D01*
X1214357Y712090D01*
X1215816Y712245D01*
X1217066Y712090D01*
X1218316Y711470D01*
X1219357Y710540D01*
X1219774Y709455D01*
X1219357Y708215D01*
X1218108Y707130D01*
X1216232Y706510D01*
X1214149Y706355D01*
X1211441Y706665D01*
X1209982Y707130D01*
X1208524Y707905D01*
X1207482Y708990D01*
X1207274Y710075D01*
X1207691Y711160D01*
X1208732Y711935D01*
G01X1207274Y721700D02*
X1207691Y720460D01*
X1208732Y719530D01*
X1209982Y718910D01*
X1211649Y718445D01*
X1213524Y718290D01*
X1215399Y718445D01*
X1217066Y718910D01*
X1218316Y719530D01*
X1219357Y720460D01*
X1219774Y721700D01*
X1219357Y722940D01*
X1218316Y723870D01*
X1217066Y724490D01*
X1215399Y724955D01*
X1213524Y725110D01*
X1211649Y724955D01*
X1209982Y724490D01*
X1208732Y723870D01*
X1207691Y722940D01*
X1207274Y721700D01*
G01X1220191Y734100D02*
X1219982Y733790D01*
X1219566D01*
X1219357Y734100D01*
X1219566Y734410D01*
X1219982D01*
X1220191Y734100D01*
G01X1209357Y743555D02*
X1208108Y744485D01*
X1207482Y745570D01*
X1207274Y746810D01*
X1207691Y748360D01*
X1208732Y749445D01*
X1209982Y749755D01*
X1211233Y749600D01*
X1212274Y748980D01*
X1214357Y745880D01*
X1215816Y744485D01*
X1217899Y743555D01*
X1219774Y743245D01*
Y749755D01*
G01Y760760D02*
X1207274D01*
X1216232Y755025D01*
Y762775D01*
G01X1233908Y-118400D02*
X1221408D01*
X1223908Y-120260D01*
G01X1233908D02*
Y-116540D01*
G01X1223491Y-108945D02*
X1222242Y-108015D01*
X1221616Y-106930D01*
X1221408Y-105690D01*
X1221825Y-104140D01*
X1222866Y-103055D01*
X1224116Y-102745D01*
X1225367Y-102900D01*
X1226408Y-103520D01*
X1228491Y-106620D01*
X1229950Y-108015D01*
X1232033Y-108945D01*
X1233908Y-109255D01*
Y-102745D01*
G01Y-91740D02*
X1221408D01*
X1230366Y-97475D01*
Y-89725D01*
G01X1221408Y-81200D02*
X1221825Y-82440D01*
X1222866Y-83370D01*
X1224116Y-83990D01*
X1225783Y-84455D01*
X1227658Y-84610D01*
X1229533Y-84455D01*
X1231200Y-83990D01*
X1232450Y-83370D01*
X1233491Y-82440D01*
X1233908Y-81200D01*
X1233491Y-79960D01*
X1232450Y-79030D01*
X1231200Y-78410D01*
X1229533Y-77945D01*
X1227658Y-77790D01*
X1225783Y-77945D01*
X1224116Y-78410D01*
X1222866Y-79030D01*
X1221825Y-79960D01*
X1221408Y-81200D01*
G01X1233908Y-68800D02*
X1221408D01*
X1223908Y-70660D01*
G01X1233908D02*
Y-66940D01*
G01X1234325Y-56400D02*
X1234116Y-56710D01*
X1233700D01*
X1233491Y-56400D01*
X1233700Y-56090D01*
X1234116D01*
X1234325Y-56400D01*
G01X1232033Y-47410D02*
X1233075Y-46480D01*
X1233700Y-45395D01*
X1233908Y-44000D01*
X1233491Y-42605D01*
X1232658Y-41520D01*
X1231200Y-40745D01*
X1229533Y-40590D01*
X1227866Y-40900D01*
X1226825Y-41675D01*
X1225991Y-42760D01*
X1225783Y-43845D01*
X1225991Y-44930D01*
X1226825Y-46325D01*
X1221408Y-45860D01*
Y-41675D01*
G01X1233908Y-31600D02*
X1233700Y-30515D01*
X1233075Y-29275D01*
X1232033Y-28500D01*
X1230575Y-28190D01*
X1229117Y-28500D01*
X1227866Y-29430D01*
X1227241Y-30825D01*
Y-32375D01*
X1226825Y-33305D01*
X1225783Y-34080D01*
X1224325Y-34390D01*
X1222866Y-33925D01*
X1221825Y-32840D01*
X1221408Y-31600D01*
X1221825Y-30360D01*
X1222866Y-29275D01*
X1224325Y-28810D01*
X1225783Y-29120D01*
X1226825Y-29895D01*
X1227241Y-30825D01*
Y-32375D01*
X1227866Y-33770D01*
X1229117Y-34700D01*
X1230575Y-35010D01*
X1232033Y-34700D01*
X1233075Y-33925D01*
X1233700Y-32685D01*
X1233908Y-31600D01*
G01X1256408Y-90660D02*
X1257867Y-89730D01*
X1258700Y-88490D01*
X1258908Y-87095D01*
X1258700Y-85855D01*
X1257658Y-84615D01*
X1256408Y-83840D01*
X1255158Y-83685D01*
X1253700Y-83995D01*
X1252658Y-85080D01*
X1252241Y-86165D01*
Y-87560D01*
G01Y-86165D02*
X1251616Y-85235D01*
X1250575Y-84460D01*
X1249325Y-84150D01*
X1248075Y-84460D01*
X1247033Y-85235D01*
X1246408Y-86630D01*
X1246616Y-88025D01*
X1247450Y-89420D01*
G01X1258908Y-74850D02*
X1246408D01*
X1248908Y-76710D01*
G01X1258908D02*
Y-72990D01*
G01X1257033Y-65860D02*
X1258075Y-64930D01*
X1258700Y-63845D01*
X1258908Y-62450D01*
X1258491Y-61055D01*
X1257658Y-59970D01*
X1256200Y-59195D01*
X1254533Y-59040D01*
X1252866Y-59350D01*
X1251825Y-60125D01*
X1250991Y-61210D01*
X1250783Y-62295D01*
X1250991Y-63380D01*
X1251825Y-64775D01*
X1246408Y-64310D01*
Y-60125D01*
G01X1242274Y681240D02*
X1243733Y682170D01*
X1244566Y683410D01*
X1244774Y684805D01*
X1244566Y686045D01*
X1243524Y687285D01*
X1242274Y688060D01*
X1241024Y688215D01*
X1239566Y687905D01*
X1238524Y686820D01*
X1238107Y685735D01*
Y684340D01*
G01Y685735D02*
X1237482Y686665D01*
X1236441Y687440D01*
X1235191Y687750D01*
X1233941Y687440D01*
X1232899Y686665D01*
X1232274Y685270D01*
X1232482Y683875D01*
X1233316Y682480D01*
G01X1244774Y697050D02*
X1232274D01*
X1234774Y695190D01*
G01X1244774D02*
Y698910D01*
G01Y709450D02*
X1232274D01*
X1234774Y707590D01*
G01X1244774D02*
Y711310D01*
G01X1245191Y721850D02*
X1244982Y721540D01*
X1244566D01*
X1244357Y721850D01*
X1244566Y722160D01*
X1244982D01*
X1245191Y721850D01*
G01X1244774Y736110D02*
X1232274D01*
X1241232Y730375D01*
Y738125D01*
G01X1244774Y746650D02*
X1232274D01*
X1234774Y744790D01*
G01X1244774D02*
Y748510D01*
G01X1302533Y359600D02*
Y367100D01*
X1304867D01*
X1305613Y366725D01*
X1306080Y366225D01*
X1306267Y365225D01*
X1306080Y364225D01*
X1305520Y363600D01*
X1304867Y363225D01*
X1302533D01*
G01X1304867D02*
X1306267Y359600D01*
G01X1313767D02*
X1310033D01*
Y367100D01*
X1313767D01*
G01X1312273Y363475D02*
X1310033D01*
G01X1321453Y366475D02*
X1320893Y366850D01*
X1320240Y367100D01*
X1319493D01*
X1318653Y366725D01*
X1318000Y366100D01*
X1317533Y365350D01*
X1317160Y364100D01*
X1317067Y362975D01*
X1317253Y361850D01*
X1317533Y361100D01*
X1318093Y360350D01*
X1318747Y359850D01*
X1319400Y359600D01*
X1320053D01*
X1320707Y359850D01*
X1321267Y360225D01*
X1321733Y360725D01*
G01X1326900Y359600D02*
X1326153Y359725D01*
X1325500Y360225D01*
X1324940Y360975D01*
X1324567Y361850D01*
X1324380Y362850D01*
Y363850D01*
X1324567Y364850D01*
X1324940Y365725D01*
X1325500Y366475D01*
X1326153Y366975D01*
X1326900Y367100D01*
X1327647Y366975D01*
X1328300Y366475D01*
X1328860Y365725D01*
X1329233Y364850D01*
X1329420Y363850D01*
Y362850D01*
X1329233Y361850D01*
X1328860Y360975D01*
X1328300Y360225D01*
X1327647Y359725D01*
X1326900Y359600D01*
G01X1331973D02*
Y367100D01*
X1334400Y360850D01*
X1336827Y367100D01*
Y359600D01*
G01X1339473D02*
Y367100D01*
X1341900Y360850D01*
X1344327Y367100D01*
Y359600D01*
G01X1351267D02*
X1347533D01*
Y367100D01*
X1351267D01*
G01X1349773Y363475D02*
X1347533D01*
G01X1354753Y359600D02*
Y367100D01*
X1359047Y359600D01*
Y367100D01*
G01X1362347Y359600D02*
Y367100D01*
X1364213D01*
X1364960Y366725D01*
X1365520Y366225D01*
X1365987Y365475D01*
X1366360Y364600D01*
X1366453Y363350D01*
X1366360Y362100D01*
X1365987Y361225D01*
X1365520Y360475D01*
X1364960Y359975D01*
X1364213Y359600D01*
X1362347D01*
G01X1373767D02*
X1370033D01*
Y367100D01*
X1373767D01*
G01X1372273Y363475D02*
X1370033D01*
G01X1377347Y359600D02*
Y367100D01*
X1379213D01*
X1379960Y366725D01*
X1380520Y366225D01*
X1380987Y365475D01*
X1381360Y364600D01*
X1381453Y363350D01*
X1381360Y362100D01*
X1380987Y361225D01*
X1380520Y360475D01*
X1379960Y359975D01*
X1379213Y359600D01*
X1377347D01*
G01X1392347D02*
Y367100D01*
X1394213D01*
X1394960Y366725D01*
X1395520Y366225D01*
X1395987Y365475D01*
X1396360Y364600D01*
X1396453Y363350D01*
X1396360Y362100D01*
X1395987Y361225D01*
X1395520Y360475D01*
X1394960Y359975D01*
X1394213Y359600D01*
X1392347D01*
G01X1400033D02*
Y367100D01*
X1402367D01*
X1403113Y366725D01*
X1403580Y366225D01*
X1403767Y365225D01*
X1403580Y364225D01*
X1403020Y363600D01*
X1402367Y363225D01*
X1400033D01*
G01X1402367D02*
X1403767Y359600D01*
G01X1408280Y367100D02*
X1410520D01*
G01X1409400D02*
Y359600D01*
G01X1408280D02*
X1410520D01*
G01X1415033Y367100D02*
Y359600D01*
X1418767D01*
G01X1422533Y367100D02*
Y359600D01*
X1426267D01*
G01X1437440Y360600D02*
X1438187Y359975D01*
X1439027Y359600D01*
X1439773D01*
X1440520Y359975D01*
X1441080Y360600D01*
X1441360Y361475D01*
X1441173Y362350D01*
X1440707Y363100D01*
X1439867Y363600D01*
X1438747Y363850D01*
X1438093Y364350D01*
X1437813Y365225D01*
X1438000Y366100D01*
X1438467Y366725D01*
X1439120Y367100D01*
X1439773D01*
X1440427Y366850D01*
X1440987Y366225D01*
G01X1445780Y367100D02*
X1448020D01*
G01X1446900D02*
Y359600D01*
G01X1445780D02*
X1448020D01*
G01X1452627Y367100D02*
X1456173D01*
X1452627Y359600D01*
X1456173D01*
G01X1463767D02*
X1460033D01*
Y367100D01*
X1463767D01*
G01X1462273Y363475D02*
X1460033D01*
G01X1475127Y359600D02*
Y367100D01*
X1478673D01*
G01X1477367Y363475D02*
X1475127D01*
G01X1484400Y359600D02*
X1483653Y359725D01*
X1483000Y360225D01*
X1482440Y360975D01*
X1482067Y361850D01*
X1481880Y362850D01*
Y363850D01*
X1482067Y364850D01*
X1482440Y365725D01*
X1483000Y366475D01*
X1483653Y366975D01*
X1484400Y367100D01*
X1485147Y366975D01*
X1485800Y366475D01*
X1486360Y365725D01*
X1486733Y364850D01*
X1486920Y363850D01*
Y362850D01*
X1486733Y361850D01*
X1486360Y360975D01*
X1485800Y360225D01*
X1485147Y359725D01*
X1484400Y359600D01*
G01X1490033D02*
Y367100D01*
X1492367D01*
X1493113Y366725D01*
X1493580Y366225D01*
X1493767Y365225D01*
X1493580Y364225D01*
X1493020Y363600D01*
X1492367Y363225D01*
X1490033D01*
G01X1492367D02*
X1493767Y359600D01*
G01X1506900D02*
Y367100D01*
X1505780Y365600D01*
G01Y359600D02*
X1508020D01*
G01X1514400Y359350D02*
X1514213Y359475D01*
Y359725D01*
X1514400Y359850D01*
X1514587Y359725D01*
Y359475D01*
X1514400Y359350D01*
G01X1521900Y367100D02*
X1521153Y366850D01*
X1520593Y366225D01*
X1520220Y365475D01*
X1519940Y364475D01*
X1519847Y363350D01*
X1519940Y362225D01*
X1520220Y361225D01*
X1520593Y360475D01*
X1521153Y359850D01*
X1521900Y359600D01*
X1522647Y359850D01*
X1523207Y360475D01*
X1523580Y361225D01*
X1523860Y362225D01*
X1523953Y363350D01*
X1523860Y364475D01*
X1523580Y365475D01*
X1523207Y366225D01*
X1522647Y366850D01*
X1521900Y367100D01*
G01X1527627Y365850D02*
X1528187Y366600D01*
X1528840Y366975D01*
X1529587Y367100D01*
X1530520Y366850D01*
X1531173Y366225D01*
X1531360Y365475D01*
X1531267Y364725D01*
X1530893Y364100D01*
X1529027Y362850D01*
X1528187Y361975D01*
X1527627Y360725D01*
X1527440Y359600D01*
X1531360D01*
G01X1534473D02*
Y367100D01*
X1536900Y360850D01*
X1539327Y367100D01*
Y359600D01*
G01X1541973D02*
Y367100D01*
X1544400Y360850D01*
X1546827Y367100D01*
Y359600D01*
G01X1557627D02*
Y367100D01*
X1561173D01*
G01X1559867Y363475D02*
X1557627D01*
G01X1565780Y367100D02*
X1568020D01*
G01X1566900D02*
Y359600D01*
G01X1565780D02*
X1568020D01*
G01X1572253D02*
Y367100D01*
X1576547Y359600D01*
Y367100D01*
G01X1580780D02*
X1583020D01*
G01X1581900D02*
Y359600D01*
G01X1580780D02*
X1583020D01*
G01X1587440Y360600D02*
X1588187Y359975D01*
X1589027Y359600D01*
X1589773D01*
X1590520Y359975D01*
X1591080Y360600D01*
X1591360Y361475D01*
X1591173Y362350D01*
X1590707Y363100D01*
X1589867Y363600D01*
X1588747Y363850D01*
X1588093Y364350D01*
X1587813Y365225D01*
X1588000Y366100D01*
X1588467Y366725D01*
X1589120Y367100D01*
X1589773D01*
X1590427Y366850D01*
X1590987Y366225D01*
G01X1594940Y359600D02*
Y367100D01*
G01X1598860D02*
Y359600D01*
G01Y363350D02*
X1594940D01*
G01X1606267Y359600D02*
X1602533D01*
Y367100D01*
X1606267D01*
G01X1604773Y363475D02*
X1602533D01*
G01X1609847Y359600D02*
Y367100D01*
X1611713D01*
X1612460Y366725D01*
X1613020Y366225D01*
X1613487Y365475D01*
X1613860Y364600D01*
X1613953Y363350D01*
X1613860Y362100D01*
X1613487Y361225D01*
X1613020Y360475D01*
X1612460Y359975D01*
X1611713Y359600D01*
X1609847D01*
G01X1625033D02*
Y367100D01*
X1627273D01*
X1628020Y366725D01*
X1628580Y365850D01*
X1628767Y364850D01*
X1628580Y363850D01*
X1628113Y363100D01*
X1627273Y362725D01*
X1625033D01*
G01X1634400Y367100D02*
Y359600D01*
G01X1632253Y367100D02*
X1636547D01*
G01X1639940Y359600D02*
Y367100D01*
G01X1643860D02*
Y359600D01*
G01Y363350D02*
X1639940D01*
G01X1655780Y367100D02*
X1658020D01*
G01X1656900D02*
Y359600D01*
G01X1655780D02*
X1658020D01*
G01X1662440Y360600D02*
X1663187Y359975D01*
X1664027Y359600D01*
X1664773D01*
X1665520Y359975D01*
X1666080Y360600D01*
X1666360Y361475D01*
X1666173Y362350D01*
X1665707Y363100D01*
X1664867Y363600D01*
X1663747Y363850D01*
X1663093Y364350D01*
X1662813Y365225D01*
X1663000Y366100D01*
X1663467Y366725D01*
X1664120Y367100D01*
X1664773D01*
X1665427Y366850D01*
X1665987Y366225D01*
G01X1679400Y359600D02*
Y367100D01*
X1678280Y365600D01*
G01Y359600D02*
X1680520D01*
G01X1686900Y359350D02*
X1686713Y359475D01*
Y359725D01*
X1686900Y359850D01*
X1687087Y359725D01*
Y359475D01*
X1686900Y359350D01*
G01X1694400Y359600D02*
Y367100D01*
X1693280Y365600D01*
G01Y359600D02*
X1695520D01*
G01X1699847Y360725D02*
X1700407Y360100D01*
X1701060Y359725D01*
X1701900Y359600D01*
X1702740Y359850D01*
X1703393Y360350D01*
X1703860Y361225D01*
X1703953Y362225D01*
X1703767Y363225D01*
X1703300Y363850D01*
X1702647Y364350D01*
X1701993Y364475D01*
X1701340Y364350D01*
X1700500Y363850D01*
X1700780Y367100D01*
X1703300D01*
G01X1708373Y362100D02*
X1710613D01*
G01X1709400Y363725D02*
Y360475D01*
G01X1715220Y359350D02*
X1718580Y367100D01*
G01X1723187Y362100D02*
X1725613D01*
G01X1731900Y367100D02*
X1731153Y366850D01*
X1730593Y366225D01*
X1730220Y365475D01*
X1729940Y364475D01*
X1729847Y363350D01*
X1729940Y362225D01*
X1730220Y361225D01*
X1730593Y360475D01*
X1731153Y359850D01*
X1731900Y359600D01*
X1732647Y359850D01*
X1733207Y360475D01*
X1733580Y361225D01*
X1733860Y362225D01*
X1733953Y363350D01*
X1733860Y364475D01*
X1733580Y365475D01*
X1733207Y366225D01*
X1732647Y366850D01*
X1731900Y367100D01*
G01X1739400Y359350D02*
X1739213Y359475D01*
Y359725D01*
X1739400Y359850D01*
X1739587Y359725D01*
Y359475D01*
X1739400Y359350D01*
G01X1746900Y367100D02*
X1746153Y366850D01*
X1745593Y366225D01*
X1745220Y365475D01*
X1744940Y364475D01*
X1744847Y363350D01*
X1744940Y362225D01*
X1745220Y361225D01*
X1745593Y360475D01*
X1746153Y359850D01*
X1746900Y359600D01*
X1747647Y359850D01*
X1748207Y360475D01*
X1748580Y361225D01*
X1748860Y362225D01*
X1748953Y363350D01*
X1748860Y364475D01*
X1748580Y365475D01*
X1748207Y366225D01*
X1747647Y366850D01*
X1746900Y367100D01*
G01X1752627Y365850D02*
X1753187Y366600D01*
X1753840Y366975D01*
X1754587Y367100D01*
X1755520Y366850D01*
X1756173Y366225D01*
X1756360Y365475D01*
X1756267Y364725D01*
X1755893Y364100D01*
X1754027Y362850D01*
X1753187Y361975D01*
X1752627Y360725D01*
X1752440Y359600D01*
X1756360D01*
G01X1759847Y360725D02*
X1760407Y360100D01*
X1761060Y359725D01*
X1761900Y359600D01*
X1762740Y359850D01*
X1763393Y360350D01*
X1763860Y361225D01*
X1763953Y362225D01*
X1763767Y363225D01*
X1763300Y363850D01*
X1762647Y364350D01*
X1761993Y364475D01*
X1761340Y364350D01*
X1760500Y363850D01*
X1760780Y367100D01*
X1763300D01*
G01X1766973Y359600D02*
Y367100D01*
X1769400Y360850D01*
X1771827Y367100D01*
Y359600D01*
G01X1774473D02*
Y367100D01*
X1776900Y360850D01*
X1779327Y367100D01*
Y359600D01*
G01X1784400Y359350D02*
X1784213Y359475D01*
Y359725D01*
X1784400Y359850D01*
X1784587Y359725D01*
Y359475D01*
X1784400Y359350D01*
G01X1397479Y155658D02*
Y168158D01*
X1395619Y165658D01*
G01Y155658D02*
X1399339D01*
G01X1411739D02*
Y168158D01*
X1406004Y159200D01*
X1413754D01*
G01X1419644Y157116D02*
X1420729Y156075D01*
X1421969Y155658D01*
X1423209Y156075D01*
X1424294Y157324D01*
X1425069Y159200D01*
X1425379Y161075D01*
Y163366D01*
X1425069Y165241D01*
X1424294Y166908D01*
X1423364Y167741D01*
X1422279Y168158D01*
X1421039Y167741D01*
X1420109Y166908D01*
X1419489Y165658D01*
X1419179Y163991D01*
X1419489Y162533D01*
X1420264Y161075D01*
X1421194Y160241D01*
X1422279Y160033D01*
X1423519Y160449D01*
X1424449Y161491D01*
X1425379Y163366D01*
G01X1436539Y155658D02*
Y168158D01*
X1430804Y159200D01*
X1438554D01*
G01X1447079Y155241D02*
X1446769Y155450D01*
Y155866D01*
X1447079Y156075D01*
X1447389Y155866D01*
Y155450D01*
X1447079Y155241D01*
G01X1459479Y168158D02*
X1458239Y167741D01*
X1457309Y166700D01*
X1456689Y165450D01*
X1456224Y163783D01*
X1456069Y161908D01*
X1456224Y160033D01*
X1456689Y158366D01*
X1457309Y157116D01*
X1458239Y156075D01*
X1459479Y155658D01*
X1460719Y156075D01*
X1461649Y157116D01*
X1462269Y158366D01*
X1462734Y160033D01*
X1462889Y161908D01*
X1462734Y163783D01*
X1462269Y165450D01*
X1461649Y166700D01*
X1460719Y167741D01*
X1459479Y168158D01*
G01X1471879Y155658D02*
X1472964Y155866D01*
X1474204Y156491D01*
X1474979Y157533D01*
X1475289Y158991D01*
X1474979Y160449D01*
X1474049Y161700D01*
X1472654Y162325D01*
X1471104D01*
X1470174Y162741D01*
X1469399Y163783D01*
X1469089Y165241D01*
X1469554Y166700D01*
X1470639Y167741D01*
X1471879Y168158D01*
X1473119Y167741D01*
X1474204Y166700D01*
X1474669Y165241D01*
X1474359Y163783D01*
X1473584Y162741D01*
X1472654Y162325D01*
X1471104D01*
X1469709Y161700D01*
X1468779Y160449D01*
X1468469Y158991D01*
X1468779Y157533D01*
X1469554Y156491D01*
X1470794Y155866D01*
X1471879Y155658D01*
G01X1397900Y201750D02*
Y214250D01*
X1396040Y211750D01*
G01Y201750D02*
X1399760D01*
G01X1409990D02*
X1410300Y204458D01*
X1410765Y206750D01*
X1411385Y208833D01*
X1412160Y211125D01*
X1413400Y214250D01*
X1407200D01*
G01X1424560Y201750D02*
Y214250D01*
X1418825Y205292D01*
X1426575D01*
G01X1436960Y201750D02*
Y214250D01*
X1431225Y205292D01*
X1438975D01*
G01X1447500Y201333D02*
X1447190Y201542D01*
Y201958D01*
X1447500Y202167D01*
X1447810Y201958D01*
Y201542D01*
X1447500Y201333D01*
G01X1456955Y212167D02*
X1457885Y213416D01*
X1458970Y214042D01*
X1460210Y214250D01*
X1461760Y213833D01*
X1462845Y212792D01*
X1463155Y211542D01*
X1463000Y210291D01*
X1462380Y209250D01*
X1459280Y207167D01*
X1457885Y205708D01*
X1456955Y203625D01*
X1456645Y201750D01*
X1463155D01*
G01X1469665Y203208D02*
X1470750Y202167D01*
X1471990Y201750D01*
X1473230Y202167D01*
X1474315Y203416D01*
X1475090Y205292D01*
X1475400Y207167D01*
Y209458D01*
X1475090Y211333D01*
X1474315Y213000D01*
X1473385Y213833D01*
X1472300Y214250D01*
X1471060Y213833D01*
X1470130Y213000D01*
X1469510Y211750D01*
X1469200Y210083D01*
X1469510Y208625D01*
X1470285Y207167D01*
X1471215Y206333D01*
X1472300Y206125D01*
X1473540Y206541D01*
X1474470Y207583D01*
X1475400Y209458D01*
G01X1393919Y408179D02*
X1394849Y406720D01*
X1396089Y405887D01*
X1397484Y405679D01*
X1398724Y405887D01*
X1399964Y406929D01*
X1400739Y408179D01*
X1400894Y409429D01*
X1400584Y410887D01*
X1399499Y411929D01*
X1398414Y412346D01*
X1397019D01*
G01X1398414D02*
X1399344Y412971D01*
X1400119Y414012D01*
X1400429Y415262D01*
X1400119Y416512D01*
X1399344Y417554D01*
X1397949Y418179D01*
X1396554Y417971D01*
X1395159Y417137D01*
G01X1407094Y407137D02*
X1408179Y406096D01*
X1409419Y405679D01*
X1410659Y406096D01*
X1411744Y407345D01*
X1412519Y409221D01*
X1412829Y411096D01*
Y413387D01*
X1412519Y415262D01*
X1411744Y416929D01*
X1410814Y417762D01*
X1409729Y418179D01*
X1408489Y417762D01*
X1407559Y416929D01*
X1406939Y415679D01*
X1406629Y414012D01*
X1406939Y412554D01*
X1407714Y411096D01*
X1408644Y410262D01*
X1409729Y410054D01*
X1410969Y410470D01*
X1411899Y411512D01*
X1412829Y413387D01*
G01X1419494Y407137D02*
X1420579Y406096D01*
X1421819Y405679D01*
X1423059Y406096D01*
X1424144Y407345D01*
X1424919Y409221D01*
X1425229Y411096D01*
Y413387D01*
X1424919Y415262D01*
X1424144Y416929D01*
X1423214Y417762D01*
X1422129Y418179D01*
X1420889Y417762D01*
X1419959Y416929D01*
X1419339Y415679D01*
X1419029Y414012D01*
X1419339Y412554D01*
X1420114Y411096D01*
X1421044Y410262D01*
X1422129Y410054D01*
X1423369Y410470D01*
X1424299Y411512D01*
X1425229Y413387D01*
G01X1436389Y405679D02*
Y418179D01*
X1430654Y409221D01*
X1438404D01*
G01X1446929Y405262D02*
X1446619Y405471D01*
Y405887D01*
X1446929Y406096D01*
X1447239Y405887D01*
Y405471D01*
X1446929Y405262D01*
G01X1456384Y416096D02*
X1457314Y417345D01*
X1458399Y417971D01*
X1459639Y418179D01*
X1461189Y417762D01*
X1462274Y416721D01*
X1462584Y415471D01*
X1462429Y414220D01*
X1461809Y413179D01*
X1458709Y411096D01*
X1457314Y409637D01*
X1456384Y407554D01*
X1456074Y405679D01*
X1462584D01*
G01X1469094Y407137D02*
X1470179Y406096D01*
X1471419Y405679D01*
X1472659Y406096D01*
X1473744Y407345D01*
X1474519Y409221D01*
X1474829Y411096D01*
Y413387D01*
X1474519Y415262D01*
X1473744Y416929D01*
X1472814Y417762D01*
X1471729Y418179D01*
X1470489Y417762D01*
X1469559Y416929D01*
X1468939Y415679D01*
X1468629Y414012D01*
X1468939Y412554D01*
X1469714Y411096D01*
X1470644Y410262D01*
X1471729Y410054D01*
X1472969Y410470D01*
X1473899Y411512D01*
X1474829Y413387D01*
G01X1394069Y491322D02*
X1394999Y490280D01*
X1396084Y489655D01*
X1397479Y489447D01*
X1398874Y489864D01*
X1399959Y490697D01*
X1400734Y492155D01*
X1400889Y493822D01*
X1400579Y495489D01*
X1399804Y496530D01*
X1398719Y497364D01*
X1397634Y497572D01*
X1396549Y497364D01*
X1395154Y496530D01*
X1395619Y501947D01*
X1399804D01*
G01X1406934Y499864D02*
X1407864Y501113D01*
X1408949Y501739D01*
X1410189Y501947D01*
X1411739Y501530D01*
X1412824Y500489D01*
X1413134Y499239D01*
X1412979Y497988D01*
X1412359Y496947D01*
X1409259Y494864D01*
X1407864Y493405D01*
X1406934Y491322D01*
X1406624Y489447D01*
X1413134D01*
G01X1422279D02*
Y501947D01*
X1420419Y499447D01*
G01Y489447D02*
X1424139D01*
G01X1431734Y499864D02*
X1432664Y501113D01*
X1433749Y501739D01*
X1434989Y501947D01*
X1436539Y501530D01*
X1437624Y500489D01*
X1437934Y499239D01*
X1437779Y497988D01*
X1437159Y496947D01*
X1434059Y494864D01*
X1432664Y493405D01*
X1431734Y491322D01*
X1431424Y489447D01*
X1437934D01*
G01X1447079Y489030D02*
X1446769Y489239D01*
Y489655D01*
X1447079Y489864D01*
X1447389Y489655D01*
Y489239D01*
X1447079Y489030D01*
G01X1456534Y494655D02*
X1457619Y496114D01*
X1458549Y496947D01*
X1459789Y497364D01*
X1460874Y496947D01*
X1461649Y496114D01*
X1462269Y494864D01*
X1462424Y493405D01*
X1462269Y492155D01*
X1461649Y490905D01*
X1460719Y489864D01*
X1459634Y489447D01*
X1458394Y489864D01*
X1457309Y491113D01*
X1456689Y492989D01*
X1456534Y495072D01*
X1456844Y497780D01*
X1457309Y499239D01*
X1458084Y500697D01*
X1459169Y501739D01*
X1460254Y501947D01*
X1461339Y501530D01*
X1462114Y500489D01*
G01X1471879Y501947D02*
X1470639Y501530D01*
X1469709Y500489D01*
X1469089Y499239D01*
X1468624Y497572D01*
X1468469Y495697D01*
X1468624Y493822D01*
X1469089Y492155D01*
X1469709Y490905D01*
X1470639Y489864D01*
X1471879Y489447D01*
X1473119Y489864D01*
X1474049Y490905D01*
X1474669Y492155D01*
X1475134Y493822D01*
X1475289Y495697D01*
X1475134Y497572D01*
X1474669Y499239D01*
X1474049Y500489D01*
X1473119Y501530D01*
X1471879Y501947D01*
G01X1394040Y550625D02*
X1394970Y549583D01*
X1396055Y548958D01*
X1397450Y548750D01*
X1398845Y549167D01*
X1399930Y550000D01*
X1400705Y551458D01*
X1400860Y553125D01*
X1400550Y554792D01*
X1399775Y555833D01*
X1398690Y556667D01*
X1397605Y556875D01*
X1396520Y556667D01*
X1395125Y555833D01*
X1395590Y561250D01*
X1399775D01*
G01X1411710Y548750D02*
Y561250D01*
X1405975Y552292D01*
X1413725D01*
G01X1419305Y559167D02*
X1420235Y560416D01*
X1421320Y561042D01*
X1422560Y561250D01*
X1424110Y560833D01*
X1425195Y559792D01*
X1425505Y558542D01*
X1425350Y557291D01*
X1424730Y556250D01*
X1421630Y554167D01*
X1420235Y552708D01*
X1419305Y550625D01*
X1418995Y548750D01*
X1425505D01*
G01X1431240Y550625D02*
X1432170Y549583D01*
X1433255Y548958D01*
X1434650Y548750D01*
X1436045Y549167D01*
X1437130Y550000D01*
X1437905Y551458D01*
X1438060Y553125D01*
X1437750Y554792D01*
X1436975Y555833D01*
X1435890Y556667D01*
X1434805Y556875D01*
X1433720Y556667D01*
X1432325Y555833D01*
X1432790Y561250D01*
X1436975D01*
G01X1447050Y548333D02*
X1446740Y548542D01*
Y548958D01*
X1447050Y549167D01*
X1447360Y548958D01*
Y548542D01*
X1447050Y548333D01*
G01X1459450Y561250D02*
X1458210Y560833D01*
X1457280Y559792D01*
X1456660Y558542D01*
X1456195Y556875D01*
X1456040Y555000D01*
X1456195Y553125D01*
X1456660Y551458D01*
X1457280Y550208D01*
X1458210Y549167D01*
X1459450Y548750D01*
X1460690Y549167D01*
X1461620Y550208D01*
X1462240Y551458D01*
X1462705Y553125D01*
X1462860Y555000D01*
X1462705Y556875D01*
X1462240Y558542D01*
X1461620Y559792D01*
X1460690Y560833D01*
X1459450Y561250D01*
G01X1471850D02*
X1470610Y560833D01*
X1469680Y559792D01*
X1469060Y558542D01*
X1468595Y556875D01*
X1468440Y555000D01*
X1468595Y553125D01*
X1469060Y551458D01*
X1469680Y550208D01*
X1470610Y549167D01*
X1471850Y548750D01*
X1473090Y549167D01*
X1474020Y550208D01*
X1474640Y551458D01*
X1475105Y553125D01*
X1475260Y555000D01*
X1475105Y556875D01*
X1474640Y558542D01*
X1474020Y559792D01*
X1473090Y560833D01*
X1471850Y561250D01*
G01X1428629Y28494D02*
Y40994D01*
X1426769Y38494D01*
G01Y28494D02*
X1430489D01*
G01X1438084Y38911D02*
X1439014Y40160D01*
X1440099Y40786D01*
X1441339Y40994D01*
X1442889Y40577D01*
X1443974Y39536D01*
X1444284Y38286D01*
X1444129Y37035D01*
X1443509Y35994D01*
X1440409Y33911D01*
X1439014Y32452D01*
X1438084Y30369D01*
X1437774Y28494D01*
X1444284D01*
G01X1405539Y53494D02*
Y65994D01*
X1399804Y57036D01*
X1407554D01*
G01X1415769Y53494D02*
X1416079Y56202D01*
X1416544Y58494D01*
X1417164Y60577D01*
X1417939Y62869D01*
X1419179Y65994D01*
X1412979D01*
G01X1425534Y63911D02*
X1426464Y65160D01*
X1427549Y65786D01*
X1428789Y65994D01*
X1430339Y65577D01*
X1431424Y64536D01*
X1431734Y63286D01*
X1431579Y62035D01*
X1430959Y60994D01*
X1427859Y58911D01*
X1426464Y57452D01*
X1425534Y55369D01*
X1425224Y53494D01*
X1431734D01*
G01X1440879Y53077D02*
X1440569Y53286D01*
Y53702D01*
X1440879Y53911D01*
X1441189Y53702D01*
Y53286D01*
X1440879Y53077D01*
G01X1455139Y53494D02*
Y65994D01*
X1449404Y57036D01*
X1457154D01*
G01X1467539Y53494D02*
Y65994D01*
X1461804Y57036D01*
X1469554D01*
G01X1416650Y71750D02*
Y84250D01*
X1414790Y81750D01*
G01Y71750D02*
X1418510D01*
G01X1430910D02*
Y84250D01*
X1425175Y75292D01*
X1432925D01*
G01X1441450Y71333D02*
X1441140Y71542D01*
Y71958D01*
X1441450Y72167D01*
X1441760Y71958D01*
Y71542D01*
X1441450Y71333D01*
G01X1450905Y76958D02*
X1451990Y78417D01*
X1452920Y79250D01*
X1454160Y79667D01*
X1455245Y79250D01*
X1456020Y78417D01*
X1456640Y77167D01*
X1456795Y75708D01*
X1456640Y74458D01*
X1456020Y73208D01*
X1455090Y72167D01*
X1454005Y71750D01*
X1452765Y72167D01*
X1451680Y73416D01*
X1451060Y75292D01*
X1450905Y77375D01*
X1451215Y80083D01*
X1451680Y81542D01*
X1452455Y83000D01*
X1453540Y84042D01*
X1454625Y84250D01*
X1455710Y83833D01*
X1456485Y82792D01*
G01X1400690Y98625D02*
X1401620Y97583D01*
X1402705Y96958D01*
X1404100Y96750D01*
X1405495Y97167D01*
X1406580Y98000D01*
X1407355Y99458D01*
X1407510Y101125D01*
X1407200Y102792D01*
X1406425Y103833D01*
X1405340Y104667D01*
X1404255Y104875D01*
X1403170Y104667D01*
X1401775Y103833D01*
X1402240Y109250D01*
X1406425D01*
G01X1416190Y96750D02*
X1416500Y99458D01*
X1416965Y101750D01*
X1417585Y103833D01*
X1418360Y106125D01*
X1419600Y109250D01*
X1413400D01*
G01X1430760Y96750D02*
Y109250D01*
X1425025Y100292D01*
X1432775D01*
G01X1441300Y96333D02*
X1440990Y96542D01*
Y96958D01*
X1441300Y97167D01*
X1441610Y96958D01*
Y96542D01*
X1441300Y96333D01*
G01X1453700Y96750D02*
X1454785Y96958D01*
X1456025Y97583D01*
X1456800Y98625D01*
X1457110Y100083D01*
X1456800Y101541D01*
X1455870Y102792D01*
X1454475Y103417D01*
X1452925D01*
X1451995Y103833D01*
X1451220Y104875D01*
X1450910Y106333D01*
X1451375Y107792D01*
X1452460Y108833D01*
X1453700Y109250D01*
X1454940Y108833D01*
X1456025Y107792D01*
X1456490Y106333D01*
X1456180Y104875D01*
X1455405Y103833D01*
X1454475Y103417D01*
X1452925D01*
X1451530Y102792D01*
X1450600Y101541D01*
X1450290Y100083D01*
X1450600Y98625D01*
X1451375Y97583D01*
X1452615Y96958D01*
X1453700Y96750D01*
G01X1466100Y109250D02*
X1464860Y108833D01*
X1463930Y107792D01*
X1463310Y106542D01*
X1462845Y104875D01*
X1462690Y103000D01*
X1462845Y101125D01*
X1463310Y99458D01*
X1463930Y98208D01*
X1464860Y97167D01*
X1466100Y96750D01*
X1467340Y97167D01*
X1468270Y98208D01*
X1468890Y99458D01*
X1469355Y101125D01*
X1469510Y103000D01*
X1469355Y104875D01*
X1468890Y106542D01*
X1468270Y107792D01*
X1467340Y108833D01*
X1466100Y109250D01*
G01X1406619Y133158D02*
X1407549Y131699D01*
X1408789Y130866D01*
X1410184Y130658D01*
X1411424Y130866D01*
X1412664Y131908D01*
X1413439Y133158D01*
X1413594Y134408D01*
X1413284Y135866D01*
X1412199Y136908D01*
X1411114Y137325D01*
X1409719D01*
G01X1411114D02*
X1412044Y137950D01*
X1412819Y138991D01*
X1413129Y140241D01*
X1412819Y141491D01*
X1412044Y142533D01*
X1410649Y143158D01*
X1409254Y142950D01*
X1407859Y142116D01*
G01X1422119Y130658D02*
X1422429Y133366D01*
X1422894Y135658D01*
X1423514Y137741D01*
X1424289Y140033D01*
X1425529Y143158D01*
X1419329D01*
G01X1434829Y130241D02*
X1434519Y130450D01*
Y130866D01*
X1434829Y131075D01*
X1435139Y130866D01*
Y130450D01*
X1434829Y130241D01*
G01X1444594Y132116D02*
X1445679Y131075D01*
X1446919Y130658D01*
X1448159Y131075D01*
X1449244Y132324D01*
X1450019Y134200D01*
X1450329Y136075D01*
Y138366D01*
X1450019Y140241D01*
X1449244Y141908D01*
X1448314Y142741D01*
X1447229Y143158D01*
X1445989Y142741D01*
X1445059Y141908D01*
X1444439Y140658D01*
X1444129Y138991D01*
X1444439Y137533D01*
X1445214Y136075D01*
X1446144Y135241D01*
X1447229Y135033D01*
X1448469Y135449D01*
X1449399Y136491D01*
X1450329Y138366D01*
G01X1456219Y132533D02*
X1457149Y131491D01*
X1458234Y130866D01*
X1459629Y130658D01*
X1461024Y131075D01*
X1462109Y131908D01*
X1462884Y133366D01*
X1463039Y135033D01*
X1462729Y136700D01*
X1461954Y137741D01*
X1460869Y138575D01*
X1459784Y138783D01*
X1458699Y138575D01*
X1457304Y137741D01*
X1457769Y143158D01*
X1461954D01*
G01X1418510Y176750D02*
Y189250D01*
X1412775Y180292D01*
X1420525D01*
G01X1430910Y176750D02*
Y189250D01*
X1425175Y180292D01*
X1432925D01*
G01X1441450Y176333D02*
X1441140Y176542D01*
Y176958D01*
X1441450Y177167D01*
X1441760Y176958D01*
Y176542D01*
X1441450Y176333D01*
G01X1450440Y179250D02*
X1451370Y177791D01*
X1452610Y176958D01*
X1454005Y176750D01*
X1455245Y176958D01*
X1456485Y178000D01*
X1457260Y179250D01*
X1457415Y180500D01*
X1457105Y181958D01*
X1456020Y183000D01*
X1454935Y183417D01*
X1453540D01*
G01X1454935D02*
X1455865Y184042D01*
X1456640Y185083D01*
X1456950Y186333D01*
X1456640Y187583D01*
X1455865Y188625D01*
X1454470Y189250D01*
X1453075Y189042D01*
X1451680Y188208D01*
G01X1403679Y380679D02*
Y393179D01*
X1401819Y390679D01*
G01Y380679D02*
X1405539D01*
G01X1416079Y393179D02*
X1414839Y392762D01*
X1413909Y391721D01*
X1413289Y390471D01*
X1412824Y388804D01*
X1412669Y386929D01*
X1412824Y385054D01*
X1413289Y383387D01*
X1413909Y382137D01*
X1414839Y381096D01*
X1416079Y380679D01*
X1417319Y381096D01*
X1418249Y382137D01*
X1418869Y383387D01*
X1419334Y385054D01*
X1419489Y386929D01*
X1419334Y388804D01*
X1418869Y390471D01*
X1418249Y391721D01*
X1417319Y392762D01*
X1416079Y393179D01*
G01X1428479Y380679D02*
Y393179D01*
X1426619Y390679D01*
G01Y380679D02*
X1430339D01*
G01X1440879Y380262D02*
X1440569Y380471D01*
Y380887D01*
X1440879Y381096D01*
X1441189Y380887D01*
Y380471D01*
X1440879Y380262D01*
G01X1455139Y380679D02*
Y393179D01*
X1449404Y384221D01*
X1457154D01*
G01X1462269Y382554D02*
X1463199Y381512D01*
X1464284Y380887D01*
X1465679Y380679D01*
X1467074Y381096D01*
X1468159Y381929D01*
X1468934Y383387D01*
X1469089Y385054D01*
X1468779Y386721D01*
X1468004Y387762D01*
X1466919Y388596D01*
X1465834Y388804D01*
X1464749Y388596D01*
X1463354Y387762D01*
X1463819Y393179D01*
X1468004D01*
G01X1410029Y464447D02*
Y476947D01*
X1408169Y474447D01*
G01Y464447D02*
X1411889D01*
G01X1419019Y466947D02*
X1419949Y465488D01*
X1421189Y464655D01*
X1422584Y464447D01*
X1423824Y464655D01*
X1425064Y465697D01*
X1425839Y466947D01*
X1425994Y468197D01*
X1425684Y469655D01*
X1424599Y470697D01*
X1423514Y471114D01*
X1422119D01*
G01X1423514D02*
X1424444Y471739D01*
X1425219Y472780D01*
X1425529Y474030D01*
X1425219Y475280D01*
X1424444Y476322D01*
X1423049Y476947D01*
X1421654Y476739D01*
X1420259Y475905D01*
G01X1431884Y474864D02*
X1432814Y476113D01*
X1433899Y476739D01*
X1435139Y476947D01*
X1436689Y476530D01*
X1437774Y475489D01*
X1438084Y474239D01*
X1437929Y472988D01*
X1437309Y471947D01*
X1434209Y469864D01*
X1432814Y468405D01*
X1431884Y466322D01*
X1431574Y464447D01*
X1438084D01*
G01X1447229Y464030D02*
X1446919Y464239D01*
Y464655D01*
X1447229Y464864D01*
X1447539Y464655D01*
Y464239D01*
X1447229Y464030D01*
G01X1461489Y464447D02*
Y476947D01*
X1455754Y467989D01*
X1463504D01*
G01X1403800Y523750D02*
Y536250D01*
X1401940Y533750D01*
G01Y523750D02*
X1405660D01*
G01X1412790Y526250D02*
X1413720Y524791D01*
X1414960Y523958D01*
X1416355Y523750D01*
X1417595Y523958D01*
X1418835Y525000D01*
X1419610Y526250D01*
X1419765Y527500D01*
X1419455Y528958D01*
X1418370Y530000D01*
X1417285Y530417D01*
X1415890D01*
G01X1417285D02*
X1418215Y531042D01*
X1418990Y532083D01*
X1419300Y533333D01*
X1418990Y534583D01*
X1418215Y535625D01*
X1416820Y536250D01*
X1415425Y536042D01*
X1414030Y535208D01*
G01X1428290Y523750D02*
X1428600Y526458D01*
X1429065Y528750D01*
X1429685Y530833D01*
X1430460Y533125D01*
X1431700Y536250D01*
X1425500D01*
G01X1441000Y523333D02*
X1440690Y523542D01*
Y523958D01*
X1441000Y524167D01*
X1441310Y523958D01*
Y523542D01*
X1441000Y523333D01*
G01X1453090Y523750D02*
X1453400Y526458D01*
X1453865Y528750D01*
X1454485Y530833D01*
X1455260Y533125D01*
X1456500Y536250D01*
X1450300D01*
G01X1463165Y525208D02*
X1464250Y524167D01*
X1465490Y523750D01*
X1466730Y524167D01*
X1467815Y525416D01*
X1468590Y527292D01*
X1468900Y529167D01*
Y531458D01*
X1468590Y533333D01*
X1467815Y535000D01*
X1466885Y535833D01*
X1465800Y536250D01*
X1464560Y535833D01*
X1463630Y535000D01*
X1463010Y533750D01*
X1462700Y532083D01*
X1463010Y530625D01*
X1463785Y529167D01*
X1464715Y528333D01*
X1465800Y528125D01*
X1467040Y528541D01*
X1467970Y529583D01*
X1468900Y531458D01*
G01X1521364Y260376D02*
X1522406Y261306D01*
X1523031Y262391D01*
X1523239Y263786D01*
X1522822Y265181D01*
X1521989Y266266D01*
X1520531Y267041D01*
X1518864Y267196D01*
X1517197Y266886D01*
X1516156Y266111D01*
X1515322Y265026D01*
X1515114Y263941D01*
X1515322Y262856D01*
X1516156Y261461D01*
X1510739Y261926D01*
Y266111D01*
G01X1523239Y275876D02*
X1520531Y276186D01*
X1518239Y276651D01*
X1516156Y277271D01*
X1513864Y278046D01*
X1510739Y279286D01*
Y273086D01*
G01X1523239Y288586D02*
X1523031Y289671D01*
X1522406Y290911D01*
X1521364Y291686D01*
X1519906Y291996D01*
X1518448Y291686D01*
X1517197Y290756D01*
X1516572Y289361D01*
Y287811D01*
X1516156Y286881D01*
X1515114Y286106D01*
X1513656Y285796D01*
X1512197Y286261D01*
X1511156Y287346D01*
X1510739Y288586D01*
X1511156Y289826D01*
X1512197Y290911D01*
X1513656Y291376D01*
X1515114Y291066D01*
X1516156Y290291D01*
X1516572Y289361D01*
Y287811D01*
X1517197Y286416D01*
X1518448Y285486D01*
X1519906Y285176D01*
X1521364Y285486D01*
X1522406Y286261D01*
X1523031Y287501D01*
X1523239Y288586D01*
G01Y300676D02*
X1520531Y300986D01*
X1518239Y301451D01*
X1516156Y302071D01*
X1513864Y302846D01*
X1510739Y304086D01*
Y297886D01*
G01X1523656Y313386D02*
X1523447Y313076D01*
X1523031D01*
X1522822Y313386D01*
X1523031Y313696D01*
X1523447D01*
X1523656Y313386D01*
G01X1523239Y327646D02*
X1510739D01*
X1519697Y321911D01*
Y329661D01*
G01X1510739Y338186D02*
X1511156Y336946D01*
X1512197Y336016D01*
X1513447Y335396D01*
X1515114Y334931D01*
X1516989Y334776D01*
X1518864Y334931D01*
X1520531Y335396D01*
X1521781Y336016D01*
X1522822Y336946D01*
X1523239Y338186D01*
X1522822Y339426D01*
X1521781Y340356D01*
X1520531Y340976D01*
X1518864Y341441D01*
X1516989Y341596D01*
X1515114Y341441D01*
X1513447Y340976D01*
X1512197Y340356D01*
X1511156Y339426D01*
X1510739Y338186D01*
G01X1548239Y288736D02*
X1535739D01*
X1538239Y286876D01*
G01X1548239D02*
Y290596D01*
G01Y302996D02*
X1535739D01*
X1544697Y297261D01*
Y305011D01*
G01X1548239Y313226D02*
X1545531Y313536D01*
X1543239Y314001D01*
X1541156Y314621D01*
X1538864Y315396D01*
X1535739Y316636D01*
Y310436D01*
G01X1877181Y612459D02*
Y624959D01*
X1883071D01*
G01X1880901Y618917D02*
X1877181D01*
G01X1890666Y624959D02*
X1894386D01*
G01X1892526D02*
Y612459D01*
G01X1890666D02*
X1894386D01*
G01X1905856Y618709D02*
X1908956D01*
Y614959D01*
X1908026Y613709D01*
X1906941Y612876D01*
X1905391Y612459D01*
X1903841Y612876D01*
X1902756Y613709D01*
X1901826Y614959D01*
X1901206Y616417D01*
X1900896Y618084D01*
Y619542D01*
X1901206Y620792D01*
X1901826Y622251D01*
X1902756Y623501D01*
X1903686Y624334D01*
X1904926Y624959D01*
X1906011D01*
X1907251Y624542D01*
X1908181Y623709D01*
G01X1913916Y624959D02*
Y616001D01*
X1914536Y614125D01*
X1915776Y612876D01*
X1917326Y612459D01*
X1918876Y612876D01*
X1920116Y614125D01*
X1920736Y616001D01*
Y624959D01*
G01X1926626Y612459D02*
Y624959D01*
X1930501D01*
X1931741Y624334D01*
X1932516Y623501D01*
X1932826Y621834D01*
X1932516Y620167D01*
X1931586Y619126D01*
X1930501Y618501D01*
X1926626D01*
G01X1930501D02*
X1932826Y612459D01*
G01X1945226D02*
X1939026D01*
Y624959D01*
X1945226D01*
G01X1942746Y618917D02*
X1939026D01*
G01X1979481Y612459D02*
Y624959D01*
X1985371D01*
G01X1983201Y618917D02*
X1979481D01*
G01X1992966Y624959D02*
X1996686D01*
G01X1994826D02*
Y612459D01*
G01X1992966D02*
X1996686D01*
G01X2003661D02*
Y624959D01*
X2010791Y612459D01*
Y624959D01*
G01X2017766D02*
X2021486D01*
G01X2019626D02*
Y612459D01*
G01X2017766D02*
X2021486D01*
G01X2028771Y614125D02*
X2030011Y613084D01*
X2031406Y612459D01*
X2032646D01*
X2033886Y613084D01*
X2034816Y614125D01*
X2035281Y615584D01*
X2034971Y617042D01*
X2034196Y618292D01*
X2032801Y619126D01*
X2030941Y619542D01*
X2029856Y620376D01*
X2029391Y621834D01*
X2029701Y623292D01*
X2030476Y624334D01*
X2031561Y624959D01*
X2032646D01*
X2033731Y624542D01*
X2034661Y623501D01*
G01X2041171Y612459D02*
Y624959D01*
G01X2047681D02*
Y612459D01*
G01Y618709D02*
X2041171D01*
G01X2059926Y612459D02*
X2053726D01*
Y624959D01*
X2059926D01*
G01X2057446Y618917D02*
X2053726D01*
G01X2065816Y612459D02*
Y624959D01*
X2068916D01*
X2070156Y624334D01*
X2071086Y623501D01*
X2071861Y622251D01*
X2072481Y620792D01*
X2072636Y618709D01*
X2072481Y616626D01*
X2071861Y615167D01*
X2071086Y613917D01*
X2070156Y613084D01*
X2068916Y612459D01*
X2065816D01*
G01X2076976Y608292D02*
X2086276D01*
G01X2090771Y614125D02*
X2092011Y613084D01*
X2093406Y612459D01*
X2094646D01*
X2095886Y613084D01*
X2096816Y614125D01*
X2097281Y615584D01*
X2096971Y617042D01*
X2096196Y618292D01*
X2094801Y619126D01*
X2092941Y619542D01*
X2091856Y620376D01*
X2091391Y621834D01*
X2091701Y623292D01*
X2092476Y624334D01*
X2093561Y624959D01*
X2094646D01*
X2095731Y624542D01*
X2096661Y623501D01*
G01X2104566Y624959D02*
X2108286D01*
G01X2106426D02*
Y612459D01*
G01X2104566D02*
X2108286D01*
G01X2115881Y624959D02*
X2121771D01*
X2115881Y612459D01*
X2121771D01*
G01X2134326D02*
X2128126D01*
Y624959D01*
X2134326D01*
G01X2131846Y618917D02*
X2128126D01*
G01X2032026Y-99341D02*
Y-86841D01*
X2030166Y-89341D01*
G01Y-99341D02*
X2033886D01*
G01X2041016Y-97466D02*
X2041946Y-98508D01*
X2043031Y-99133D01*
X2044426Y-99341D01*
X2045821Y-98924D01*
X2046906Y-98091D01*
X2047681Y-96633D01*
X2047836Y-94966D01*
X2047526Y-93299D01*
X2046751Y-92258D01*
X2045666Y-91424D01*
X2044581Y-91216D01*
X2043496Y-91424D01*
X2042101Y-92258D01*
X2042566Y-86841D01*
X2046751D01*
G01X2053881Y-94133D02*
X2054966Y-92674D01*
X2055896Y-91841D01*
X2057136Y-91424D01*
X2058221Y-91841D01*
X2058996Y-92674D01*
X2059616Y-93924D01*
X2059771Y-95383D01*
X2059616Y-96633D01*
X2058996Y-97883D01*
X2058066Y-98924D01*
X2056981Y-99341D01*
X2055741Y-98924D01*
X2054656Y-97675D01*
X2054036Y-95799D01*
X2053881Y-93716D01*
X2054191Y-91008D01*
X2054656Y-89549D01*
X2055431Y-88091D01*
X2056516Y-87049D01*
X2057601Y-86841D01*
X2058686Y-87258D01*
X2059461Y-88299D01*
G01X2069226Y-99758D02*
X2068916Y-99549D01*
Y-99133D01*
X2069226Y-98924D01*
X2069536Y-99133D01*
Y-99549D01*
X2069226Y-99758D01*
G01X2081626Y-86841D02*
X2080386Y-87258D01*
X2079456Y-88299D01*
X2078836Y-89549D01*
X2078371Y-91216D01*
X2078216Y-93091D01*
X2078371Y-94966D01*
X2078836Y-96633D01*
X2079456Y-97883D01*
X2080386Y-98924D01*
X2081626Y-99341D01*
X2082866Y-98924D01*
X2083796Y-97883D01*
X2084416Y-96633D01*
X2084881Y-94966D01*
X2085036Y-93091D01*
X2084881Y-91216D01*
X2084416Y-89549D01*
X2083796Y-88299D01*
X2082866Y-87258D01*
X2081626Y-86841D01*
G01X2032026Y-61541D02*
Y-49041D01*
X2030166Y-51541D01*
G01Y-61541D02*
X2033886D01*
G01X2041481Y-51124D02*
X2042411Y-49875D01*
X2043496Y-49249D01*
X2044736Y-49041D01*
X2046286Y-49458D01*
X2047371Y-50499D01*
X2047681Y-51749D01*
X2047526Y-53000D01*
X2046906Y-54041D01*
X2043806Y-56124D01*
X2042411Y-57583D01*
X2041481Y-59666D01*
X2041171Y-61541D01*
X2047681D01*
G01X2053881Y-56333D02*
X2054966Y-54874D01*
X2055896Y-54041D01*
X2057136Y-53624D01*
X2058221Y-54041D01*
X2058996Y-54874D01*
X2059616Y-56124D01*
X2059771Y-57583D01*
X2059616Y-58833D01*
X2058996Y-60083D01*
X2058066Y-61124D01*
X2056981Y-61541D01*
X2055741Y-61124D01*
X2054656Y-59875D01*
X2054036Y-57999D01*
X2053881Y-55916D01*
X2054191Y-53208D01*
X2054656Y-51749D01*
X2055431Y-50291D01*
X2056516Y-49249D01*
X2057601Y-49041D01*
X2058686Y-49458D01*
X2059461Y-50499D01*
G01X2069226Y-61958D02*
X2068916Y-61749D01*
Y-61333D01*
X2069226Y-61124D01*
X2069536Y-61333D01*
Y-61749D01*
X2069226Y-61958D01*
G01X2081626Y-49041D02*
X2080386Y-49458D01*
X2079456Y-50499D01*
X2078836Y-51749D01*
X2078371Y-53416D01*
X2078216Y-55291D01*
X2078371Y-57166D01*
X2078836Y-58833D01*
X2079456Y-60083D01*
X2080386Y-61124D01*
X2081626Y-61541D01*
X2082866Y-61124D01*
X2083796Y-60083D01*
X2084416Y-58833D01*
X2084881Y-57166D01*
X2085036Y-55291D01*
X2084881Y-53416D01*
X2084416Y-51749D01*
X2083796Y-50499D01*
X2082866Y-49458D01*
X2081626Y-49041D01*
G01X2032026Y-23741D02*
Y-11241D01*
X2030166Y-13741D01*
G01Y-23741D02*
X2033886D01*
G01X2041481Y-13324D02*
X2042411Y-12075D01*
X2043496Y-11449D01*
X2044736Y-11241D01*
X2046286Y-11658D01*
X2047371Y-12699D01*
X2047681Y-13949D01*
X2047526Y-15200D01*
X2046906Y-16241D01*
X2043806Y-18324D01*
X2042411Y-19783D01*
X2041481Y-21866D01*
X2041171Y-23741D01*
X2047681D01*
G01X2053416Y-21866D02*
X2054346Y-22908D01*
X2055431Y-23533D01*
X2056826Y-23741D01*
X2058221Y-23324D01*
X2059306Y-22491D01*
X2060081Y-21033D01*
X2060236Y-19366D01*
X2059926Y-17699D01*
X2059151Y-16658D01*
X2058066Y-15824D01*
X2056981Y-15616D01*
X2055896Y-15824D01*
X2054501Y-16658D01*
X2054966Y-11241D01*
X2059151D01*
G01X2069226Y-24158D02*
X2068916Y-23949D01*
Y-23533D01*
X2069226Y-23324D01*
X2069536Y-23533D01*
Y-23949D01*
X2069226Y-24158D01*
G01X2081626Y-11241D02*
X2080386Y-11658D01*
X2079456Y-12699D01*
X2078836Y-13949D01*
X2078371Y-15616D01*
X2078216Y-17491D01*
X2078371Y-19366D01*
X2078836Y-21033D01*
X2079456Y-22283D01*
X2080386Y-23324D01*
X2081626Y-23741D01*
X2082866Y-23324D01*
X2083796Y-22283D01*
X2084416Y-21033D01*
X2084881Y-19366D01*
X2085036Y-17491D01*
X2084881Y-15616D01*
X2084416Y-13949D01*
X2083796Y-12699D01*
X2082866Y-11658D01*
X2081626Y-11241D01*
G01X2038226Y14059D02*
X2039311Y14267D01*
X2040551Y14892D01*
X2041326Y15934D01*
X2041636Y17392D01*
X2041326Y18850D01*
X2040396Y20101D01*
X2039001Y20726D01*
X2037451D01*
X2036521Y21142D01*
X2035746Y22184D01*
X2035436Y23642D01*
X2035901Y25101D01*
X2036986Y26142D01*
X2038226Y26559D01*
X2039466Y26142D01*
X2040551Y25101D01*
X2041016Y23642D01*
X2040706Y22184D01*
X2039931Y21142D01*
X2039001Y20726D01*
X2037451D01*
X2036056Y20101D01*
X2035126Y18850D01*
X2034816Y17392D01*
X2035126Y15934D01*
X2035901Y14892D01*
X2037141Y14267D01*
X2038226Y14059D01*
G01X2050316D02*
X2050626Y16767D01*
X2051091Y19059D01*
X2051711Y21142D01*
X2052486Y23434D01*
X2053726Y26559D01*
X2047526D01*
G01X2063026Y13642D02*
X2062716Y13851D01*
Y14267D01*
X2063026Y14476D01*
X2063336Y14267D01*
Y13851D01*
X2063026Y13642D01*
G01X2075426Y26559D02*
X2074186Y26142D01*
X2073256Y25101D01*
X2072636Y23851D01*
X2072171Y22184D01*
X2072016Y20309D01*
X2072171Y18434D01*
X2072636Y16767D01*
X2073256Y15517D01*
X2074186Y14476D01*
X2075426Y14059D01*
X2076666Y14476D01*
X2077596Y15517D01*
X2078216Y16767D01*
X2078681Y18434D01*
X2078836Y20309D01*
X2078681Y22184D01*
X2078216Y23851D01*
X2077596Y25101D01*
X2076666Y26142D01*
X2075426Y26559D01*
G01X2029081Y62276D02*
X2030011Y63525D01*
X2031096Y64151D01*
X2032336Y64359D01*
X2033886Y63942D01*
X2034971Y62901D01*
X2035281Y61651D01*
X2035126Y60400D01*
X2034506Y59359D01*
X2031406Y57276D01*
X2030011Y55817D01*
X2029081Y53734D01*
X2028771Y51859D01*
X2035281D01*
G01X2041016Y53734D02*
X2041946Y52692D01*
X2043031Y52067D01*
X2044426Y51859D01*
X2045821Y52276D01*
X2046906Y53109D01*
X2047681Y54567D01*
X2047836Y56234D01*
X2047526Y57901D01*
X2046751Y58942D01*
X2045666Y59776D01*
X2044581Y59984D01*
X2043496Y59776D01*
X2042101Y58942D01*
X2042566Y64359D01*
X2046751D01*
G01X2053881Y62276D02*
X2054811Y63525D01*
X2055896Y64151D01*
X2057136Y64359D01*
X2058686Y63942D01*
X2059771Y62901D01*
X2060081Y61651D01*
X2059926Y60400D01*
X2059306Y59359D01*
X2056206Y57276D01*
X2054811Y55817D01*
X2053881Y53734D01*
X2053571Y51859D01*
X2060081D01*
G01X2069226Y51442D02*
X2068916Y51651D01*
Y52067D01*
X2069226Y52276D01*
X2069536Y52067D01*
Y51651D01*
X2069226Y51442D01*
G01X2081626Y64359D02*
X2080386Y63942D01*
X2079456Y62901D01*
X2078836Y61651D01*
X2078371Y59984D01*
X2078216Y58109D01*
X2078371Y56234D01*
X2078836Y54567D01*
X2079456Y53317D01*
X2080386Y52276D01*
X2081626Y51859D01*
X2082866Y52276D01*
X2083796Y53317D01*
X2084416Y54567D01*
X2084881Y56234D01*
X2085036Y58109D01*
X2084881Y59984D01*
X2084416Y61651D01*
X2083796Y62901D01*
X2082866Y63942D01*
X2081626Y64359D01*
G01X2032026Y89659D02*
Y102159D01*
X2030166Y99659D01*
G01Y89659D02*
X2033886D01*
G01X2041481Y94867D02*
X2042566Y96326D01*
X2043496Y97159D01*
X2044736Y97576D01*
X2045821Y97159D01*
X2046596Y96326D01*
X2047216Y95076D01*
X2047371Y93617D01*
X2047216Y92367D01*
X2046596Y91117D01*
X2045666Y90076D01*
X2044581Y89659D01*
X2043341Y90076D01*
X2042256Y91325D01*
X2041636Y93201D01*
X2041481Y95284D01*
X2041791Y97992D01*
X2042256Y99451D01*
X2043031Y100909D01*
X2044116Y101951D01*
X2045201Y102159D01*
X2046286Y101742D01*
X2047061Y100701D01*
G01X2056516Y89659D02*
X2056826Y92367D01*
X2057291Y94659D01*
X2057911Y96742D01*
X2058686Y99034D01*
X2059926Y102159D01*
X2053726D01*
G01X2069226Y89242D02*
X2068916Y89451D01*
Y89867D01*
X2069226Y90076D01*
X2069536Y89867D01*
Y89451D01*
X2069226Y89242D01*
G01X2081626Y102159D02*
X2080386Y101742D01*
X2079456Y100701D01*
X2078836Y99451D01*
X2078371Y97784D01*
X2078216Y95909D01*
X2078371Y94034D01*
X2078836Y92367D01*
X2079456Y91117D01*
X2080386Y90076D01*
X2081626Y89659D01*
X2082866Y90076D01*
X2083796Y91117D01*
X2084416Y92367D01*
X2084881Y94034D01*
X2085036Y95909D01*
X2084881Y97784D01*
X2084416Y99451D01*
X2083796Y100701D01*
X2082866Y101742D01*
X2081626Y102159D01*
G01X2032026Y127459D02*
Y139959D01*
X2030166Y137459D01*
G01Y127459D02*
X2033886D01*
G01X2044426D02*
Y139959D01*
X2042566Y137459D01*
G01Y127459D02*
X2046286D01*
G01X2054191Y128917D02*
X2055276Y127876D01*
X2056516Y127459D01*
X2057756Y127876D01*
X2058841Y129125D01*
X2059616Y131001D01*
X2059926Y132876D01*
Y135167D01*
X2059616Y137042D01*
X2058841Y138709D01*
X2057911Y139542D01*
X2056826Y139959D01*
X2055586Y139542D01*
X2054656Y138709D01*
X2054036Y137459D01*
X2053726Y135792D01*
X2054036Y134334D01*
X2054811Y132876D01*
X2055741Y132042D01*
X2056826Y131834D01*
X2058066Y132250D01*
X2058996Y133292D01*
X2059926Y135167D01*
G01X2069226Y127042D02*
X2068916Y127251D01*
Y127667D01*
X2069226Y127876D01*
X2069536Y127667D01*
Y127251D01*
X2069226Y127042D01*
G01X2081626Y139959D02*
X2080386Y139542D01*
X2079456Y138501D01*
X2078836Y137251D01*
X2078371Y135584D01*
X2078216Y133709D01*
X2078371Y131834D01*
X2078836Y130167D01*
X2079456Y128917D01*
X2080386Y127876D01*
X2081626Y127459D01*
X2082866Y127876D01*
X2083796Y128917D01*
X2084416Y130167D01*
X2084881Y131834D01*
X2085036Y133709D01*
X2084881Y135584D01*
X2084416Y137251D01*
X2083796Y138501D01*
X2082866Y139542D01*
X2081626Y139959D01*
G01X2038226Y165259D02*
X2039311Y165467D01*
X2040551Y166092D01*
X2041326Y167134D01*
X2041636Y168592D01*
X2041326Y170050D01*
X2040396Y171301D01*
X2039001Y171926D01*
X2037451D01*
X2036521Y172342D01*
X2035746Y173384D01*
X2035436Y174842D01*
X2035901Y176301D01*
X2036986Y177342D01*
X2038226Y177759D01*
X2039466Y177342D01*
X2040551Y176301D01*
X2041016Y174842D01*
X2040706Y173384D01*
X2039931Y172342D01*
X2039001Y171926D01*
X2037451D01*
X2036056Y171301D01*
X2035126Y170050D01*
X2034816Y168592D01*
X2035126Y167134D01*
X2035901Y166092D01*
X2037141Y165467D01*
X2038226Y165259D01*
G01X2047216Y167759D02*
X2048146Y166300D01*
X2049386Y165467D01*
X2050781Y165259D01*
X2052021Y165467D01*
X2053261Y166509D01*
X2054036Y167759D01*
X2054191Y169009D01*
X2053881Y170467D01*
X2052796Y171509D01*
X2051711Y171926D01*
X2050316D01*
G01X2051711D02*
X2052641Y172551D01*
X2053416Y173592D01*
X2053726Y174842D01*
X2053416Y176092D01*
X2052641Y177134D01*
X2051246Y177759D01*
X2049851Y177551D01*
X2048456Y176717D01*
G01X2063026Y164842D02*
X2062716Y165051D01*
Y165467D01*
X2063026Y165676D01*
X2063336Y165467D01*
Y165051D01*
X2063026Y164842D01*
G01X2075426Y177759D02*
X2074186Y177342D01*
X2073256Y176301D01*
X2072636Y175051D01*
X2072171Y173384D01*
X2072016Y171509D01*
X2072171Y169634D01*
X2072636Y167967D01*
X2073256Y166717D01*
X2074186Y165676D01*
X2075426Y165259D01*
X2076666Y165676D01*
X2077596Y166717D01*
X2078216Y167967D01*
X2078681Y169634D01*
X2078836Y171509D01*
X2078681Y173384D01*
X2078216Y175051D01*
X2077596Y176301D01*
X2076666Y177342D01*
X2075426Y177759D01*
G01X2035281Y208267D02*
X2036366Y209726D01*
X2037296Y210559D01*
X2038536Y210976D01*
X2039621Y210559D01*
X2040396Y209726D01*
X2041016Y208476D01*
X2041171Y207017D01*
X2041016Y205767D01*
X2040396Y204517D01*
X2039466Y203476D01*
X2038381Y203059D01*
X2037141Y203476D01*
X2036056Y204725D01*
X2035436Y206601D01*
X2035281Y208684D01*
X2035591Y211392D01*
X2036056Y212851D01*
X2036831Y214309D01*
X2037916Y215351D01*
X2039001Y215559D01*
X2040086Y215142D01*
X2040861Y214101D01*
G01X2050316Y203059D02*
X2050626Y205767D01*
X2051091Y208059D01*
X2051711Y210142D01*
X2052486Y212434D01*
X2053726Y215559D01*
X2047526D01*
G01X2063026Y202642D02*
X2062716Y202851D01*
Y203267D01*
X2063026Y203476D01*
X2063336Y203267D01*
Y202851D01*
X2063026Y202642D01*
G01X2075426Y215559D02*
X2074186Y215142D01*
X2073256Y214101D01*
X2072636Y212851D01*
X2072171Y211184D01*
X2072016Y209309D01*
X2072171Y207434D01*
X2072636Y205767D01*
X2073256Y204517D01*
X2074186Y203476D01*
X2075426Y203059D01*
X2076666Y203476D01*
X2077596Y204517D01*
X2078216Y205767D01*
X2078681Y207434D01*
X2078836Y209309D01*
X2078681Y211184D01*
X2078216Y212851D01*
X2077596Y214101D01*
X2076666Y215142D01*
X2075426Y215559D01*
G01X2035281Y246067D02*
X2036366Y247526D01*
X2037296Y248359D01*
X2038536Y248776D01*
X2039621Y248359D01*
X2040396Y247526D01*
X2041016Y246276D01*
X2041171Y244817D01*
X2041016Y243567D01*
X2040396Y242317D01*
X2039466Y241276D01*
X2038381Y240859D01*
X2037141Y241276D01*
X2036056Y242525D01*
X2035436Y244401D01*
X2035281Y246484D01*
X2035591Y249192D01*
X2036056Y250651D01*
X2036831Y252109D01*
X2037916Y253151D01*
X2039001Y253359D01*
X2040086Y252942D01*
X2040861Y251901D01*
G01X2047216Y243359D02*
X2048146Y241900D01*
X2049386Y241067D01*
X2050781Y240859D01*
X2052021Y241067D01*
X2053261Y242109D01*
X2054036Y243359D01*
X2054191Y244609D01*
X2053881Y246067D01*
X2052796Y247109D01*
X2051711Y247526D01*
X2050316D01*
G01X2051711D02*
X2052641Y248151D01*
X2053416Y249192D01*
X2053726Y250442D01*
X2053416Y251692D01*
X2052641Y252734D01*
X2051246Y253359D01*
X2049851Y253151D01*
X2048456Y252317D01*
G01X2063026Y240442D02*
X2062716Y240651D01*
Y241067D01*
X2063026Y241276D01*
X2063336Y241067D01*
Y240651D01*
X2063026Y240442D01*
G01X2075426Y253359D02*
X2074186Y252942D01*
X2073256Y251901D01*
X2072636Y250651D01*
X2072171Y248984D01*
X2072016Y247109D01*
X2072171Y245234D01*
X2072636Y243567D01*
X2073256Y242317D01*
X2074186Y241276D01*
X2075426Y240859D01*
X2076666Y241276D01*
X2077596Y242317D01*
X2078216Y243567D01*
X2078681Y245234D01*
X2078836Y247109D01*
X2078681Y248984D01*
X2078216Y250651D01*
X2077596Y251901D01*
X2076666Y252942D01*
X2075426Y253359D01*
G01X2040086Y278659D02*
Y291159D01*
X2034351Y282201D01*
X2042101D01*
G01X2047681Y283867D02*
X2048766Y285326D01*
X2049696Y286159D01*
X2050936Y286576D01*
X2052021Y286159D01*
X2052796Y285326D01*
X2053416Y284076D01*
X2053571Y282617D01*
X2053416Y281367D01*
X2052796Y280117D01*
X2051866Y279076D01*
X2050781Y278659D01*
X2049541Y279076D01*
X2048456Y280325D01*
X2047836Y282201D01*
X2047681Y284284D01*
X2047991Y286992D01*
X2048456Y288451D01*
X2049231Y289909D01*
X2050316Y290951D01*
X2051401Y291159D01*
X2052486Y290742D01*
X2053261Y289701D01*
G01X2063026Y278242D02*
X2062716Y278451D01*
Y278867D01*
X2063026Y279076D01*
X2063336Y278867D01*
Y278451D01*
X2063026Y278242D01*
G01X2075426Y291159D02*
X2074186Y290742D01*
X2073256Y289701D01*
X2072636Y288451D01*
X2072171Y286784D01*
X2072016Y284909D01*
X2072171Y283034D01*
X2072636Y281367D01*
X2073256Y280117D01*
X2074186Y279076D01*
X2075426Y278659D01*
X2076666Y279076D01*
X2077596Y280117D01*
X2078216Y281367D01*
X2078681Y283034D01*
X2078836Y284909D01*
X2078681Y286784D01*
X2078216Y288451D01*
X2077596Y289701D01*
X2076666Y290742D01*
X2075426Y291159D01*
G01X2040086Y316459D02*
Y328959D01*
X2034351Y320001D01*
X2042101D01*
G01X2047681Y326876D02*
X2048611Y328125D01*
X2049696Y328751D01*
X2050936Y328959D01*
X2052486Y328542D01*
X2053571Y327501D01*
X2053881Y326251D01*
X2053726Y325000D01*
X2053106Y323959D01*
X2050006Y321876D01*
X2048611Y320417D01*
X2047681Y318334D01*
X2047371Y316459D01*
X2053881D01*
G01X2063026Y316042D02*
X2062716Y316251D01*
Y316667D01*
X2063026Y316876D01*
X2063336Y316667D01*
Y316251D01*
X2063026Y316042D01*
G01X2075426Y328959D02*
X2074186Y328542D01*
X2073256Y327501D01*
X2072636Y326251D01*
X2072171Y324584D01*
X2072016Y322709D01*
X2072171Y320834D01*
X2072636Y319167D01*
X2073256Y317917D01*
X2074186Y316876D01*
X2075426Y316459D01*
X2076666Y316876D01*
X2077596Y317917D01*
X2078216Y319167D01*
X2078681Y320834D01*
X2078836Y322709D01*
X2078681Y324584D01*
X2078216Y326251D01*
X2077596Y327501D01*
X2076666Y328542D01*
X2075426Y328959D01*
G01X2040086Y354259D02*
Y366759D01*
X2034351Y357801D01*
X2042101D01*
G01X2050626Y354259D02*
Y366759D01*
X2048766Y364259D01*
G01Y354259D02*
X2052486D01*
G01X2063026Y353842D02*
X2062716Y354051D01*
Y354467D01*
X2063026Y354676D01*
X2063336Y354467D01*
Y354051D01*
X2063026Y353842D01*
G01X2075426Y366759D02*
X2074186Y366342D01*
X2073256Y365301D01*
X2072636Y364051D01*
X2072171Y362384D01*
X2072016Y360509D01*
X2072171Y358634D01*
X2072636Y356967D01*
X2073256Y355717D01*
X2074186Y354676D01*
X2075426Y354259D01*
X2076666Y354676D01*
X2077596Y355717D01*
X2078216Y356967D01*
X2078681Y358634D01*
X2078836Y360509D01*
X2078681Y362384D01*
X2078216Y364051D01*
X2077596Y365301D01*
X2076666Y366342D01*
X2075426Y366759D01*
G01X2033886Y392059D02*
Y404559D01*
X2028151Y395601D01*
X2035901D01*
G01X2044426Y404559D02*
X2043186Y404142D01*
X2042256Y403101D01*
X2041636Y401851D01*
X2041171Y400184D01*
X2041016Y398309D01*
X2041171Y396434D01*
X2041636Y394767D01*
X2042256Y393517D01*
X2043186Y392476D01*
X2044426Y392059D01*
X2045666Y392476D01*
X2046596Y393517D01*
X2047216Y394767D01*
X2047681Y396434D01*
X2047836Y398309D01*
X2047681Y400184D01*
X2047216Y401851D01*
X2046596Y403101D01*
X2045666Y404142D01*
X2044426Y404559D01*
G01X2056826Y391642D02*
X2056516Y391851D01*
Y392267D01*
X2056826Y392476D01*
X2057136Y392267D01*
Y391851D01*
X2056826Y391642D01*
G01X2069226Y392059D02*
Y404559D01*
X2067366Y402059D01*
G01Y392059D02*
X2071086D01*
G01X2078216Y393934D02*
X2079146Y392892D01*
X2080231Y392267D01*
X2081626Y392059D01*
X2083021Y392476D01*
X2084106Y393309D01*
X2084881Y394767D01*
X2085036Y396434D01*
X2084726Y398101D01*
X2083951Y399142D01*
X2082866Y399976D01*
X2081781Y400184D01*
X2080696Y399976D01*
X2079301Y399142D01*
X2079766Y404559D01*
X2083951D01*
G01X2040086Y429859D02*
Y442359D01*
X2034351Y433401D01*
X2042101D01*
G01X2050626Y442359D02*
X2049386Y441942D01*
X2048456Y440901D01*
X2047836Y439651D01*
X2047371Y437984D01*
X2047216Y436109D01*
X2047371Y434234D01*
X2047836Y432567D01*
X2048456Y431317D01*
X2049386Y430276D01*
X2050626Y429859D01*
X2051866Y430276D01*
X2052796Y431317D01*
X2053416Y432567D01*
X2053881Y434234D01*
X2054036Y436109D01*
X2053881Y437984D01*
X2053416Y439651D01*
X2052796Y440901D01*
X2051866Y441942D01*
X2050626Y442359D01*
G01X2063026Y429442D02*
X2062716Y429651D01*
Y430067D01*
X2063026Y430276D01*
X2063336Y430067D01*
Y429651D01*
X2063026Y429442D01*
G01X2075426Y442359D02*
X2074186Y441942D01*
X2073256Y440901D01*
X2072636Y439651D01*
X2072171Y437984D01*
X2072016Y436109D01*
X2072171Y434234D01*
X2072636Y432567D01*
X2073256Y431317D01*
X2074186Y430276D01*
X2075426Y429859D01*
X2076666Y430276D01*
X2077596Y431317D01*
X2078216Y432567D01*
X2078681Y434234D01*
X2078836Y436109D01*
X2078681Y437984D01*
X2078216Y439651D01*
X2077596Y440901D01*
X2076666Y441942D01*
X2075426Y442359D01*
G01X2034816Y470159D02*
X2035746Y468700D01*
X2036986Y467867D01*
X2038381Y467659D01*
X2039621Y467867D01*
X2040861Y468909D01*
X2041636Y470159D01*
X2041791Y471409D01*
X2041481Y472867D01*
X2040396Y473909D01*
X2039311Y474326D01*
X2037916D01*
G01X2039311D02*
X2040241Y474951D01*
X2041016Y475992D01*
X2041326Y477242D01*
X2041016Y478492D01*
X2040241Y479534D01*
X2038846Y480159D01*
X2037451Y479951D01*
X2036056Y479117D01*
G01X2047681Y472867D02*
X2048766Y474326D01*
X2049696Y475159D01*
X2050936Y475576D01*
X2052021Y475159D01*
X2052796Y474326D01*
X2053416Y473076D01*
X2053571Y471617D01*
X2053416Y470367D01*
X2052796Y469117D01*
X2051866Y468076D01*
X2050781Y467659D01*
X2049541Y468076D01*
X2048456Y469325D01*
X2047836Y471201D01*
X2047681Y473284D01*
X2047991Y475992D01*
X2048456Y477451D01*
X2049231Y478909D01*
X2050316Y479951D01*
X2051401Y480159D01*
X2052486Y479742D01*
X2053261Y478701D01*
G01X2063026Y467242D02*
X2062716Y467451D01*
Y467867D01*
X2063026Y468076D01*
X2063336Y467867D01*
Y467451D01*
X2063026Y467242D01*
G01X2075426Y480159D02*
X2074186Y479742D01*
X2073256Y478701D01*
X2072636Y477451D01*
X2072171Y475784D01*
X2072016Y473909D01*
X2072171Y472034D01*
X2072636Y470367D01*
X2073256Y469117D01*
X2074186Y468076D01*
X2075426Y467659D01*
X2076666Y468076D01*
X2077596Y469117D01*
X2078216Y470367D01*
X2078681Y472034D01*
X2078836Y473909D01*
X2078681Y475784D01*
X2078216Y477451D01*
X2077596Y478701D01*
X2076666Y479742D01*
X2075426Y480159D01*
G01X2034816Y507959D02*
X2035746Y506500D01*
X2036986Y505667D01*
X2038381Y505459D01*
X2039621Y505667D01*
X2040861Y506709D01*
X2041636Y507959D01*
X2041791Y509209D01*
X2041481Y510667D01*
X2040396Y511709D01*
X2039311Y512126D01*
X2037916D01*
G01X2039311D02*
X2040241Y512751D01*
X2041016Y513792D01*
X2041326Y515042D01*
X2041016Y516292D01*
X2040241Y517334D01*
X2038846Y517959D01*
X2037451Y517751D01*
X2036056Y516917D01*
G01X2052486Y505459D02*
Y517959D01*
X2046751Y509001D01*
X2054501D01*
G01X2063026Y505042D02*
X2062716Y505251D01*
Y505667D01*
X2063026Y505876D01*
X2063336Y505667D01*
Y505251D01*
X2063026Y505042D01*
G01X2075426Y517959D02*
X2074186Y517542D01*
X2073256Y516501D01*
X2072636Y515251D01*
X2072171Y513584D01*
X2072016Y511709D01*
X2072171Y509834D01*
X2072636Y508167D01*
X2073256Y506917D01*
X2074186Y505876D01*
X2075426Y505459D01*
X2076666Y505876D01*
X2077596Y506917D01*
X2078216Y508167D01*
X2078681Y509834D01*
X2078836Y511709D01*
X2078681Y513584D01*
X2078216Y515251D01*
X2077596Y516501D01*
X2076666Y517542D01*
X2075426Y517959D01*
G01X2038226Y543259D02*
Y555759D01*
X2036366Y553259D01*
G01Y543259D02*
X2040086D01*
G01X2050626Y555759D02*
X2049386Y555342D01*
X2048456Y554301D01*
X2047836Y553051D01*
X2047371Y551384D01*
X2047216Y549509D01*
X2047371Y547634D01*
X2047836Y545967D01*
X2048456Y544717D01*
X2049386Y543676D01*
X2050626Y543259D01*
X2051866Y543676D01*
X2052796Y544717D01*
X2053416Y545967D01*
X2053881Y547634D01*
X2054036Y549509D01*
X2053881Y551384D01*
X2053416Y553051D01*
X2052796Y554301D01*
X2051866Y555342D01*
X2050626Y555759D01*
G01X2063026Y542842D02*
X2062716Y543051D01*
Y543467D01*
X2063026Y543676D01*
X2063336Y543467D01*
Y543051D01*
X2063026Y542842D01*
G01X2075426Y555759D02*
X2074186Y555342D01*
X2073256Y554301D01*
X2072636Y553051D01*
X2072171Y551384D01*
X2072016Y549509D01*
X2072171Y547634D01*
X2072636Y545967D01*
X2073256Y544717D01*
X2074186Y543676D01*
X2075426Y543259D01*
X2076666Y543676D01*
X2077596Y544717D01*
X2078216Y545967D01*
X2078681Y547634D01*
X2078836Y549509D01*
X2078681Y551384D01*
X2078216Y553051D01*
X2077596Y554301D01*
X2076666Y555342D01*
X2075426Y555759D01*
G01X2038226Y581059D02*
Y593559D01*
X2036366Y591059D01*
G01Y581059D02*
X2040086D01*
G01X2050626Y593559D02*
X2049386Y593142D01*
X2048456Y592101D01*
X2047836Y590851D01*
X2047371Y589184D01*
X2047216Y587309D01*
X2047371Y585434D01*
X2047836Y583767D01*
X2048456Y582517D01*
X2049386Y581476D01*
X2050626Y581059D01*
X2051866Y581476D01*
X2052796Y582517D01*
X2053416Y583767D01*
X2053881Y585434D01*
X2054036Y587309D01*
X2053881Y589184D01*
X2053416Y590851D01*
X2052796Y592101D01*
X2051866Y593142D01*
X2050626Y593559D01*
G01X2063026Y580642D02*
X2062716Y580851D01*
Y581267D01*
X2063026Y581476D01*
X2063336Y581267D01*
Y580851D01*
X2063026Y580642D01*
G01X2075426Y593559D02*
X2074186Y593142D01*
X2073256Y592101D01*
X2072636Y590851D01*
X2072171Y589184D01*
X2072016Y587309D01*
X2072171Y585434D01*
X2072636Y583767D01*
X2073256Y582517D01*
X2074186Y581476D01*
X2075426Y581059D01*
X2076666Y581476D01*
X2077596Y582517D01*
X2078216Y583767D01*
X2078681Y585434D01*
X2078836Y587309D01*
X2078681Y589184D01*
X2078216Y590851D01*
X2077596Y592101D01*
X2076666Y593142D01*
X2075426Y593559D01*
G01X2056516Y662459D02*
Y674959D01*
X2059616D01*
X2060856Y674334D01*
X2061786Y673501D01*
X2062561Y672251D01*
X2063181Y670792D01*
X2063336Y668709D01*
X2063181Y666626D01*
X2062561Y665167D01*
X2061786Y663917D01*
X2060856Y663084D01*
X2059616Y662459D01*
X2056516D01*
G01X2069226D02*
Y674959D01*
X2073101D01*
X2074341Y674334D01*
X2075116Y673501D01*
X2075426Y671834D01*
X2075116Y670167D01*
X2074186Y669126D01*
X2073101Y668501D01*
X2069226D01*
G01X2073101D02*
X2075426Y662459D01*
G01X2082866Y674959D02*
X2086586D01*
G01X2084726D02*
Y662459D01*
G01X2082866D02*
X2086586D01*
G01X2094026Y674959D02*
Y662459D01*
X2100226D01*
G01X2106426Y674959D02*
Y662459D01*
X2112626D01*
G01X2137736Y673917D02*
X2136806Y674542D01*
X2135721Y674959D01*
X2134481D01*
X2133086Y674334D01*
X2132001Y673292D01*
X2131226Y672042D01*
X2130606Y669959D01*
X2130451Y668084D01*
X2130761Y666209D01*
X2131226Y664959D01*
X2132156Y663709D01*
X2133241Y662876D01*
X2134326Y662459D01*
X2135411D01*
X2136496Y662876D01*
X2137426Y663500D01*
X2138201Y664334D01*
G01X2143471Y662459D02*
Y674959D01*
G01X2149981D02*
Y662459D01*
G01Y668709D02*
X2143471D01*
G01X2155251Y662459D02*
X2159126Y674959D01*
X2163001Y662459D01*
G01X2161606Y666834D02*
X2156646D01*
G01X2168426Y662459D02*
Y674959D01*
X2172301D01*
X2173541Y674334D01*
X2174316Y673501D01*
X2174626Y671834D01*
X2174316Y670167D01*
X2173386Y669126D01*
X2172301Y668501D01*
X2168426D01*
G01X2172301D02*
X2174626Y662459D01*
G01X2183926Y674959D02*
Y662459D01*
G01X2180361Y674959D02*
X2187491D01*
G01X2196326Y662042D02*
X2196016Y662251D01*
Y662667D01*
X2196326Y662876D01*
X2196636Y662667D01*
Y662251D01*
X2196326Y662042D01*
G01Y667667D02*
X2196016Y667876D01*
Y668292D01*
X2196326Y668501D01*
X2196636Y668292D01*
Y667876D01*
X2196326Y667667D01*
G01X2221126Y674959D02*
Y662459D01*
G01X2217561Y674959D02*
X2224691D01*
G01X2233526Y662459D02*
X2232286Y662667D01*
X2231201Y663500D01*
X2230271Y664751D01*
X2229651Y666209D01*
X2229341Y667876D01*
Y669542D01*
X2229651Y671209D01*
X2230271Y672667D01*
X2231201Y673917D01*
X2232286Y674751D01*
X2233526Y674959D01*
X2234766Y674751D01*
X2235851Y673917D01*
X2236781Y672667D01*
X2237401Y671209D01*
X2237711Y669542D01*
Y667876D01*
X2237401Y666209D01*
X2236781Y664751D01*
X2235851Y663500D01*
X2234766Y662667D01*
X2233526Y662459D01*
G01X2242826D02*
Y674959D01*
X2246546D01*
X2247786Y674334D01*
X2248716Y672876D01*
X2249026Y671209D01*
X2248716Y669542D01*
X2247941Y668292D01*
X2246546Y667667D01*
X2242826D01*
G01X2270726Y674959D02*
Y662459D01*
G01X2268556Y670792D02*
X2272896D01*
G01X2283126Y662459D02*
X2282196Y662667D01*
X2281266Y663500D01*
X2280646Y664959D01*
X2280336Y666626D01*
X2280646Y668292D01*
X2281266Y669751D01*
X2282196Y670584D01*
X2283126Y670792D01*
X2284056Y670584D01*
X2284986Y669751D01*
X2285606Y668292D01*
X2285761Y666626D01*
X2285606Y664959D01*
X2284986Y663500D01*
X2284056Y662667D01*
X2283126Y662459D01*
G01X2309166Y669126D02*
X2309786Y669751D01*
X2310251Y670792D01*
X2310561Y672251D01*
X2310251Y673501D01*
X2309631Y674334D01*
X2308546Y674959D01*
X2304361D01*
Y662459D01*
X2309476D01*
X2310561Y663292D01*
X2311181Y664542D01*
X2311491Y666001D01*
X2311181Y667459D01*
X2310251Y668709D01*
X2309166Y669126D01*
X2304361D01*
G01X2320326Y662459D02*
X2319086Y662667D01*
X2318001Y663500D01*
X2317071Y664751D01*
X2316451Y666209D01*
X2316141Y667876D01*
Y669542D01*
X2316451Y671209D01*
X2317071Y672667D01*
X2318001Y673917D01*
X2319086Y674751D01*
X2320326Y674959D01*
X2321566Y674751D01*
X2322651Y673917D01*
X2323581Y672667D01*
X2324201Y671209D01*
X2324511Y669542D01*
Y667876D01*
X2324201Y666209D01*
X2323581Y664751D01*
X2322651Y663500D01*
X2321566Y662667D01*
X2320326Y662459D01*
G01X2332726Y674959D02*
Y662459D01*
G01X2329161Y674959D02*
X2336291D01*
G01X2345126D02*
Y662459D01*
G01X2341561Y674959D02*
X2348691D01*
G01X2357526Y662459D02*
X2356286Y662667D01*
X2355201Y663500D01*
X2354271Y664751D01*
X2353651Y666209D01*
X2353341Y667876D01*
Y669542D01*
X2353651Y671209D01*
X2354271Y672667D01*
X2355201Y673917D01*
X2356286Y674751D01*
X2357526Y674959D01*
X2358766Y674751D01*
X2359851Y673917D01*
X2360781Y672667D01*
X2361401Y671209D01*
X2361711Y669542D01*
Y667876D01*
X2361401Y666209D01*
X2360781Y664751D01*
X2359851Y663500D01*
X2358766Y662667D01*
X2357526Y662459D01*
G01X2365896D02*
Y674959D01*
X2369926Y664542D01*
X2373956Y674959D01*
Y662459D01*
G01X2087051Y637459D02*
X2090926Y649959D01*
X2094801Y637459D01*
G01X2093406Y641834D02*
X2088446D01*
G01X2100226Y649959D02*
Y637459D01*
X2106426D01*
G01X2112626Y649959D02*
Y637459D01*
X2118826D01*
G01X2137116Y649959D02*
Y641001D01*
X2137736Y639125D01*
X2138976Y637876D01*
X2140526Y637459D01*
X2142076Y637876D01*
X2143316Y639125D01*
X2143936Y641001D01*
Y649959D01*
G01X2149361Y637459D02*
Y649959D01*
X2156491Y637459D01*
Y649959D01*
G01X2163466D02*
X2167186D01*
G01X2165326D02*
Y637459D01*
G01X2163466D02*
X2167186D01*
G01X2177726Y649959D02*
Y637459D01*
G01X2174161Y649959D02*
X2181291D01*
G01X2186871Y639125D02*
X2188111Y638084D01*
X2189506Y637459D01*
X2190746D01*
X2191986Y638084D01*
X2192916Y639125D01*
X2193381Y640584D01*
X2193071Y642042D01*
X2192296Y643292D01*
X2190901Y644126D01*
X2189041Y644542D01*
X2187956Y645376D01*
X2187491Y646834D01*
X2187801Y648292D01*
X2188576Y649334D01*
X2189661Y649959D01*
X2190746D01*
X2191831Y649542D01*
X2192761Y648501D01*
G01X2211051Y637459D02*
X2214926Y649959D01*
X2218801Y637459D01*
G01X2217406Y641834D02*
X2212446D01*
G01X2224226Y637459D02*
Y649959D01*
X2228101D01*
X2229341Y649334D01*
X2230116Y648501D01*
X2230426Y646834D01*
X2230116Y645167D01*
X2229186Y644126D01*
X2228101Y643501D01*
X2224226D01*
G01X2228101D02*
X2230426Y637459D01*
G01X2242826D02*
X2236626D01*
Y649959D01*
X2242826D01*
G01X2240346Y643917D02*
X2236626D01*
G01X2262666Y649959D02*
X2266386D01*
G01X2264526D02*
Y637459D01*
G01X2262666D02*
X2266386D01*
G01X2273361D02*
Y649959D01*
X2280491Y637459D01*
Y649959D01*
G01X2297696Y637459D02*
Y649959D01*
X2301726Y639542D01*
X2305756Y649959D01*
Y637459D01*
G01X2312266Y649959D02*
X2315986D01*
G01X2314126D02*
Y637459D01*
G01X2312266D02*
X2315986D01*
G01X2323426Y649959D02*
Y637459D01*
X2329626D01*
G01X2335671Y639125D02*
X2336911Y638084D01*
X2338306Y637459D01*
X2339546D01*
X2340786Y638084D01*
X2341716Y639125D01*
X2342181Y640584D01*
X2341871Y642042D01*
X2341096Y643292D01*
X2339701Y644126D01*
X2337841Y644542D01*
X2336756Y645376D01*
X2336291Y646834D01*
X2336601Y648292D01*
X2337376Y649334D01*
X2338461Y649959D01*
X2339546D01*
X2340631Y649542D01*
X2341561Y648501D01*
G01X2171526Y624959D02*
Y612459D01*
G01X2167961Y624959D02*
X2175091D01*
G01X2183926Y612459D02*
X2182686Y612667D01*
X2181601Y613500D01*
X2180671Y614751D01*
X2180051Y616209D01*
X2179741Y617876D01*
Y619542D01*
X2180051Y621209D01*
X2180671Y622667D01*
X2181601Y623917D01*
X2182686Y624751D01*
X2183926Y624959D01*
X2185166Y624751D01*
X2186251Y623917D01*
X2187181Y622667D01*
X2187801Y621209D01*
X2188111Y619542D01*
Y617876D01*
X2187801Y616209D01*
X2187181Y614751D01*
X2186251Y613500D01*
X2185166Y612667D01*
X2183926Y612459D01*
G01X2193226Y624959D02*
Y612459D01*
X2199426D01*
G01X2211826D02*
X2205626D01*
Y624959D01*
X2211826D01*
G01X2209346Y618917D02*
X2205626D01*
G01X2218026Y612459D02*
Y624959D01*
X2221901D01*
X2223141Y624334D01*
X2223916Y623501D01*
X2224226Y621834D01*
X2223916Y620167D01*
X2222986Y619126D01*
X2221901Y618501D01*
X2218026D01*
G01X2221901D02*
X2224226Y612459D01*
G01X2229651D02*
X2233526Y624959D01*
X2237401Y612459D01*
G01X2236006Y616834D02*
X2231046D01*
G01X2242361Y612459D02*
Y624959D01*
X2249491Y612459D01*
Y624959D01*
G01X2261736Y623917D02*
X2260806Y624542D01*
X2259721Y624959D01*
X2258481D01*
X2257086Y624334D01*
X2256001Y623292D01*
X2255226Y622042D01*
X2254606Y619959D01*
X2254451Y618084D01*
X2254761Y616209D01*
X2255226Y614959D01*
X2256156Y613709D01*
X2257241Y612876D01*
X2258326Y612459D01*
X2259411D01*
X2260496Y612876D01*
X2261426Y613500D01*
X2262201Y614334D01*
G01X2273826Y612459D02*
X2267626D01*
Y624959D01*
X2273826D01*
G01X2271346Y618917D02*
X2267626D01*
G01X2278476Y608292D02*
X2287776D01*
G01X2292116Y612459D02*
Y624959D01*
X2295216D01*
X2296456Y624334D01*
X2297386Y623501D01*
X2298161Y622251D01*
X2298781Y620792D01*
X2298936Y618709D01*
X2298781Y616626D01*
X2298161Y615167D01*
X2297386Y613917D01*
X2296456Y613084D01*
X2295216Y612459D01*
X2292116D01*
G01X2304826D02*
Y624959D01*
X2308701D01*
X2309941Y624334D01*
X2310716Y623501D01*
X2311026Y621834D01*
X2310716Y620167D01*
X2309786Y619126D01*
X2308701Y618501D01*
X2304826D01*
G01X2308701D02*
X2311026Y612459D01*
G01X2318466Y624959D02*
X2322186D01*
G01X2320326D02*
Y612459D01*
G01X2318466D02*
X2322186D01*
G01X2329626Y624959D02*
Y612459D01*
X2335826D01*
G01X2342026Y624959D02*
Y612459D01*
X2348226D01*
G01X2207021Y-95174D02*
X2210741D01*
G01X2208726Y-92466D02*
Y-97883D01*
G01X2218181Y-88924D02*
X2219111Y-87675D01*
X2220196Y-87049D01*
X2221436Y-86841D01*
X2222986Y-87258D01*
X2224071Y-88299D01*
X2224381Y-89549D01*
X2224226Y-90800D01*
X2223606Y-91841D01*
X2220506Y-93924D01*
X2219111Y-95383D01*
X2218181Y-97466D01*
X2217871Y-99341D01*
X2224381D01*
G01X2233526Y-99758D02*
X2233216Y-99549D01*
Y-99133D01*
X2233526Y-98924D01*
X2233836Y-99133D01*
Y-99549D01*
X2233526Y-99758D01*
G01X2245926Y-86841D02*
X2244686Y-87258D01*
X2243756Y-88299D01*
X2243136Y-89549D01*
X2242671Y-91216D01*
X2242516Y-93091D01*
X2242671Y-94966D01*
X2243136Y-96633D01*
X2243756Y-97883D01*
X2244686Y-98924D01*
X2245926Y-99341D01*
X2247166Y-98924D01*
X2248096Y-97883D01*
X2248716Y-96633D01*
X2249181Y-94966D01*
X2249336Y-93091D01*
X2249181Y-91216D01*
X2248716Y-89549D01*
X2248096Y-88299D01*
X2247166Y-87258D01*
X2245926Y-86841D01*
G01X2255536Y-99758D02*
X2261116Y-86841D01*
G01X2268711Y-95174D02*
X2272741D01*
G01X2280181Y-88924D02*
X2281111Y-87675D01*
X2282196Y-87049D01*
X2283436Y-86841D01*
X2284986Y-87258D01*
X2286071Y-88299D01*
X2286381Y-89549D01*
X2286226Y-90800D01*
X2285606Y-91841D01*
X2282506Y-93924D01*
X2281111Y-95383D01*
X2280181Y-97466D01*
X2279871Y-99341D01*
X2286381D01*
G01X2295526Y-99758D02*
X2295216Y-99549D01*
Y-99133D01*
X2295526Y-98924D01*
X2295836Y-99133D01*
Y-99549D01*
X2295526Y-99758D01*
G01X2307926Y-86841D02*
X2306686Y-87258D01*
X2305756Y-88299D01*
X2305136Y-89549D01*
X2304671Y-91216D01*
X2304516Y-93091D01*
X2304671Y-94966D01*
X2305136Y-96633D01*
X2305756Y-97883D01*
X2306686Y-98924D01*
X2307926Y-99341D01*
X2309166Y-98924D01*
X2310096Y-97883D01*
X2310716Y-96633D01*
X2311181Y-94966D01*
X2311336Y-93091D01*
X2311181Y-91216D01*
X2310716Y-89549D01*
X2310096Y-88299D01*
X2309166Y-87258D01*
X2307926Y-86841D01*
G01X2207021Y-57374D02*
X2210741D01*
G01X2208726Y-54666D02*
Y-60083D01*
G01X2218181Y-51124D02*
X2219111Y-49875D01*
X2220196Y-49249D01*
X2221436Y-49041D01*
X2222986Y-49458D01*
X2224071Y-50499D01*
X2224381Y-51749D01*
X2224226Y-53000D01*
X2223606Y-54041D01*
X2220506Y-56124D01*
X2219111Y-57583D01*
X2218181Y-59666D01*
X2217871Y-61541D01*
X2224381D01*
G01X2233526Y-61958D02*
X2233216Y-61749D01*
Y-61333D01*
X2233526Y-61124D01*
X2233836Y-61333D01*
Y-61749D01*
X2233526Y-61958D01*
G01X2245926Y-49041D02*
X2244686Y-49458D01*
X2243756Y-50499D01*
X2243136Y-51749D01*
X2242671Y-53416D01*
X2242516Y-55291D01*
X2242671Y-57166D01*
X2243136Y-58833D01*
X2243756Y-60083D01*
X2244686Y-61124D01*
X2245926Y-61541D01*
X2247166Y-61124D01*
X2248096Y-60083D01*
X2248716Y-58833D01*
X2249181Y-57166D01*
X2249336Y-55291D01*
X2249181Y-53416D01*
X2248716Y-51749D01*
X2248096Y-50499D01*
X2247166Y-49458D01*
X2245926Y-49041D01*
G01X2255536Y-61958D02*
X2261116Y-49041D01*
G01X2268711Y-57374D02*
X2272741D01*
G01X2280181Y-51124D02*
X2281111Y-49875D01*
X2282196Y-49249D01*
X2283436Y-49041D01*
X2284986Y-49458D01*
X2286071Y-50499D01*
X2286381Y-51749D01*
X2286226Y-53000D01*
X2285606Y-54041D01*
X2282506Y-56124D01*
X2281111Y-57583D01*
X2280181Y-59666D01*
X2279871Y-61541D01*
X2286381D01*
G01X2295526Y-61958D02*
X2295216Y-61749D01*
Y-61333D01*
X2295526Y-61124D01*
X2295836Y-61333D01*
Y-61749D01*
X2295526Y-61958D01*
G01X2307926Y-49041D02*
X2306686Y-49458D01*
X2305756Y-50499D01*
X2305136Y-51749D01*
X2304671Y-53416D01*
X2304516Y-55291D01*
X2304671Y-57166D01*
X2305136Y-58833D01*
X2305756Y-60083D01*
X2306686Y-61124D01*
X2307926Y-61541D01*
X2309166Y-61124D01*
X2310096Y-60083D01*
X2310716Y-58833D01*
X2311181Y-57166D01*
X2311336Y-55291D01*
X2311181Y-53416D01*
X2310716Y-51749D01*
X2310096Y-50499D01*
X2309166Y-49458D01*
X2307926Y-49041D01*
G01X2207021Y-19574D02*
X2210741D01*
G01X2208726Y-16866D02*
Y-22283D01*
G01X2218181Y-13324D02*
X2219111Y-12075D01*
X2220196Y-11449D01*
X2221436Y-11241D01*
X2222986Y-11658D01*
X2224071Y-12699D01*
X2224381Y-13949D01*
X2224226Y-15200D01*
X2223606Y-16241D01*
X2220506Y-18324D01*
X2219111Y-19783D01*
X2218181Y-21866D01*
X2217871Y-23741D01*
X2224381D01*
G01X2233526Y-24158D02*
X2233216Y-23949D01*
Y-23533D01*
X2233526Y-23324D01*
X2233836Y-23533D01*
Y-23949D01*
X2233526Y-24158D01*
G01X2245926Y-11241D02*
X2244686Y-11658D01*
X2243756Y-12699D01*
X2243136Y-13949D01*
X2242671Y-15616D01*
X2242516Y-17491D01*
X2242671Y-19366D01*
X2243136Y-21033D01*
X2243756Y-22283D01*
X2244686Y-23324D01*
X2245926Y-23741D01*
X2247166Y-23324D01*
X2248096Y-22283D01*
X2248716Y-21033D01*
X2249181Y-19366D01*
X2249336Y-17491D01*
X2249181Y-15616D01*
X2248716Y-13949D01*
X2248096Y-12699D01*
X2247166Y-11658D01*
X2245926Y-11241D01*
G01X2255536Y-24158D02*
X2261116Y-11241D01*
G01X2268711Y-19574D02*
X2272741D01*
G01X2283126Y-11241D02*
X2281886Y-11658D01*
X2280956Y-12699D01*
X2280336Y-13949D01*
X2279871Y-15616D01*
X2279716Y-17491D01*
X2279871Y-19366D01*
X2280336Y-21033D01*
X2280956Y-22283D01*
X2281886Y-23324D01*
X2283126Y-23741D01*
X2284366Y-23324D01*
X2285296Y-22283D01*
X2285916Y-21033D01*
X2286381Y-19366D01*
X2286536Y-17491D01*
X2286381Y-15616D01*
X2285916Y-13949D01*
X2285296Y-12699D01*
X2284366Y-11658D01*
X2283126Y-11241D01*
G01X2295526Y-24158D02*
X2295216Y-23949D01*
Y-23533D01*
X2295526Y-23324D01*
X2295836Y-23533D01*
Y-23949D01*
X2295526Y-24158D01*
G01X2307926Y-11241D02*
X2306686Y-11658D01*
X2305756Y-12699D01*
X2305136Y-13949D01*
X2304671Y-15616D01*
X2304516Y-17491D01*
X2304671Y-19366D01*
X2305136Y-21033D01*
X2305756Y-22283D01*
X2306686Y-23324D01*
X2307926Y-23741D01*
X2309166Y-23324D01*
X2310096Y-22283D01*
X2310716Y-21033D01*
X2311181Y-19366D01*
X2311336Y-17491D01*
X2311181Y-15616D01*
X2310716Y-13949D01*
X2310096Y-12699D01*
X2309166Y-11658D01*
X2307926Y-11241D01*
G01X2207021Y18226D02*
X2210741D01*
G01X2208726Y20934D02*
Y15517D01*
G01X2218181Y24476D02*
X2219111Y25725D01*
X2220196Y26351D01*
X2221436Y26559D01*
X2222986Y26142D01*
X2224071Y25101D01*
X2224381Y23851D01*
X2224226Y22600D01*
X2223606Y21559D01*
X2220506Y19476D01*
X2219111Y18017D01*
X2218181Y15934D01*
X2217871Y14059D01*
X2224381D01*
G01X2233526Y13642D02*
X2233216Y13851D01*
Y14267D01*
X2233526Y14476D01*
X2233836Y14267D01*
Y13851D01*
X2233526Y13642D01*
G01X2245926Y26559D02*
X2244686Y26142D01*
X2243756Y25101D01*
X2243136Y23851D01*
X2242671Y22184D01*
X2242516Y20309D01*
X2242671Y18434D01*
X2243136Y16767D01*
X2243756Y15517D01*
X2244686Y14476D01*
X2245926Y14059D01*
X2247166Y14476D01*
X2248096Y15517D01*
X2248716Y16767D01*
X2249181Y18434D01*
X2249336Y20309D01*
X2249181Y22184D01*
X2248716Y23851D01*
X2248096Y25101D01*
X2247166Y26142D01*
X2245926Y26559D01*
G01X2255536Y13642D02*
X2261116Y26559D01*
G01X2268711Y18226D02*
X2272741D01*
G01X2280181Y24476D02*
X2281111Y25725D01*
X2282196Y26351D01*
X2283436Y26559D01*
X2284986Y26142D01*
X2286071Y25101D01*
X2286381Y23851D01*
X2286226Y22600D01*
X2285606Y21559D01*
X2282506Y19476D01*
X2281111Y18017D01*
X2280181Y15934D01*
X2279871Y14059D01*
X2286381D01*
G01X2295526Y13642D02*
X2295216Y13851D01*
Y14267D01*
X2295526Y14476D01*
X2295836Y14267D01*
Y13851D01*
X2295526Y13642D01*
G01X2307926Y26559D02*
X2306686Y26142D01*
X2305756Y25101D01*
X2305136Y23851D01*
X2304671Y22184D01*
X2304516Y20309D01*
X2304671Y18434D01*
X2305136Y16767D01*
X2305756Y15517D01*
X2306686Y14476D01*
X2307926Y14059D01*
X2309166Y14476D01*
X2310096Y15517D01*
X2310716Y16767D01*
X2311181Y18434D01*
X2311336Y20309D01*
X2311181Y22184D01*
X2310716Y23851D01*
X2310096Y25101D01*
X2309166Y26142D01*
X2307926Y26559D01*
G01X2207021Y56026D02*
X2210741D01*
G01X2208726Y58734D02*
Y53317D01*
G01X2222986Y51859D02*
Y64359D01*
X2217251Y55401D01*
X2225001D01*
G01X2233526Y51442D02*
X2233216Y51651D01*
Y52067D01*
X2233526Y52276D01*
X2233836Y52067D01*
Y51651D01*
X2233526Y51442D01*
G01X2245926Y64359D02*
X2244686Y63942D01*
X2243756Y62901D01*
X2243136Y61651D01*
X2242671Y59984D01*
X2242516Y58109D01*
X2242671Y56234D01*
X2243136Y54567D01*
X2243756Y53317D01*
X2244686Y52276D01*
X2245926Y51859D01*
X2247166Y52276D01*
X2248096Y53317D01*
X2248716Y54567D01*
X2249181Y56234D01*
X2249336Y58109D01*
X2249181Y59984D01*
X2248716Y61651D01*
X2248096Y62901D01*
X2247166Y63942D01*
X2245926Y64359D01*
G01X2255536Y51442D02*
X2261116Y64359D01*
G01X2268711Y56026D02*
X2272741D01*
G01X2284986Y51859D02*
Y64359D01*
X2279251Y55401D01*
X2287001D01*
G01X2295526Y51442D02*
X2295216Y51651D01*
Y52067D01*
X2295526Y52276D01*
X2295836Y52067D01*
Y51651D01*
X2295526Y51442D01*
G01X2307926Y64359D02*
X2306686Y63942D01*
X2305756Y62901D01*
X2305136Y61651D01*
X2304671Y59984D01*
X2304516Y58109D01*
X2304671Y56234D01*
X2305136Y54567D01*
X2305756Y53317D01*
X2306686Y52276D01*
X2307926Y51859D01*
X2309166Y52276D01*
X2310096Y53317D01*
X2310716Y54567D01*
X2311181Y56234D01*
X2311336Y58109D01*
X2311181Y59984D01*
X2310716Y61651D01*
X2310096Y62901D01*
X2309166Y63942D01*
X2307926Y64359D01*
G01X2207021Y93826D02*
X2210741D01*
G01X2208726Y96534D02*
Y91117D01*
G01X2217716Y92159D02*
X2218646Y90700D01*
X2219886Y89867D01*
X2221281Y89659D01*
X2222521Y89867D01*
X2223761Y90909D01*
X2224536Y92159D01*
X2224691Y93409D01*
X2224381Y94867D01*
X2223296Y95909D01*
X2222211Y96326D01*
X2220816D01*
G01X2222211D02*
X2223141Y96951D01*
X2223916Y97992D01*
X2224226Y99242D01*
X2223916Y100492D01*
X2223141Y101534D01*
X2221746Y102159D01*
X2220351Y101951D01*
X2218956Y101117D01*
G01X2233526Y89242D02*
X2233216Y89451D01*
Y89867D01*
X2233526Y90076D01*
X2233836Y89867D01*
Y89451D01*
X2233526Y89242D01*
G01X2245926Y102159D02*
X2244686Y101742D01*
X2243756Y100701D01*
X2243136Y99451D01*
X2242671Y97784D01*
X2242516Y95909D01*
X2242671Y94034D01*
X2243136Y92367D01*
X2243756Y91117D01*
X2244686Y90076D01*
X2245926Y89659D01*
X2247166Y90076D01*
X2248096Y91117D01*
X2248716Y92367D01*
X2249181Y94034D01*
X2249336Y95909D01*
X2249181Y97784D01*
X2248716Y99451D01*
X2248096Y100701D01*
X2247166Y101742D01*
X2245926Y102159D01*
G01X2255536Y89242D02*
X2261116Y102159D01*
G01X2268711Y93826D02*
X2272741D01*
G01X2279716Y92159D02*
X2280646Y90700D01*
X2281886Y89867D01*
X2283281Y89659D01*
X2284521Y89867D01*
X2285761Y90909D01*
X2286536Y92159D01*
X2286691Y93409D01*
X2286381Y94867D01*
X2285296Y95909D01*
X2284211Y96326D01*
X2282816D01*
G01X2284211D02*
X2285141Y96951D01*
X2285916Y97992D01*
X2286226Y99242D01*
X2285916Y100492D01*
X2285141Y101534D01*
X2283746Y102159D01*
X2282351Y101951D01*
X2280956Y101117D01*
G01X2295526Y89242D02*
X2295216Y89451D01*
Y89867D01*
X2295526Y90076D01*
X2295836Y89867D01*
Y89451D01*
X2295526Y89242D01*
G01X2307926Y102159D02*
X2306686Y101742D01*
X2305756Y100701D01*
X2305136Y99451D01*
X2304671Y97784D01*
X2304516Y95909D01*
X2304671Y94034D01*
X2305136Y92367D01*
X2305756Y91117D01*
X2306686Y90076D01*
X2307926Y89659D01*
X2309166Y90076D01*
X2310096Y91117D01*
X2310716Y92367D01*
X2311181Y94034D01*
X2311336Y95909D01*
X2311181Y97784D01*
X2310716Y99451D01*
X2310096Y100701D01*
X2309166Y101742D01*
X2307926Y102159D01*
G01X2207021Y131626D02*
X2210741D01*
G01X2208726Y134334D02*
Y128917D01*
G01X2217716Y129959D02*
X2218646Y128500D01*
X2219886Y127667D01*
X2221281Y127459D01*
X2222521Y127667D01*
X2223761Y128709D01*
X2224536Y129959D01*
X2224691Y131209D01*
X2224381Y132667D01*
X2223296Y133709D01*
X2222211Y134126D01*
X2220816D01*
G01X2222211D02*
X2223141Y134751D01*
X2223916Y135792D01*
X2224226Y137042D01*
X2223916Y138292D01*
X2223141Y139334D01*
X2221746Y139959D01*
X2220351Y139751D01*
X2218956Y138917D01*
G01X2233526Y127042D02*
X2233216Y127251D01*
Y127667D01*
X2233526Y127876D01*
X2233836Y127667D01*
Y127251D01*
X2233526Y127042D01*
G01X2245926Y139959D02*
X2244686Y139542D01*
X2243756Y138501D01*
X2243136Y137251D01*
X2242671Y135584D01*
X2242516Y133709D01*
X2242671Y131834D01*
X2243136Y130167D01*
X2243756Y128917D01*
X2244686Y127876D01*
X2245926Y127459D01*
X2247166Y127876D01*
X2248096Y128917D01*
X2248716Y130167D01*
X2249181Y131834D01*
X2249336Y133709D01*
X2249181Y135584D01*
X2248716Y137251D01*
X2248096Y138501D01*
X2247166Y139542D01*
X2245926Y139959D01*
G01X2255536Y127042D02*
X2261116Y139959D01*
G01X2268711Y131626D02*
X2272741D01*
G01X2279716Y129959D02*
X2280646Y128500D01*
X2281886Y127667D01*
X2283281Y127459D01*
X2284521Y127667D01*
X2285761Y128709D01*
X2286536Y129959D01*
X2286691Y131209D01*
X2286381Y132667D01*
X2285296Y133709D01*
X2284211Y134126D01*
X2282816D01*
G01X2284211D02*
X2285141Y134751D01*
X2285916Y135792D01*
X2286226Y137042D01*
X2285916Y138292D01*
X2285141Y139334D01*
X2283746Y139959D01*
X2282351Y139751D01*
X2280956Y138917D01*
G01X2295526Y127042D02*
X2295216Y127251D01*
Y127667D01*
X2295526Y127876D01*
X2295836Y127667D01*
Y127251D01*
X2295526Y127042D01*
G01X2307926Y139959D02*
X2306686Y139542D01*
X2305756Y138501D01*
X2305136Y137251D01*
X2304671Y135584D01*
X2304516Y133709D01*
X2304671Y131834D01*
X2305136Y130167D01*
X2305756Y128917D01*
X2306686Y127876D01*
X2307926Y127459D01*
X2309166Y127876D01*
X2310096Y128917D01*
X2310716Y130167D01*
X2311181Y131834D01*
X2311336Y133709D01*
X2311181Y135584D01*
X2310716Y137251D01*
X2310096Y138501D01*
X2309166Y139542D01*
X2307926Y139959D01*
G01X2207021Y169426D02*
X2210741D01*
G01X2208726Y172134D02*
Y166717D01*
G01X2217716Y167759D02*
X2218646Y166300D01*
X2219886Y165467D01*
X2221281Y165259D01*
X2222521Y165467D01*
X2223761Y166509D01*
X2224536Y167759D01*
X2224691Y169009D01*
X2224381Y170467D01*
X2223296Y171509D01*
X2222211Y171926D01*
X2220816D01*
G01X2222211D02*
X2223141Y172551D01*
X2223916Y173592D01*
X2224226Y174842D01*
X2223916Y176092D01*
X2223141Y177134D01*
X2221746Y177759D01*
X2220351Y177551D01*
X2218956Y176717D01*
G01X2233526Y164842D02*
X2233216Y165051D01*
Y165467D01*
X2233526Y165676D01*
X2233836Y165467D01*
Y165051D01*
X2233526Y164842D01*
G01X2245926Y177759D02*
X2244686Y177342D01*
X2243756Y176301D01*
X2243136Y175051D01*
X2242671Y173384D01*
X2242516Y171509D01*
X2242671Y169634D01*
X2243136Y167967D01*
X2243756Y166717D01*
X2244686Y165676D01*
X2245926Y165259D01*
X2247166Y165676D01*
X2248096Y166717D01*
X2248716Y167967D01*
X2249181Y169634D01*
X2249336Y171509D01*
X2249181Y173384D01*
X2248716Y175051D01*
X2248096Y176301D01*
X2247166Y177342D01*
X2245926Y177759D01*
G01X2255536Y164842D02*
X2261116Y177759D01*
G01X2268711Y169426D02*
X2272741D01*
G01X2279716Y167759D02*
X2280646Y166300D01*
X2281886Y165467D01*
X2283281Y165259D01*
X2284521Y165467D01*
X2285761Y166509D01*
X2286536Y167759D01*
X2286691Y169009D01*
X2286381Y170467D01*
X2285296Y171509D01*
X2284211Y171926D01*
X2282816D01*
G01X2284211D02*
X2285141Y172551D01*
X2285916Y173592D01*
X2286226Y174842D01*
X2285916Y176092D01*
X2285141Y177134D01*
X2283746Y177759D01*
X2282351Y177551D01*
X2280956Y176717D01*
G01X2295526Y164842D02*
X2295216Y165051D01*
Y165467D01*
X2295526Y165676D01*
X2295836Y165467D01*
Y165051D01*
X2295526Y164842D01*
G01X2307926Y177759D02*
X2306686Y177342D01*
X2305756Y176301D01*
X2305136Y175051D01*
X2304671Y173384D01*
X2304516Y171509D01*
X2304671Y169634D01*
X2305136Y167967D01*
X2305756Y166717D01*
X2306686Y165676D01*
X2307926Y165259D01*
X2309166Y165676D01*
X2310096Y166717D01*
X2310716Y167967D01*
X2311181Y169634D01*
X2311336Y171509D01*
X2311181Y173384D01*
X2310716Y175051D01*
X2310096Y176301D01*
X2309166Y177342D01*
X2307926Y177759D01*
G01X2207021Y207226D02*
X2210741D01*
G01X2208726Y209934D02*
Y204517D01*
G01X2217716Y205559D02*
X2218646Y204100D01*
X2219886Y203267D01*
X2221281Y203059D01*
X2222521Y203267D01*
X2223761Y204309D01*
X2224536Y205559D01*
X2224691Y206809D01*
X2224381Y208267D01*
X2223296Y209309D01*
X2222211Y209726D01*
X2220816D01*
G01X2222211D02*
X2223141Y210351D01*
X2223916Y211392D01*
X2224226Y212642D01*
X2223916Y213892D01*
X2223141Y214934D01*
X2221746Y215559D01*
X2220351Y215351D01*
X2218956Y214517D01*
G01X2233526Y202642D02*
X2233216Y202851D01*
Y203267D01*
X2233526Y203476D01*
X2233836Y203267D01*
Y202851D01*
X2233526Y202642D01*
G01X2245926Y215559D02*
X2244686Y215142D01*
X2243756Y214101D01*
X2243136Y212851D01*
X2242671Y211184D01*
X2242516Y209309D01*
X2242671Y207434D01*
X2243136Y205767D01*
X2243756Y204517D01*
X2244686Y203476D01*
X2245926Y203059D01*
X2247166Y203476D01*
X2248096Y204517D01*
X2248716Y205767D01*
X2249181Y207434D01*
X2249336Y209309D01*
X2249181Y211184D01*
X2248716Y212851D01*
X2248096Y214101D01*
X2247166Y215142D01*
X2245926Y215559D01*
G01X2255536Y202642D02*
X2261116Y215559D01*
G01X2268711Y207226D02*
X2272741D01*
G01X2279716Y205559D02*
X2280646Y204100D01*
X2281886Y203267D01*
X2283281Y203059D01*
X2284521Y203267D01*
X2285761Y204309D01*
X2286536Y205559D01*
X2286691Y206809D01*
X2286381Y208267D01*
X2285296Y209309D01*
X2284211Y209726D01*
X2282816D01*
G01X2284211D02*
X2285141Y210351D01*
X2285916Y211392D01*
X2286226Y212642D01*
X2285916Y213892D01*
X2285141Y214934D01*
X2283746Y215559D01*
X2282351Y215351D01*
X2280956Y214517D01*
G01X2295526Y202642D02*
X2295216Y202851D01*
Y203267D01*
X2295526Y203476D01*
X2295836Y203267D01*
Y202851D01*
X2295526Y202642D01*
G01X2307926Y215559D02*
X2306686Y215142D01*
X2305756Y214101D01*
X2305136Y212851D01*
X2304671Y211184D01*
X2304516Y209309D01*
X2304671Y207434D01*
X2305136Y205767D01*
X2305756Y204517D01*
X2306686Y203476D01*
X2307926Y203059D01*
X2309166Y203476D01*
X2310096Y204517D01*
X2310716Y205767D01*
X2311181Y207434D01*
X2311336Y209309D01*
X2311181Y211184D01*
X2310716Y212851D01*
X2310096Y214101D01*
X2309166Y215142D01*
X2307926Y215559D01*
G01X2207021Y245026D02*
X2210741D01*
G01X2208726Y247734D02*
Y242317D01*
G01X2217716Y243359D02*
X2218646Y241900D01*
X2219886Y241067D01*
X2221281Y240859D01*
X2222521Y241067D01*
X2223761Y242109D01*
X2224536Y243359D01*
X2224691Y244609D01*
X2224381Y246067D01*
X2223296Y247109D01*
X2222211Y247526D01*
X2220816D01*
G01X2222211D02*
X2223141Y248151D01*
X2223916Y249192D01*
X2224226Y250442D01*
X2223916Y251692D01*
X2223141Y252734D01*
X2221746Y253359D01*
X2220351Y253151D01*
X2218956Y252317D01*
G01X2233526Y240442D02*
X2233216Y240651D01*
Y241067D01*
X2233526Y241276D01*
X2233836Y241067D01*
Y240651D01*
X2233526Y240442D01*
G01X2245926Y253359D02*
X2244686Y252942D01*
X2243756Y251901D01*
X2243136Y250651D01*
X2242671Y248984D01*
X2242516Y247109D01*
X2242671Y245234D01*
X2243136Y243567D01*
X2243756Y242317D01*
X2244686Y241276D01*
X2245926Y240859D01*
X2247166Y241276D01*
X2248096Y242317D01*
X2248716Y243567D01*
X2249181Y245234D01*
X2249336Y247109D01*
X2249181Y248984D01*
X2248716Y250651D01*
X2248096Y251901D01*
X2247166Y252942D01*
X2245926Y253359D01*
G01X2255536Y240442D02*
X2261116Y253359D01*
G01X2268711Y245026D02*
X2272741D01*
G01X2279716Y243359D02*
X2280646Y241900D01*
X2281886Y241067D01*
X2283281Y240859D01*
X2284521Y241067D01*
X2285761Y242109D01*
X2286536Y243359D01*
X2286691Y244609D01*
X2286381Y246067D01*
X2285296Y247109D01*
X2284211Y247526D01*
X2282816D01*
G01X2284211D02*
X2285141Y248151D01*
X2285916Y249192D01*
X2286226Y250442D01*
X2285916Y251692D01*
X2285141Y252734D01*
X2283746Y253359D01*
X2282351Y253151D01*
X2280956Y252317D01*
G01X2295526Y240442D02*
X2295216Y240651D01*
Y241067D01*
X2295526Y241276D01*
X2295836Y241067D01*
Y240651D01*
X2295526Y240442D01*
G01X2307926Y253359D02*
X2306686Y252942D01*
X2305756Y251901D01*
X2305136Y250651D01*
X2304671Y248984D01*
X2304516Y247109D01*
X2304671Y245234D01*
X2305136Y243567D01*
X2305756Y242317D01*
X2306686Y241276D01*
X2307926Y240859D01*
X2309166Y241276D01*
X2310096Y242317D01*
X2310716Y243567D01*
X2311181Y245234D01*
X2311336Y247109D01*
X2311181Y248984D01*
X2310716Y250651D01*
X2310096Y251901D01*
X2309166Y252942D01*
X2307926Y253359D01*
G01X2207021Y282826D02*
X2210741D01*
G01X2208726Y285534D02*
Y280117D01*
G01X2217716Y281159D02*
X2218646Y279700D01*
X2219886Y278867D01*
X2221281Y278659D01*
X2222521Y278867D01*
X2223761Y279909D01*
X2224536Y281159D01*
X2224691Y282409D01*
X2224381Y283867D01*
X2223296Y284909D01*
X2222211Y285326D01*
X2220816D01*
G01X2222211D02*
X2223141Y285951D01*
X2223916Y286992D01*
X2224226Y288242D01*
X2223916Y289492D01*
X2223141Y290534D01*
X2221746Y291159D01*
X2220351Y290951D01*
X2218956Y290117D01*
G01X2233526Y278242D02*
X2233216Y278451D01*
Y278867D01*
X2233526Y279076D01*
X2233836Y278867D01*
Y278451D01*
X2233526Y278242D01*
G01X2245926Y291159D02*
X2244686Y290742D01*
X2243756Y289701D01*
X2243136Y288451D01*
X2242671Y286784D01*
X2242516Y284909D01*
X2242671Y283034D01*
X2243136Y281367D01*
X2243756Y280117D01*
X2244686Y279076D01*
X2245926Y278659D01*
X2247166Y279076D01*
X2248096Y280117D01*
X2248716Y281367D01*
X2249181Y283034D01*
X2249336Y284909D01*
X2249181Y286784D01*
X2248716Y288451D01*
X2248096Y289701D01*
X2247166Y290742D01*
X2245926Y291159D01*
G01X2255536Y278242D02*
X2261116Y291159D01*
G01X2268711Y282826D02*
X2272741D01*
G01X2279716Y281159D02*
X2280646Y279700D01*
X2281886Y278867D01*
X2283281Y278659D01*
X2284521Y278867D01*
X2285761Y279909D01*
X2286536Y281159D01*
X2286691Y282409D01*
X2286381Y283867D01*
X2285296Y284909D01*
X2284211Y285326D01*
X2282816D01*
G01X2284211D02*
X2285141Y285951D01*
X2285916Y286992D01*
X2286226Y288242D01*
X2285916Y289492D01*
X2285141Y290534D01*
X2283746Y291159D01*
X2282351Y290951D01*
X2280956Y290117D01*
G01X2295526Y278242D02*
X2295216Y278451D01*
Y278867D01*
X2295526Y279076D01*
X2295836Y278867D01*
Y278451D01*
X2295526Y278242D01*
G01X2307926Y291159D02*
X2306686Y290742D01*
X2305756Y289701D01*
X2305136Y288451D01*
X2304671Y286784D01*
X2304516Y284909D01*
X2304671Y283034D01*
X2305136Y281367D01*
X2305756Y280117D01*
X2306686Y279076D01*
X2307926Y278659D01*
X2309166Y279076D01*
X2310096Y280117D01*
X2310716Y281367D01*
X2311181Y283034D01*
X2311336Y284909D01*
X2311181Y286784D01*
X2310716Y288451D01*
X2310096Y289701D01*
X2309166Y290742D01*
X2307926Y291159D01*
G01X2207021Y320626D02*
X2210741D01*
G01X2208726Y323334D02*
Y317917D01*
G01X2217716Y318959D02*
X2218646Y317500D01*
X2219886Y316667D01*
X2221281Y316459D01*
X2222521Y316667D01*
X2223761Y317709D01*
X2224536Y318959D01*
X2224691Y320209D01*
X2224381Y321667D01*
X2223296Y322709D01*
X2222211Y323126D01*
X2220816D01*
G01X2222211D02*
X2223141Y323751D01*
X2223916Y324792D01*
X2224226Y326042D01*
X2223916Y327292D01*
X2223141Y328334D01*
X2221746Y328959D01*
X2220351Y328751D01*
X2218956Y327917D01*
G01X2233526Y316042D02*
X2233216Y316251D01*
Y316667D01*
X2233526Y316876D01*
X2233836Y316667D01*
Y316251D01*
X2233526Y316042D01*
G01X2245926Y328959D02*
X2244686Y328542D01*
X2243756Y327501D01*
X2243136Y326251D01*
X2242671Y324584D01*
X2242516Y322709D01*
X2242671Y320834D01*
X2243136Y319167D01*
X2243756Y317917D01*
X2244686Y316876D01*
X2245926Y316459D01*
X2247166Y316876D01*
X2248096Y317917D01*
X2248716Y319167D01*
X2249181Y320834D01*
X2249336Y322709D01*
X2249181Y324584D01*
X2248716Y326251D01*
X2248096Y327501D01*
X2247166Y328542D01*
X2245926Y328959D01*
G01X2255536Y316042D02*
X2261116Y328959D01*
G01X2268711Y320626D02*
X2272741D01*
G01X2279716Y318959D02*
X2280646Y317500D01*
X2281886Y316667D01*
X2283281Y316459D01*
X2284521Y316667D01*
X2285761Y317709D01*
X2286536Y318959D01*
X2286691Y320209D01*
X2286381Y321667D01*
X2285296Y322709D01*
X2284211Y323126D01*
X2282816D01*
G01X2284211D02*
X2285141Y323751D01*
X2285916Y324792D01*
X2286226Y326042D01*
X2285916Y327292D01*
X2285141Y328334D01*
X2283746Y328959D01*
X2282351Y328751D01*
X2280956Y327917D01*
G01X2295526Y316042D02*
X2295216Y316251D01*
Y316667D01*
X2295526Y316876D01*
X2295836Y316667D01*
Y316251D01*
X2295526Y316042D01*
G01X2307926Y328959D02*
X2306686Y328542D01*
X2305756Y327501D01*
X2305136Y326251D01*
X2304671Y324584D01*
X2304516Y322709D01*
X2304671Y320834D01*
X2305136Y319167D01*
X2305756Y317917D01*
X2306686Y316876D01*
X2307926Y316459D01*
X2309166Y316876D01*
X2310096Y317917D01*
X2310716Y319167D01*
X2311181Y320834D01*
X2311336Y322709D01*
X2311181Y324584D01*
X2310716Y326251D01*
X2310096Y327501D01*
X2309166Y328542D01*
X2307926Y328959D01*
G01X2207021Y358426D02*
X2210741D01*
G01X2208726Y361134D02*
Y355717D01*
G01X2217716Y356759D02*
X2218646Y355300D01*
X2219886Y354467D01*
X2221281Y354259D01*
X2222521Y354467D01*
X2223761Y355509D01*
X2224536Y356759D01*
X2224691Y358009D01*
X2224381Y359467D01*
X2223296Y360509D01*
X2222211Y360926D01*
X2220816D01*
G01X2222211D02*
X2223141Y361551D01*
X2223916Y362592D01*
X2224226Y363842D01*
X2223916Y365092D01*
X2223141Y366134D01*
X2221746Y366759D01*
X2220351Y366551D01*
X2218956Y365717D01*
G01X2233526Y353842D02*
X2233216Y354051D01*
Y354467D01*
X2233526Y354676D01*
X2233836Y354467D01*
Y354051D01*
X2233526Y353842D01*
G01X2245926Y366759D02*
X2244686Y366342D01*
X2243756Y365301D01*
X2243136Y364051D01*
X2242671Y362384D01*
X2242516Y360509D01*
X2242671Y358634D01*
X2243136Y356967D01*
X2243756Y355717D01*
X2244686Y354676D01*
X2245926Y354259D01*
X2247166Y354676D01*
X2248096Y355717D01*
X2248716Y356967D01*
X2249181Y358634D01*
X2249336Y360509D01*
X2249181Y362384D01*
X2248716Y364051D01*
X2248096Y365301D01*
X2247166Y366342D01*
X2245926Y366759D01*
G01X2255536Y353842D02*
X2261116Y366759D01*
G01X2268711Y358426D02*
X2272741D01*
G01X2279716Y356759D02*
X2280646Y355300D01*
X2281886Y354467D01*
X2283281Y354259D01*
X2284521Y354467D01*
X2285761Y355509D01*
X2286536Y356759D01*
X2286691Y358009D01*
X2286381Y359467D01*
X2285296Y360509D01*
X2284211Y360926D01*
X2282816D01*
G01X2284211D02*
X2285141Y361551D01*
X2285916Y362592D01*
X2286226Y363842D01*
X2285916Y365092D01*
X2285141Y366134D01*
X2283746Y366759D01*
X2282351Y366551D01*
X2280956Y365717D01*
G01X2295526Y353842D02*
X2295216Y354051D01*
Y354467D01*
X2295526Y354676D01*
X2295836Y354467D01*
Y354051D01*
X2295526Y353842D01*
G01X2307926Y366759D02*
X2306686Y366342D01*
X2305756Y365301D01*
X2305136Y364051D01*
X2304671Y362384D01*
X2304516Y360509D01*
X2304671Y358634D01*
X2305136Y356967D01*
X2305756Y355717D01*
X2306686Y354676D01*
X2307926Y354259D01*
X2309166Y354676D01*
X2310096Y355717D01*
X2310716Y356967D01*
X2311181Y358634D01*
X2311336Y360509D01*
X2311181Y362384D01*
X2310716Y364051D01*
X2310096Y365301D01*
X2309166Y366342D01*
X2307926Y366759D01*
G01X2207021Y396226D02*
X2210741D01*
G01X2208726Y398934D02*
Y393517D01*
G01X2218181Y402476D02*
X2219111Y403725D01*
X2220196Y404351D01*
X2221436Y404559D01*
X2222986Y404142D01*
X2224071Y403101D01*
X2224381Y401851D01*
X2224226Y400600D01*
X2223606Y399559D01*
X2220506Y397476D01*
X2219111Y396017D01*
X2218181Y393934D01*
X2217871Y392059D01*
X2224381D01*
G01X2233526Y391642D02*
X2233216Y391851D01*
Y392267D01*
X2233526Y392476D01*
X2233836Y392267D01*
Y391851D01*
X2233526Y391642D01*
G01X2245926Y404559D02*
X2244686Y404142D01*
X2243756Y403101D01*
X2243136Y401851D01*
X2242671Y400184D01*
X2242516Y398309D01*
X2242671Y396434D01*
X2243136Y394767D01*
X2243756Y393517D01*
X2244686Y392476D01*
X2245926Y392059D01*
X2247166Y392476D01*
X2248096Y393517D01*
X2248716Y394767D01*
X2249181Y396434D01*
X2249336Y398309D01*
X2249181Y400184D01*
X2248716Y401851D01*
X2248096Y403101D01*
X2247166Y404142D01*
X2245926Y404559D01*
G01X2255536Y391642D02*
X2261116Y404559D01*
G01X2268711Y396226D02*
X2272741D01*
G01X2280181Y402476D02*
X2281111Y403725D01*
X2282196Y404351D01*
X2283436Y404559D01*
X2284986Y404142D01*
X2286071Y403101D01*
X2286381Y401851D01*
X2286226Y400600D01*
X2285606Y399559D01*
X2282506Y397476D01*
X2281111Y396017D01*
X2280181Y393934D01*
X2279871Y392059D01*
X2286381D01*
G01X2295526Y391642D02*
X2295216Y391851D01*
Y392267D01*
X2295526Y392476D01*
X2295836Y392267D01*
Y391851D01*
X2295526Y391642D01*
G01X2307926Y404559D02*
X2306686Y404142D01*
X2305756Y403101D01*
X2305136Y401851D01*
X2304671Y400184D01*
X2304516Y398309D01*
X2304671Y396434D01*
X2305136Y394767D01*
X2305756Y393517D01*
X2306686Y392476D01*
X2307926Y392059D01*
X2309166Y392476D01*
X2310096Y393517D01*
X2310716Y394767D01*
X2311181Y396434D01*
X2311336Y398309D01*
X2311181Y400184D01*
X2310716Y401851D01*
X2310096Y403101D01*
X2309166Y404142D01*
X2307926Y404559D01*
G01X2207021Y434026D02*
X2210741D01*
G01X2208726Y436734D02*
Y431317D01*
G01X2217716Y432359D02*
X2218646Y430900D01*
X2219886Y430067D01*
X2221281Y429859D01*
X2222521Y430067D01*
X2223761Y431109D01*
X2224536Y432359D01*
X2224691Y433609D01*
X2224381Y435067D01*
X2223296Y436109D01*
X2222211Y436526D01*
X2220816D01*
G01X2222211D02*
X2223141Y437151D01*
X2223916Y438192D01*
X2224226Y439442D01*
X2223916Y440692D01*
X2223141Y441734D01*
X2221746Y442359D01*
X2220351Y442151D01*
X2218956Y441317D01*
G01X2233526Y429442D02*
X2233216Y429651D01*
Y430067D01*
X2233526Y430276D01*
X2233836Y430067D01*
Y429651D01*
X2233526Y429442D01*
G01X2245926Y442359D02*
X2244686Y441942D01*
X2243756Y440901D01*
X2243136Y439651D01*
X2242671Y437984D01*
X2242516Y436109D01*
X2242671Y434234D01*
X2243136Y432567D01*
X2243756Y431317D01*
X2244686Y430276D01*
X2245926Y429859D01*
X2247166Y430276D01*
X2248096Y431317D01*
X2248716Y432567D01*
X2249181Y434234D01*
X2249336Y436109D01*
X2249181Y437984D01*
X2248716Y439651D01*
X2248096Y440901D01*
X2247166Y441942D01*
X2245926Y442359D01*
G01X2255536Y429442D02*
X2261116Y442359D01*
G01X2268711Y434026D02*
X2272741D01*
G01X2279716Y432359D02*
X2280646Y430900D01*
X2281886Y430067D01*
X2283281Y429859D01*
X2284521Y430067D01*
X2285761Y431109D01*
X2286536Y432359D01*
X2286691Y433609D01*
X2286381Y435067D01*
X2285296Y436109D01*
X2284211Y436526D01*
X2282816D01*
G01X2284211D02*
X2285141Y437151D01*
X2285916Y438192D01*
X2286226Y439442D01*
X2285916Y440692D01*
X2285141Y441734D01*
X2283746Y442359D01*
X2282351Y442151D01*
X2280956Y441317D01*
G01X2295526Y429442D02*
X2295216Y429651D01*
Y430067D01*
X2295526Y430276D01*
X2295836Y430067D01*
Y429651D01*
X2295526Y429442D01*
G01X2307926Y442359D02*
X2306686Y441942D01*
X2305756Y440901D01*
X2305136Y439651D01*
X2304671Y437984D01*
X2304516Y436109D01*
X2304671Y434234D01*
X2305136Y432567D01*
X2305756Y431317D01*
X2306686Y430276D01*
X2307926Y429859D01*
X2309166Y430276D01*
X2310096Y431317D01*
X2310716Y432567D01*
X2311181Y434234D01*
X2311336Y436109D01*
X2311181Y437984D01*
X2310716Y439651D01*
X2310096Y440901D01*
X2309166Y441942D01*
X2307926Y442359D01*
G01X2207021Y471826D02*
X2210741D01*
G01X2208726Y474534D02*
Y469117D01*
G01X2217716Y470159D02*
X2218646Y468700D01*
X2219886Y467867D01*
X2221281Y467659D01*
X2222521Y467867D01*
X2223761Y468909D01*
X2224536Y470159D01*
X2224691Y471409D01*
X2224381Y472867D01*
X2223296Y473909D01*
X2222211Y474326D01*
X2220816D01*
G01X2222211D02*
X2223141Y474951D01*
X2223916Y475992D01*
X2224226Y477242D01*
X2223916Y478492D01*
X2223141Y479534D01*
X2221746Y480159D01*
X2220351Y479951D01*
X2218956Y479117D01*
G01X2233526Y467242D02*
X2233216Y467451D01*
Y467867D01*
X2233526Y468076D01*
X2233836Y467867D01*
Y467451D01*
X2233526Y467242D01*
G01X2245926Y480159D02*
X2244686Y479742D01*
X2243756Y478701D01*
X2243136Y477451D01*
X2242671Y475784D01*
X2242516Y473909D01*
X2242671Y472034D01*
X2243136Y470367D01*
X2243756Y469117D01*
X2244686Y468076D01*
X2245926Y467659D01*
X2247166Y468076D01*
X2248096Y469117D01*
X2248716Y470367D01*
X2249181Y472034D01*
X2249336Y473909D01*
X2249181Y475784D01*
X2248716Y477451D01*
X2248096Y478701D01*
X2247166Y479742D01*
X2245926Y480159D01*
G01X2255536Y467242D02*
X2261116Y480159D01*
G01X2268711Y471826D02*
X2272741D01*
G01X2279716Y470159D02*
X2280646Y468700D01*
X2281886Y467867D01*
X2283281Y467659D01*
X2284521Y467867D01*
X2285761Y468909D01*
X2286536Y470159D01*
X2286691Y471409D01*
X2286381Y472867D01*
X2285296Y473909D01*
X2284211Y474326D01*
X2282816D01*
G01X2284211D02*
X2285141Y474951D01*
X2285916Y475992D01*
X2286226Y477242D01*
X2285916Y478492D01*
X2285141Y479534D01*
X2283746Y480159D01*
X2282351Y479951D01*
X2280956Y479117D01*
G01X2295526Y467242D02*
X2295216Y467451D01*
Y467867D01*
X2295526Y468076D01*
X2295836Y467867D01*
Y467451D01*
X2295526Y467242D01*
G01X2307926Y480159D02*
X2306686Y479742D01*
X2305756Y478701D01*
X2305136Y477451D01*
X2304671Y475784D01*
X2304516Y473909D01*
X2304671Y472034D01*
X2305136Y470367D01*
X2305756Y469117D01*
X2306686Y468076D01*
X2307926Y467659D01*
X2309166Y468076D01*
X2310096Y469117D01*
X2310716Y470367D01*
X2311181Y472034D01*
X2311336Y473909D01*
X2311181Y475784D01*
X2310716Y477451D01*
X2310096Y478701D01*
X2309166Y479742D01*
X2307926Y480159D01*
G01X2207021Y509626D02*
X2210741D01*
G01X2208726Y512334D02*
Y506917D01*
G01X2217716Y507959D02*
X2218646Y506500D01*
X2219886Y505667D01*
X2221281Y505459D01*
X2222521Y505667D01*
X2223761Y506709D01*
X2224536Y507959D01*
X2224691Y509209D01*
X2224381Y510667D01*
X2223296Y511709D01*
X2222211Y512126D01*
X2220816D01*
G01X2222211D02*
X2223141Y512751D01*
X2223916Y513792D01*
X2224226Y515042D01*
X2223916Y516292D01*
X2223141Y517334D01*
X2221746Y517959D01*
X2220351Y517751D01*
X2218956Y516917D01*
G01X2233526Y505042D02*
X2233216Y505251D01*
Y505667D01*
X2233526Y505876D01*
X2233836Y505667D01*
Y505251D01*
X2233526Y505042D01*
G01X2245926Y517959D02*
X2244686Y517542D01*
X2243756Y516501D01*
X2243136Y515251D01*
X2242671Y513584D01*
X2242516Y511709D01*
X2242671Y509834D01*
X2243136Y508167D01*
X2243756Y506917D01*
X2244686Y505876D01*
X2245926Y505459D01*
X2247166Y505876D01*
X2248096Y506917D01*
X2248716Y508167D01*
X2249181Y509834D01*
X2249336Y511709D01*
X2249181Y513584D01*
X2248716Y515251D01*
X2248096Y516501D01*
X2247166Y517542D01*
X2245926Y517959D01*
G01X2255536Y505042D02*
X2261116Y517959D01*
G01X2268711Y509626D02*
X2272741D01*
G01X2279716Y507959D02*
X2280646Y506500D01*
X2281886Y505667D01*
X2283281Y505459D01*
X2284521Y505667D01*
X2285761Y506709D01*
X2286536Y507959D01*
X2286691Y509209D01*
X2286381Y510667D01*
X2285296Y511709D01*
X2284211Y512126D01*
X2282816D01*
G01X2284211D02*
X2285141Y512751D01*
X2285916Y513792D01*
X2286226Y515042D01*
X2285916Y516292D01*
X2285141Y517334D01*
X2283746Y517959D01*
X2282351Y517751D01*
X2280956Y516917D01*
G01X2295526Y505042D02*
X2295216Y505251D01*
Y505667D01*
X2295526Y505876D01*
X2295836Y505667D01*
Y505251D01*
X2295526Y505042D01*
G01X2307926Y517959D02*
X2306686Y517542D01*
X2305756Y516501D01*
X2305136Y515251D01*
X2304671Y513584D01*
X2304516Y511709D01*
X2304671Y509834D01*
X2305136Y508167D01*
X2305756Y506917D01*
X2306686Y505876D01*
X2307926Y505459D01*
X2309166Y505876D01*
X2310096Y506917D01*
X2310716Y508167D01*
X2311181Y509834D01*
X2311336Y511709D01*
X2311181Y513584D01*
X2310716Y515251D01*
X2310096Y516501D01*
X2309166Y517542D01*
X2307926Y517959D01*
G01X2200821Y547426D02*
X2204541D01*
G01X2202526Y550134D02*
Y544717D01*
G01X2214926Y555759D02*
X2213686Y555342D01*
X2212756Y554301D01*
X2212136Y553051D01*
X2211671Y551384D01*
X2211516Y549509D01*
X2211671Y547634D01*
X2212136Y545967D01*
X2212756Y544717D01*
X2213686Y543676D01*
X2214926Y543259D01*
X2216166Y543676D01*
X2217096Y544717D01*
X2217716Y545967D01*
X2218181Y547634D01*
X2218336Y549509D01*
X2218181Y551384D01*
X2217716Y553051D01*
X2217096Y554301D01*
X2216166Y555342D01*
X2214926Y555759D01*
G01X2227326Y542842D02*
X2227016Y543051D01*
Y543467D01*
X2227326Y543676D01*
X2227636Y543467D01*
Y543051D01*
X2227326Y542842D01*
G01X2239726Y555759D02*
X2238486Y555342D01*
X2237556Y554301D01*
X2236936Y553051D01*
X2236471Y551384D01*
X2236316Y549509D01*
X2236471Y547634D01*
X2236936Y545967D01*
X2237556Y544717D01*
X2238486Y543676D01*
X2239726Y543259D01*
X2240966Y543676D01*
X2241896Y544717D01*
X2242516Y545967D01*
X2242981Y547634D01*
X2243136Y549509D01*
X2242981Y551384D01*
X2242516Y553051D01*
X2241896Y554301D01*
X2240966Y555342D01*
X2239726Y555759D01*
G01X2249336Y542842D02*
X2254916Y555759D01*
G01X2262511Y547426D02*
X2266541D01*
G01X2276926Y543259D02*
Y555759D01*
X2275066Y553259D01*
G01Y543259D02*
X2278786D01*
G01X2289326Y555759D02*
X2288086Y555342D01*
X2287156Y554301D01*
X2286536Y553051D01*
X2286071Y551384D01*
X2285916Y549509D01*
X2286071Y547634D01*
X2286536Y545967D01*
X2287156Y544717D01*
X2288086Y543676D01*
X2289326Y543259D01*
X2290566Y543676D01*
X2291496Y544717D01*
X2292116Y545967D01*
X2292581Y547634D01*
X2292736Y549509D01*
X2292581Y551384D01*
X2292116Y553051D01*
X2291496Y554301D01*
X2290566Y555342D01*
X2289326Y555759D01*
G01X2301726Y542842D02*
X2301416Y543051D01*
Y543467D01*
X2301726Y543676D01*
X2302036Y543467D01*
Y543051D01*
X2301726Y542842D01*
G01X2314126Y555759D02*
X2312886Y555342D01*
X2311956Y554301D01*
X2311336Y553051D01*
X2310871Y551384D01*
X2310716Y549509D01*
X2310871Y547634D01*
X2311336Y545967D01*
X2311956Y544717D01*
X2312886Y543676D01*
X2314126Y543259D01*
X2315366Y543676D01*
X2316296Y544717D01*
X2316916Y545967D01*
X2317381Y547634D01*
X2317536Y549509D01*
X2317381Y551384D01*
X2316916Y553051D01*
X2316296Y554301D01*
X2315366Y555342D01*
X2314126Y555759D01*
G01X2200821Y585226D02*
X2204541D01*
G01X2202526Y587934D02*
Y582517D01*
G01X2214926Y593559D02*
X2213686Y593142D01*
X2212756Y592101D01*
X2212136Y590851D01*
X2211671Y589184D01*
X2211516Y587309D01*
X2211671Y585434D01*
X2212136Y583767D01*
X2212756Y582517D01*
X2213686Y581476D01*
X2214926Y581059D01*
X2216166Y581476D01*
X2217096Y582517D01*
X2217716Y583767D01*
X2218181Y585434D01*
X2218336Y587309D01*
X2218181Y589184D01*
X2217716Y590851D01*
X2217096Y592101D01*
X2216166Y593142D01*
X2214926Y593559D01*
G01X2227326Y580642D02*
X2227016Y580851D01*
Y581267D01*
X2227326Y581476D01*
X2227636Y581267D01*
Y580851D01*
X2227326Y580642D01*
G01X2239726Y593559D02*
X2238486Y593142D01*
X2237556Y592101D01*
X2236936Y590851D01*
X2236471Y589184D01*
X2236316Y587309D01*
X2236471Y585434D01*
X2236936Y583767D01*
X2237556Y582517D01*
X2238486Y581476D01*
X2239726Y581059D01*
X2240966Y581476D01*
X2241896Y582517D01*
X2242516Y583767D01*
X2242981Y585434D01*
X2243136Y587309D01*
X2242981Y589184D01*
X2242516Y590851D01*
X2241896Y592101D01*
X2240966Y593142D01*
X2239726Y593559D01*
G01X2249336Y580642D02*
X2254916Y593559D01*
G01X2262511Y585226D02*
X2266541D01*
G01X2276926Y581059D02*
Y593559D01*
X2275066Y591059D01*
G01Y581059D02*
X2278786D01*
G01X2289326Y593559D02*
X2288086Y593142D01*
X2287156Y592101D01*
X2286536Y590851D01*
X2286071Y589184D01*
X2285916Y587309D01*
X2286071Y585434D01*
X2286536Y583767D01*
X2287156Y582517D01*
X2288086Y581476D01*
X2289326Y581059D01*
X2290566Y581476D01*
X2291496Y582517D01*
X2292116Y583767D01*
X2292581Y585434D01*
X2292736Y587309D01*
X2292581Y589184D01*
X2292116Y590851D01*
X2291496Y592101D01*
X2290566Y593142D01*
X2289326Y593559D01*
G01X2301726Y580642D02*
X2301416Y580851D01*
Y581267D01*
X2301726Y581476D01*
X2302036Y581267D01*
Y580851D01*
X2301726Y580642D01*
G01X2314126Y593559D02*
X2312886Y593142D01*
X2311956Y592101D01*
X2311336Y590851D01*
X2310871Y589184D01*
X2310716Y587309D01*
X2310871Y585434D01*
X2311336Y583767D01*
X2311956Y582517D01*
X2312886Y581476D01*
X2314126Y581059D01*
X2315366Y581476D01*
X2316296Y582517D01*
X2316916Y583767D01*
X2317381Y585434D01*
X2317536Y587309D01*
X2317381Y589184D01*
X2316916Y590851D01*
X2316296Y592101D01*
X2315366Y593142D01*
X2314126Y593559D01*
G01X2363261Y-99341D02*
Y-86841D01*
X2370391Y-99341D01*
Y-86841D01*
G01X2379226Y-99341D02*
X2377986Y-99133D01*
X2376901Y-98300D01*
X2375971Y-97049D01*
X2375351Y-95591D01*
X2375041Y-93924D01*
Y-92258D01*
X2375351Y-90591D01*
X2375971Y-89133D01*
X2376901Y-87883D01*
X2377986Y-87049D01*
X2379226Y-86841D01*
X2380466Y-87049D01*
X2381551Y-87883D01*
X2382481Y-89133D01*
X2383101Y-90591D01*
X2383411Y-92258D01*
Y-93924D01*
X2383101Y-95591D01*
X2382481Y-97049D01*
X2381551Y-98300D01*
X2380466Y-99133D01*
X2379226Y-99341D01*
G01X2388061D02*
Y-86841D01*
X2395191Y-99341D01*
Y-86841D01*
G01X2402011Y-95174D02*
X2406041D01*
G01X2413326Y-99341D02*
Y-86841D01*
X2417046D01*
X2418286Y-87466D01*
X2419216Y-88924D01*
X2419526Y-90591D01*
X2419216Y-92258D01*
X2418441Y-93508D01*
X2417046Y-94133D01*
X2413326D01*
G01X2425726Y-86841D02*
Y-99341D01*
X2431926D01*
G01X2437351D02*
X2441226Y-86841D01*
X2445101Y-99341D01*
G01X2443706Y-94966D02*
X2438746D01*
G01X2453626Y-86841D02*
Y-99341D01*
G01X2450061Y-86841D02*
X2457191D01*
G01X2469126Y-99341D02*
X2462926D01*
Y-86841D01*
X2469126D01*
G01X2466646Y-92883D02*
X2462926D01*
G01X2475016Y-99341D02*
Y-86841D01*
X2478116D01*
X2479356Y-87466D01*
X2480286Y-88299D01*
X2481061Y-89549D01*
X2481681Y-91008D01*
X2481836Y-93091D01*
X2481681Y-95174D01*
X2481061Y-96633D01*
X2480286Y-97883D01*
X2479356Y-98716D01*
X2478116Y-99341D01*
X2475016D01*
G01X2363261Y-61541D02*
Y-49041D01*
X2370391Y-61541D01*
Y-49041D01*
G01X2379226Y-61541D02*
X2377986Y-61333D01*
X2376901Y-60500D01*
X2375971Y-59249D01*
X2375351Y-57791D01*
X2375041Y-56124D01*
Y-54458D01*
X2375351Y-52791D01*
X2375971Y-51333D01*
X2376901Y-50083D01*
X2377986Y-49249D01*
X2379226Y-49041D01*
X2380466Y-49249D01*
X2381551Y-50083D01*
X2382481Y-51333D01*
X2383101Y-52791D01*
X2383411Y-54458D01*
Y-56124D01*
X2383101Y-57791D01*
X2382481Y-59249D01*
X2381551Y-60500D01*
X2380466Y-61333D01*
X2379226Y-61541D01*
G01X2388061D02*
Y-49041D01*
X2395191Y-61541D01*
Y-49041D01*
G01X2402011Y-57374D02*
X2406041D01*
G01X2413326Y-61541D02*
Y-49041D01*
X2417046D01*
X2418286Y-49666D01*
X2419216Y-51124D01*
X2419526Y-52791D01*
X2419216Y-54458D01*
X2418441Y-55708D01*
X2417046Y-56333D01*
X2413326D01*
G01X2425726Y-49041D02*
Y-61541D01*
X2431926D01*
G01X2437351D02*
X2441226Y-49041D01*
X2445101Y-61541D01*
G01X2443706Y-57166D02*
X2438746D01*
G01X2453626Y-49041D02*
Y-61541D01*
G01X2450061Y-49041D02*
X2457191D01*
G01X2469126Y-61541D02*
X2462926D01*
Y-49041D01*
X2469126D01*
G01X2466646Y-55083D02*
X2462926D01*
G01X2475016Y-61541D02*
Y-49041D01*
X2478116D01*
X2479356Y-49666D01*
X2480286Y-50499D01*
X2481061Y-51749D01*
X2481681Y-53208D01*
X2481836Y-55291D01*
X2481681Y-57374D01*
X2481061Y-58833D01*
X2480286Y-60083D01*
X2479356Y-60916D01*
X2478116Y-61541D01*
X2475016D01*
G01X2363261Y-23741D02*
Y-11241D01*
X2370391Y-23741D01*
Y-11241D01*
G01X2379226Y-23741D02*
X2377986Y-23533D01*
X2376901Y-22700D01*
X2375971Y-21449D01*
X2375351Y-19991D01*
X2375041Y-18324D01*
Y-16658D01*
X2375351Y-14991D01*
X2375971Y-13533D01*
X2376901Y-12283D01*
X2377986Y-11449D01*
X2379226Y-11241D01*
X2380466Y-11449D01*
X2381551Y-12283D01*
X2382481Y-13533D01*
X2383101Y-14991D01*
X2383411Y-16658D01*
Y-18324D01*
X2383101Y-19991D01*
X2382481Y-21449D01*
X2381551Y-22700D01*
X2380466Y-23533D01*
X2379226Y-23741D01*
G01X2388061D02*
Y-11241D01*
X2395191Y-23741D01*
Y-11241D01*
G01X2402011Y-19574D02*
X2406041D01*
G01X2413326Y-23741D02*
Y-11241D01*
X2417046D01*
X2418286Y-11866D01*
X2419216Y-13324D01*
X2419526Y-14991D01*
X2419216Y-16658D01*
X2418441Y-17908D01*
X2417046Y-18533D01*
X2413326D01*
G01X2425726Y-11241D02*
Y-23741D01*
X2431926D01*
G01X2437351D02*
X2441226Y-11241D01*
X2445101Y-23741D01*
G01X2443706Y-19366D02*
X2438746D01*
G01X2453626Y-11241D02*
Y-23741D01*
G01X2450061Y-11241D02*
X2457191D01*
G01X2469126Y-23741D02*
X2462926D01*
Y-11241D01*
X2469126D01*
G01X2466646Y-17283D02*
X2462926D01*
G01X2475016Y-23741D02*
Y-11241D01*
X2478116D01*
X2479356Y-11866D01*
X2480286Y-12699D01*
X2481061Y-13949D01*
X2481681Y-15408D01*
X2481836Y-17491D01*
X2481681Y-19574D01*
X2481061Y-21033D01*
X2480286Y-22283D01*
X2479356Y-23116D01*
X2478116Y-23741D01*
X2475016D01*
G01X2363261Y14059D02*
Y26559D01*
X2370391Y14059D01*
Y26559D01*
G01X2379226Y14059D02*
X2377986Y14267D01*
X2376901Y15100D01*
X2375971Y16351D01*
X2375351Y17809D01*
X2375041Y19476D01*
Y21142D01*
X2375351Y22809D01*
X2375971Y24267D01*
X2376901Y25517D01*
X2377986Y26351D01*
X2379226Y26559D01*
X2380466Y26351D01*
X2381551Y25517D01*
X2382481Y24267D01*
X2383101Y22809D01*
X2383411Y21142D01*
Y19476D01*
X2383101Y17809D01*
X2382481Y16351D01*
X2381551Y15100D01*
X2380466Y14267D01*
X2379226Y14059D01*
G01X2388061D02*
Y26559D01*
X2395191Y14059D01*
Y26559D01*
G01X2402011Y18226D02*
X2406041D01*
G01X2413326Y14059D02*
Y26559D01*
X2417046D01*
X2418286Y25934D01*
X2419216Y24476D01*
X2419526Y22809D01*
X2419216Y21142D01*
X2418441Y19892D01*
X2417046Y19267D01*
X2413326D01*
G01X2425726Y26559D02*
Y14059D01*
X2431926D01*
G01X2437351D02*
X2441226Y26559D01*
X2445101Y14059D01*
G01X2443706Y18434D02*
X2438746D01*
G01X2453626Y26559D02*
Y14059D01*
G01X2450061Y26559D02*
X2457191D01*
G01X2469126Y14059D02*
X2462926D01*
Y26559D01*
X2469126D01*
G01X2466646Y20517D02*
X2462926D01*
G01X2475016Y14059D02*
Y26559D01*
X2478116D01*
X2479356Y25934D01*
X2480286Y25101D01*
X2481061Y23851D01*
X2481681Y22392D01*
X2481836Y20309D01*
X2481681Y18226D01*
X2481061Y16767D01*
X2480286Y15517D01*
X2479356Y14684D01*
X2478116Y14059D01*
X2475016D01*
G01X2388526Y51859D02*
Y64359D01*
X2392246D01*
X2393486Y63734D01*
X2394416Y62276D01*
X2394726Y60609D01*
X2394416Y58942D01*
X2393641Y57692D01*
X2392246Y57067D01*
X2388526D01*
G01X2400926Y64359D02*
Y51859D01*
X2407126D01*
G01X2412551D02*
X2416426Y64359D01*
X2420301Y51859D01*
G01X2418906Y56234D02*
X2413946D01*
G01X2428826Y64359D02*
Y51859D01*
G01X2425261Y64359D02*
X2432391D01*
G01X2444326Y51859D02*
X2438126D01*
Y64359D01*
X2444326D01*
G01X2441846Y58317D02*
X2438126D01*
G01X2450216Y51859D02*
Y64359D01*
X2453316D01*
X2454556Y63734D01*
X2455486Y62901D01*
X2456261Y61651D01*
X2456881Y60192D01*
X2457036Y58109D01*
X2456881Y56026D01*
X2456261Y54567D01*
X2455486Y53317D01*
X2454556Y52484D01*
X2453316Y51859D01*
X2450216D01*
G01X2388526Y89659D02*
Y102159D01*
X2392246D01*
X2393486Y101534D01*
X2394416Y100076D01*
X2394726Y98409D01*
X2394416Y96742D01*
X2393641Y95492D01*
X2392246Y94867D01*
X2388526D01*
G01X2400926Y102159D02*
Y89659D01*
X2407126D01*
G01X2412551D02*
X2416426Y102159D01*
X2420301Y89659D01*
G01X2418906Y94034D02*
X2413946D01*
G01X2428826Y102159D02*
Y89659D01*
G01X2425261Y102159D02*
X2432391D01*
G01X2444326Y89659D02*
X2438126D01*
Y102159D01*
X2444326D01*
G01X2441846Y96117D02*
X2438126D01*
G01X2450216Y89659D02*
Y102159D01*
X2453316D01*
X2454556Y101534D01*
X2455486Y100701D01*
X2456261Y99451D01*
X2456881Y97992D01*
X2457036Y95909D01*
X2456881Y93826D01*
X2456261Y92367D01*
X2455486Y91117D01*
X2454556Y90284D01*
X2453316Y89659D01*
X2450216D01*
G01X2388526Y127459D02*
Y139959D01*
X2392246D01*
X2393486Y139334D01*
X2394416Y137876D01*
X2394726Y136209D01*
X2394416Y134542D01*
X2393641Y133292D01*
X2392246Y132667D01*
X2388526D01*
G01X2400926Y139959D02*
Y127459D01*
X2407126D01*
G01X2412551D02*
X2416426Y139959D01*
X2420301Y127459D01*
G01X2418906Y131834D02*
X2413946D01*
G01X2428826Y139959D02*
Y127459D01*
G01X2425261Y139959D02*
X2432391D01*
G01X2444326Y127459D02*
X2438126D01*
Y139959D01*
X2444326D01*
G01X2441846Y133917D02*
X2438126D01*
G01X2450216Y127459D02*
Y139959D01*
X2453316D01*
X2454556Y139334D01*
X2455486Y138501D01*
X2456261Y137251D01*
X2456881Y135792D01*
X2457036Y133709D01*
X2456881Y131626D01*
X2456261Y130167D01*
X2455486Y128917D01*
X2454556Y128084D01*
X2453316Y127459D01*
X2450216D01*
G01X2388526Y165259D02*
Y177759D01*
X2392246D01*
X2393486Y177134D01*
X2394416Y175676D01*
X2394726Y174009D01*
X2394416Y172342D01*
X2393641Y171092D01*
X2392246Y170467D01*
X2388526D01*
G01X2400926Y177759D02*
Y165259D01*
X2407126D01*
G01X2412551D02*
X2416426Y177759D01*
X2420301Y165259D01*
G01X2418906Y169634D02*
X2413946D01*
G01X2428826Y177759D02*
Y165259D01*
G01X2425261Y177759D02*
X2432391D01*
G01X2444326Y165259D02*
X2438126D01*
Y177759D01*
X2444326D01*
G01X2441846Y171717D02*
X2438126D01*
G01X2450216Y165259D02*
Y177759D01*
X2453316D01*
X2454556Y177134D01*
X2455486Y176301D01*
X2456261Y175051D01*
X2456881Y173592D01*
X2457036Y171509D01*
X2456881Y169426D01*
X2456261Y167967D01*
X2455486Y166717D01*
X2454556Y165884D01*
X2453316Y165259D01*
X2450216D01*
G01X2388526Y203059D02*
Y215559D01*
X2392246D01*
X2393486Y214934D01*
X2394416Y213476D01*
X2394726Y211809D01*
X2394416Y210142D01*
X2393641Y208892D01*
X2392246Y208267D01*
X2388526D01*
G01X2400926Y215559D02*
Y203059D01*
X2407126D01*
G01X2412551D02*
X2416426Y215559D01*
X2420301Y203059D01*
G01X2418906Y207434D02*
X2413946D01*
G01X2428826Y215559D02*
Y203059D01*
G01X2425261Y215559D02*
X2432391D01*
G01X2444326Y203059D02*
X2438126D01*
Y215559D01*
X2444326D01*
G01X2441846Y209517D02*
X2438126D01*
G01X2450216Y203059D02*
Y215559D01*
X2453316D01*
X2454556Y214934D01*
X2455486Y214101D01*
X2456261Y212851D01*
X2456881Y211392D01*
X2457036Y209309D01*
X2456881Y207226D01*
X2456261Y205767D01*
X2455486Y204517D01*
X2454556Y203684D01*
X2453316Y203059D01*
X2450216D01*
G01X2388526Y240859D02*
Y253359D01*
X2392246D01*
X2393486Y252734D01*
X2394416Y251276D01*
X2394726Y249609D01*
X2394416Y247942D01*
X2393641Y246692D01*
X2392246Y246067D01*
X2388526D01*
G01X2400926Y253359D02*
Y240859D01*
X2407126D01*
G01X2412551D02*
X2416426Y253359D01*
X2420301Y240859D01*
G01X2418906Y245234D02*
X2413946D01*
G01X2428826Y253359D02*
Y240859D01*
G01X2425261Y253359D02*
X2432391D01*
G01X2444326Y240859D02*
X2438126D01*
Y253359D01*
X2444326D01*
G01X2441846Y247317D02*
X2438126D01*
G01X2450216Y240859D02*
Y253359D01*
X2453316D01*
X2454556Y252734D01*
X2455486Y251901D01*
X2456261Y250651D01*
X2456881Y249192D01*
X2457036Y247109D01*
X2456881Y245026D01*
X2456261Y243567D01*
X2455486Y242317D01*
X2454556Y241484D01*
X2453316Y240859D01*
X2450216D01*
G01X2388526Y278659D02*
Y291159D01*
X2392246D01*
X2393486Y290534D01*
X2394416Y289076D01*
X2394726Y287409D01*
X2394416Y285742D01*
X2393641Y284492D01*
X2392246Y283867D01*
X2388526D01*
G01X2400926Y291159D02*
Y278659D01*
X2407126D01*
G01X2412551D02*
X2416426Y291159D01*
X2420301Y278659D01*
G01X2418906Y283034D02*
X2413946D01*
G01X2428826Y291159D02*
Y278659D01*
G01X2425261Y291159D02*
X2432391D01*
G01X2444326Y278659D02*
X2438126D01*
Y291159D01*
X2444326D01*
G01X2441846Y285117D02*
X2438126D01*
G01X2450216Y278659D02*
Y291159D01*
X2453316D01*
X2454556Y290534D01*
X2455486Y289701D01*
X2456261Y288451D01*
X2456881Y286992D01*
X2457036Y284909D01*
X2456881Y282826D01*
X2456261Y281367D01*
X2455486Y280117D01*
X2454556Y279284D01*
X2453316Y278659D01*
X2450216D01*
G01X2388526Y316459D02*
Y328959D01*
X2392246D01*
X2393486Y328334D01*
X2394416Y326876D01*
X2394726Y325209D01*
X2394416Y323542D01*
X2393641Y322292D01*
X2392246Y321667D01*
X2388526D01*
G01X2400926Y328959D02*
Y316459D01*
X2407126D01*
G01X2412551D02*
X2416426Y328959D01*
X2420301Y316459D01*
G01X2418906Y320834D02*
X2413946D01*
G01X2428826Y328959D02*
Y316459D01*
G01X2425261Y328959D02*
X2432391D01*
G01X2444326Y316459D02*
X2438126D01*
Y328959D01*
X2444326D01*
G01X2441846Y322917D02*
X2438126D01*
G01X2450216Y316459D02*
Y328959D01*
X2453316D01*
X2454556Y328334D01*
X2455486Y327501D01*
X2456261Y326251D01*
X2456881Y324792D01*
X2457036Y322709D01*
X2456881Y320626D01*
X2456261Y319167D01*
X2455486Y317917D01*
X2454556Y317084D01*
X2453316Y316459D01*
X2450216D01*
G01X2388526Y354259D02*
Y366759D01*
X2392246D01*
X2393486Y366134D01*
X2394416Y364676D01*
X2394726Y363009D01*
X2394416Y361342D01*
X2393641Y360092D01*
X2392246Y359467D01*
X2388526D01*
G01X2400926Y366759D02*
Y354259D01*
X2407126D01*
G01X2412551D02*
X2416426Y366759D01*
X2420301Y354259D01*
G01X2418906Y358634D02*
X2413946D01*
G01X2428826Y366759D02*
Y354259D01*
G01X2425261Y366759D02*
X2432391D01*
G01X2444326Y354259D02*
X2438126D01*
Y366759D01*
X2444326D01*
G01X2441846Y360717D02*
X2438126D01*
G01X2450216Y354259D02*
Y366759D01*
X2453316D01*
X2454556Y366134D01*
X2455486Y365301D01*
X2456261Y364051D01*
X2456881Y362592D01*
X2457036Y360509D01*
X2456881Y358426D01*
X2456261Y356967D01*
X2455486Y355717D01*
X2454556Y354884D01*
X2453316Y354259D01*
X2450216D01*
G01X2388526Y392059D02*
Y404559D01*
X2392246D01*
X2393486Y403934D01*
X2394416Y402476D01*
X2394726Y400809D01*
X2394416Y399142D01*
X2393641Y397892D01*
X2392246Y397267D01*
X2388526D01*
G01X2400926Y404559D02*
Y392059D01*
X2407126D01*
G01X2412551D02*
X2416426Y404559D01*
X2420301Y392059D01*
G01X2418906Y396434D02*
X2413946D01*
G01X2428826Y404559D02*
Y392059D01*
G01X2425261Y404559D02*
X2432391D01*
G01X2444326Y392059D02*
X2438126D01*
Y404559D01*
X2444326D01*
G01X2441846Y398517D02*
X2438126D01*
G01X2450216Y392059D02*
Y404559D01*
X2453316D01*
X2454556Y403934D01*
X2455486Y403101D01*
X2456261Y401851D01*
X2456881Y400392D01*
X2457036Y398309D01*
X2456881Y396226D01*
X2456261Y394767D01*
X2455486Y393517D01*
X2454556Y392684D01*
X2453316Y392059D01*
X2450216D01*
G01X2388526Y429859D02*
Y442359D01*
X2392246D01*
X2393486Y441734D01*
X2394416Y440276D01*
X2394726Y438609D01*
X2394416Y436942D01*
X2393641Y435692D01*
X2392246Y435067D01*
X2388526D01*
G01X2400926Y442359D02*
Y429859D01*
X2407126D01*
G01X2412551D02*
X2416426Y442359D01*
X2420301Y429859D01*
G01X2418906Y434234D02*
X2413946D01*
G01X2428826Y442359D02*
Y429859D01*
G01X2425261Y442359D02*
X2432391D01*
G01X2444326Y429859D02*
X2438126D01*
Y442359D01*
X2444326D01*
G01X2441846Y436317D02*
X2438126D01*
G01X2450216Y429859D02*
Y442359D01*
X2453316D01*
X2454556Y441734D01*
X2455486Y440901D01*
X2456261Y439651D01*
X2456881Y438192D01*
X2457036Y436109D01*
X2456881Y434026D01*
X2456261Y432567D01*
X2455486Y431317D01*
X2454556Y430484D01*
X2453316Y429859D01*
X2450216D01*
G01X2388526Y467659D02*
Y480159D01*
X2392246D01*
X2393486Y479534D01*
X2394416Y478076D01*
X2394726Y476409D01*
X2394416Y474742D01*
X2393641Y473492D01*
X2392246Y472867D01*
X2388526D01*
G01X2400926Y480159D02*
Y467659D01*
X2407126D01*
G01X2412551D02*
X2416426Y480159D01*
X2420301Y467659D01*
G01X2418906Y472034D02*
X2413946D01*
G01X2428826Y480159D02*
Y467659D01*
G01X2425261Y480159D02*
X2432391D01*
G01X2444326Y467659D02*
X2438126D01*
Y480159D01*
X2444326D01*
G01X2441846Y474117D02*
X2438126D01*
G01X2450216Y467659D02*
Y480159D01*
X2453316D01*
X2454556Y479534D01*
X2455486Y478701D01*
X2456261Y477451D01*
X2456881Y475992D01*
X2457036Y473909D01*
X2456881Y471826D01*
X2456261Y470367D01*
X2455486Y469117D01*
X2454556Y468284D01*
X2453316Y467659D01*
X2450216D01*
G01X2388526Y505459D02*
Y517959D01*
X2392246D01*
X2393486Y517334D01*
X2394416Y515876D01*
X2394726Y514209D01*
X2394416Y512542D01*
X2393641Y511292D01*
X2392246Y510667D01*
X2388526D01*
G01X2400926Y517959D02*
Y505459D01*
X2407126D01*
G01X2412551D02*
X2416426Y517959D01*
X2420301Y505459D01*
G01X2418906Y509834D02*
X2413946D01*
G01X2428826Y517959D02*
Y505459D01*
G01X2425261Y517959D02*
X2432391D01*
G01X2444326Y505459D02*
X2438126D01*
Y517959D01*
X2444326D01*
G01X2441846Y511917D02*
X2438126D01*
G01X2450216Y505459D02*
Y517959D01*
X2453316D01*
X2454556Y517334D01*
X2455486Y516501D01*
X2456261Y515251D01*
X2456881Y513792D01*
X2457036Y511709D01*
X2456881Y509626D01*
X2456261Y508167D01*
X2455486Y506917D01*
X2454556Y506084D01*
X2453316Y505459D01*
X2450216D01*
G01X2388526Y543259D02*
Y555759D01*
X2392246D01*
X2393486Y555134D01*
X2394416Y553676D01*
X2394726Y552009D01*
X2394416Y550342D01*
X2393641Y549092D01*
X2392246Y548467D01*
X2388526D01*
G01X2400926Y555759D02*
Y543259D01*
X2407126D01*
G01X2412551D02*
X2416426Y555759D01*
X2420301Y543259D01*
G01X2418906Y547634D02*
X2413946D01*
G01X2428826Y555759D02*
Y543259D01*
G01X2425261Y555759D02*
X2432391D01*
G01X2444326Y543259D02*
X2438126D01*
Y555759D01*
X2444326D01*
G01X2441846Y549717D02*
X2438126D01*
G01X2450216Y543259D02*
Y555759D01*
X2453316D01*
X2454556Y555134D01*
X2455486Y554301D01*
X2456261Y553051D01*
X2456881Y551592D01*
X2457036Y549509D01*
X2456881Y547426D01*
X2456261Y545967D01*
X2455486Y544717D01*
X2454556Y543884D01*
X2453316Y543259D01*
X2450216D01*
G01X2388526Y581059D02*
Y593559D01*
X2392246D01*
X2393486Y592934D01*
X2394416Y591476D01*
X2394726Y589809D01*
X2394416Y588142D01*
X2393641Y586892D01*
X2392246Y586267D01*
X2388526D01*
G01X2400926Y593559D02*
Y581059D01*
X2407126D01*
G01X2412551D02*
X2416426Y593559D01*
X2420301Y581059D01*
G01X2418906Y585434D02*
X2413946D01*
G01X2428826Y593559D02*
Y581059D01*
G01X2425261Y593559D02*
X2432391D01*
G01X2444326Y581059D02*
X2438126D01*
Y593559D01*
X2444326D01*
G01X2441846Y587517D02*
X2438126D01*
G01X2450216Y581059D02*
Y593559D01*
X2453316D01*
X2454556Y592934D01*
X2455486Y592101D01*
X2456261Y590851D01*
X2456881Y589392D01*
X2457036Y587309D01*
X2456881Y585226D01*
X2456261Y583767D01*
X2455486Y582517D01*
X2454556Y581684D01*
X2453316Y581059D01*
X2450216D01*
G01X2388526Y612459D02*
Y624959D01*
X2392246D01*
X2393486Y624334D01*
X2394416Y622876D01*
X2394726Y621209D01*
X2394416Y619542D01*
X2393641Y618292D01*
X2392246Y617667D01*
X2388526D01*
G01X2400926Y624959D02*
Y612459D01*
X2407126D01*
G01X2412551D02*
X2416426Y624959D01*
X2420301Y612459D01*
G01X2418906Y616834D02*
X2413946D01*
G01X2428826Y624959D02*
Y612459D01*
G01X2425261Y624959D02*
X2432391D01*
G01X2444326Y612459D02*
X2438126D01*
Y624959D01*
X2444326D01*
G01X2441846Y618917D02*
X2438126D01*
G01X2450216Y612459D02*
Y624959D01*
X2453316D01*
X2454556Y624334D01*
X2455486Y623501D01*
X2456261Y622251D01*
X2456881Y620792D01*
X2457036Y618709D01*
X2456881Y616626D01*
X2456261Y615167D01*
X2455486Y613917D01*
X2454556Y613084D01*
X2453316Y612459D01*
X2450216D01*
G01X2521981Y-94133D02*
X2523066Y-92674D01*
X2523996Y-91841D01*
X2525236Y-91424D01*
X2526321Y-91841D01*
X2527096Y-92674D01*
X2527716Y-93924D01*
X2527871Y-95383D01*
X2527716Y-96633D01*
X2527096Y-97883D01*
X2526166Y-98924D01*
X2525081Y-99341D01*
X2523841Y-98924D01*
X2522756Y-97675D01*
X2522136Y-95799D01*
X2521981Y-93716D01*
X2522291Y-91008D01*
X2522756Y-89549D01*
X2523531Y-88091D01*
X2524616Y-87049D01*
X2525701Y-86841D01*
X2526786Y-87258D01*
X2527561Y-88299D01*
G01X2521981Y-56333D02*
X2523066Y-54874D01*
X2523996Y-54041D01*
X2525236Y-53624D01*
X2526321Y-54041D01*
X2527096Y-54874D01*
X2527716Y-56124D01*
X2527871Y-57583D01*
X2527716Y-58833D01*
X2527096Y-60083D01*
X2526166Y-61124D01*
X2525081Y-61541D01*
X2523841Y-61124D01*
X2522756Y-59875D01*
X2522136Y-57999D01*
X2521981Y-55916D01*
X2522291Y-53208D01*
X2522756Y-51749D01*
X2523531Y-50291D01*
X2524616Y-49249D01*
X2525701Y-49041D01*
X2526786Y-49458D01*
X2527561Y-50499D01*
G01X2521516Y-21241D02*
X2522446Y-22700D01*
X2523686Y-23533D01*
X2525081Y-23741D01*
X2526321Y-23533D01*
X2527561Y-22491D01*
X2528336Y-21241D01*
X2528491Y-19991D01*
X2528181Y-18533D01*
X2527096Y-17491D01*
X2526011Y-17074D01*
X2524616D01*
G01X2526011D02*
X2526941Y-16449D01*
X2527716Y-15408D01*
X2528026Y-14158D01*
X2527716Y-12908D01*
X2526941Y-11866D01*
X2525546Y-11241D01*
X2524151Y-11449D01*
X2522756Y-12283D01*
G01X2521981Y24476D02*
X2522911Y25725D01*
X2523996Y26351D01*
X2525236Y26559D01*
X2526786Y26142D01*
X2527871Y25101D01*
X2528181Y23851D01*
X2528026Y22600D01*
X2527406Y21559D01*
X2524306Y19476D01*
X2522911Y18017D01*
X2521981Y15934D01*
X2521671Y14059D01*
X2528181D01*
G01X2521981Y62276D02*
X2522911Y63525D01*
X2523996Y64151D01*
X2525236Y64359D01*
X2526786Y63942D01*
X2527871Y62901D01*
X2528181Y61651D01*
X2528026Y60400D01*
X2527406Y59359D01*
X2524306Y57276D01*
X2522911Y55817D01*
X2521981Y53734D01*
X2521671Y51859D01*
X2528181D01*
G01X2521981Y100076D02*
X2522911Y101325D01*
X2523996Y101951D01*
X2525236Y102159D01*
X2526786Y101742D01*
X2527871Y100701D01*
X2528181Y99451D01*
X2528026Y98200D01*
X2527406Y97159D01*
X2524306Y95076D01*
X2522911Y93617D01*
X2521981Y91534D01*
X2521671Y89659D01*
X2528181D01*
G01X2521981Y132667D02*
X2523066Y134126D01*
X2523996Y134959D01*
X2525236Y135376D01*
X2526321Y134959D01*
X2527096Y134126D01*
X2527716Y132876D01*
X2527871Y131417D01*
X2527716Y130167D01*
X2527096Y128917D01*
X2526166Y127876D01*
X2525081Y127459D01*
X2523841Y127876D01*
X2522756Y129125D01*
X2522136Y131001D01*
X2521981Y133084D01*
X2522291Y135792D01*
X2522756Y137251D01*
X2523531Y138709D01*
X2524616Y139751D01*
X2525701Y139959D01*
X2526786Y139542D01*
X2527561Y138501D01*
G01X2518726Y165259D02*
Y177759D01*
X2516866Y175259D01*
G01Y165259D02*
X2520586D01*
G01X2528181Y170467D02*
X2529266Y171926D01*
X2530196Y172759D01*
X2531436Y173176D01*
X2532521Y172759D01*
X2533296Y171926D01*
X2533916Y170676D01*
X2534071Y169217D01*
X2533916Y167967D01*
X2533296Y166717D01*
X2532366Y165676D01*
X2531281Y165259D01*
X2530041Y165676D01*
X2528956Y166925D01*
X2528336Y168801D01*
X2528181Y170884D01*
X2528491Y173592D01*
X2528956Y175051D01*
X2529731Y176509D01*
X2530816Y177551D01*
X2531901Y177759D01*
X2532986Y177342D01*
X2533761Y176301D01*
G01X2518726Y203059D02*
Y215559D01*
X2516866Y213059D01*
G01Y203059D02*
X2520586D01*
G01X2528181Y213476D02*
X2529111Y214725D01*
X2530196Y215351D01*
X2531436Y215559D01*
X2532986Y215142D01*
X2534071Y214101D01*
X2534381Y212851D01*
X2534226Y211600D01*
X2533606Y210559D01*
X2530506Y208476D01*
X2529111Y207017D01*
X2528181Y204934D01*
X2527871Y203059D01*
X2534381D01*
G01X2518726Y240859D02*
Y253359D01*
X2516866Y250859D01*
G01Y240859D02*
X2520586D01*
G01X2528181Y251276D02*
X2529111Y252525D01*
X2530196Y253151D01*
X2531436Y253359D01*
X2532986Y252942D01*
X2534071Y251901D01*
X2534381Y250651D01*
X2534226Y249400D01*
X2533606Y248359D01*
X2530506Y246276D01*
X2529111Y244817D01*
X2528181Y242734D01*
X2527871Y240859D01*
X2534381D01*
G01X2521981Y283867D02*
X2523066Y285326D01*
X2523996Y286159D01*
X2525236Y286576D01*
X2526321Y286159D01*
X2527096Y285326D01*
X2527716Y284076D01*
X2527871Y282617D01*
X2527716Y281367D01*
X2527096Y280117D01*
X2526166Y279076D01*
X2525081Y278659D01*
X2523841Y279076D01*
X2522756Y280325D01*
X2522136Y282201D01*
X2521981Y284284D01*
X2522291Y286992D01*
X2522756Y288451D01*
X2523531Y289909D01*
X2524616Y290951D01*
X2525701Y291159D01*
X2526786Y290742D01*
X2527561Y289701D01*
G01X2515781Y326876D02*
X2516711Y328125D01*
X2517796Y328751D01*
X2519036Y328959D01*
X2520586Y328542D01*
X2521671Y327501D01*
X2521981Y326251D01*
X2521826Y325000D01*
X2521206Y323959D01*
X2518106Y321876D01*
X2516711Y320417D01*
X2515781Y318334D01*
X2515471Y316459D01*
X2521981D01*
G01X2532986D02*
Y328959D01*
X2527251Y320001D01*
X2535001D01*
G01X2518726Y354259D02*
Y366759D01*
X2516866Y364259D01*
G01Y354259D02*
X2520586D01*
G01X2528181Y359467D02*
X2529266Y360926D01*
X2530196Y361759D01*
X2531436Y362176D01*
X2532521Y361759D01*
X2533296Y360926D01*
X2533916Y359676D01*
X2534071Y358217D01*
X2533916Y356967D01*
X2533296Y355717D01*
X2532366Y354676D01*
X2531281Y354259D01*
X2530041Y354676D01*
X2528956Y355925D01*
X2528336Y357801D01*
X2528181Y359884D01*
X2528491Y362592D01*
X2528956Y364051D01*
X2529731Y365509D01*
X2530816Y366551D01*
X2531901Y366759D01*
X2532986Y366342D01*
X2533761Y365301D01*
G01X2512526Y392059D02*
Y404559D01*
X2510666Y402059D01*
G01Y392059D02*
X2514386D01*
G01X2526786D02*
Y404559D01*
X2521051Y395601D01*
X2528801D01*
G01X2539186Y392059D02*
Y404559D01*
X2533451Y395601D01*
X2541201D01*
G01X2515781Y440276D02*
X2516711Y441525D01*
X2517796Y442151D01*
X2519036Y442359D01*
X2520586Y441942D01*
X2521671Y440901D01*
X2521981Y439651D01*
X2521826Y438400D01*
X2521206Y437359D01*
X2518106Y435276D01*
X2516711Y433817D01*
X2515781Y431734D01*
X2515471Y429859D01*
X2521981D01*
G01X2532986D02*
Y442359D01*
X2527251Y433401D01*
X2535001D01*
G01X2515781Y478076D02*
X2516711Y479325D01*
X2517796Y479951D01*
X2519036Y480159D01*
X2520586Y479742D01*
X2521671Y478701D01*
X2521981Y477451D01*
X2521826Y476200D01*
X2521206Y475159D01*
X2518106Y473076D01*
X2516711Y471617D01*
X2515781Y469534D01*
X2515471Y467659D01*
X2521981D01*
G01X2531126D02*
X2532211Y467867D01*
X2533451Y468492D01*
X2534226Y469534D01*
X2534536Y470992D01*
X2534226Y472450D01*
X2533296Y473701D01*
X2531901Y474326D01*
X2530351D01*
X2529421Y474742D01*
X2528646Y475784D01*
X2528336Y477242D01*
X2528801Y478701D01*
X2529886Y479742D01*
X2531126Y480159D01*
X2532366Y479742D01*
X2533451Y478701D01*
X2533916Y477242D01*
X2533606Y475784D01*
X2532831Y474742D01*
X2531901Y474326D01*
X2530351D01*
X2528956Y473701D01*
X2528026Y472450D01*
X2527716Y470992D01*
X2528026Y469534D01*
X2528801Y468492D01*
X2530041Y467867D01*
X2531126Y467659D01*
G01X2518726Y505459D02*
Y517959D01*
X2516866Y515459D01*
G01Y505459D02*
X2520586D01*
G01X2528181Y510667D02*
X2529266Y512126D01*
X2530196Y512959D01*
X2531436Y513376D01*
X2532521Y512959D01*
X2533296Y512126D01*
X2533916Y510876D01*
X2534071Y509417D01*
X2533916Y508167D01*
X2533296Y506917D01*
X2532366Y505876D01*
X2531281Y505459D01*
X2530041Y505876D01*
X2528956Y507125D01*
X2528336Y509001D01*
X2528181Y511084D01*
X2528491Y513792D01*
X2528956Y515251D01*
X2529731Y516709D01*
X2530816Y517751D01*
X2531901Y517959D01*
X2532986Y517542D01*
X2533761Y516501D01*
G01X2506326Y543259D02*
Y555759D01*
X2504466Y553259D01*
G01Y543259D02*
X2508186D01*
G01X2515316Y545134D02*
X2516246Y544092D01*
X2517331Y543467D01*
X2518726Y543259D01*
X2520121Y543676D01*
X2521206Y544509D01*
X2521981Y545967D01*
X2522136Y547634D01*
X2521826Y549301D01*
X2521051Y550342D01*
X2519966Y551176D01*
X2518881Y551384D01*
X2517796Y551176D01*
X2516401Y550342D01*
X2516866Y555759D01*
X2521051D01*
G01X2530816Y543259D02*
X2531126Y545967D01*
X2531591Y548259D01*
X2532211Y550342D01*
X2532986Y552634D01*
X2534226Y555759D01*
X2528026D01*
G01X2540581Y548467D02*
X2541666Y549926D01*
X2542596Y550759D01*
X2543836Y551176D01*
X2544921Y550759D01*
X2545696Y549926D01*
X2546316Y548676D01*
X2546471Y547217D01*
X2546316Y545967D01*
X2545696Y544717D01*
X2544766Y543676D01*
X2543681Y543259D01*
X2542441Y543676D01*
X2541356Y544925D01*
X2540736Y546801D01*
X2540581Y548884D01*
X2540891Y551592D01*
X2541356Y553051D01*
X2542131Y554509D01*
X2543216Y555551D01*
X2544301Y555759D01*
X2545386Y555342D01*
X2546161Y554301D01*
G01X2512526Y581059D02*
Y593559D01*
X2510666Y591059D01*
G01Y581059D02*
X2514386D01*
G01X2524616D02*
X2524926Y583767D01*
X2525391Y586059D01*
X2526011Y588142D01*
X2526786Y590434D01*
X2528026Y593559D01*
X2521826D01*
G01X2537016Y581059D02*
X2537326Y583767D01*
X2537791Y586059D01*
X2538411Y588142D01*
X2539186Y590434D01*
X2540426Y593559D01*
X2534226D01*
G01X2512526Y612459D02*
X2511286Y612667D01*
X2510201Y613500D01*
X2509271Y614751D01*
X2508651Y616209D01*
X2508341Y617876D01*
Y619542D01*
X2508651Y621209D01*
X2509271Y622667D01*
X2510201Y623917D01*
X2511286Y624751D01*
X2512526Y624959D01*
X2513766Y624751D01*
X2514851Y623917D01*
X2515781Y622667D01*
X2516401Y621209D01*
X2516711Y619542D01*
Y617876D01*
X2516401Y616209D01*
X2515781Y614751D01*
X2514851Y613500D01*
X2513766Y612667D01*
X2512526Y612459D01*
G01X2513766Y615792D02*
X2515626Y612459D01*
G01X2524926Y624959D02*
Y612459D01*
G01X2521361Y624959D02*
X2528491D01*
G01X2537326Y612459D02*
Y618084D01*
X2534226Y624959D01*
G01X2540426D02*
X2537326Y618084D01*
G01X2577396Y394316D02*
Y401816D01*
X2579730D01*
X2580476Y401441D01*
X2580943Y400941D01*
X2581130Y399941D01*
X2580943Y398941D01*
X2580383Y398316D01*
X2579730Y397941D01*
X2577396D01*
G01X2579730D02*
X2581130Y394316D01*
G01X2588630D02*
X2584896D01*
Y401816D01*
X2588630D01*
G01X2587136Y398191D02*
X2584896D01*
G01X2596316Y401191D02*
X2595756Y401566D01*
X2595103Y401816D01*
X2594356D01*
X2593516Y401441D01*
X2592863Y400816D01*
X2592396Y400066D01*
X2592023Y398816D01*
X2591930Y397691D01*
X2592116Y396566D01*
X2592396Y395816D01*
X2592956Y395066D01*
X2593610Y394566D01*
X2594263Y394316D01*
X2594916D01*
X2595570Y394566D01*
X2596130Y394941D01*
X2596596Y395441D01*
G01X2601763Y394316D02*
X2601016Y394441D01*
X2600363Y394941D01*
X2599803Y395691D01*
X2599430Y396566D01*
X2599243Y397566D01*
Y398566D01*
X2599430Y399566D01*
X2599803Y400441D01*
X2600363Y401191D01*
X2601016Y401691D01*
X2601763Y401816D01*
X2602510Y401691D01*
X2603163Y401191D01*
X2603723Y400441D01*
X2604096Y399566D01*
X2604283Y398566D01*
Y397566D01*
X2604096Y396566D01*
X2603723Y395691D01*
X2603163Y394941D01*
X2602510Y394441D01*
X2601763Y394316D01*
G01X2606836D02*
Y401816D01*
X2609263Y395566D01*
X2611690Y401816D01*
Y394316D01*
G01X2614336D02*
Y401816D01*
X2616763Y395566D01*
X2619190Y401816D01*
Y394316D01*
G01X2626130D02*
X2622396D01*
Y401816D01*
X2626130D01*
G01X2624636Y398191D02*
X2622396D01*
G01X2629616Y394316D02*
Y401816D01*
X2633910Y394316D01*
Y401816D01*
G01X2637210Y394316D02*
Y401816D01*
X2639076D01*
X2639823Y401441D01*
X2640383Y400941D01*
X2640850Y400191D01*
X2641223Y399316D01*
X2641316Y398066D01*
X2641223Y396816D01*
X2640850Y395941D01*
X2640383Y395191D01*
X2639823Y394691D01*
X2639076Y394316D01*
X2637210D01*
G01X2648630D02*
X2644896D01*
Y401816D01*
X2648630D01*
G01X2647136Y398191D02*
X2644896D01*
G01X2652210Y394316D02*
Y401816D01*
X2654076D01*
X2654823Y401441D01*
X2655383Y400941D01*
X2655850Y400191D01*
X2656223Y399316D01*
X2656316Y398066D01*
X2656223Y396816D01*
X2655850Y395941D01*
X2655383Y395191D01*
X2654823Y394691D01*
X2654076Y394316D01*
X2652210D01*
G01X2667210D02*
Y401816D01*
X2669076D01*
X2669823Y401441D01*
X2670383Y400941D01*
X2670850Y400191D01*
X2671223Y399316D01*
X2671316Y398066D01*
X2671223Y396816D01*
X2670850Y395941D01*
X2670383Y395191D01*
X2669823Y394691D01*
X2669076Y394316D01*
X2667210D01*
G01X2674896D02*
Y401816D01*
X2677230D01*
X2677976Y401441D01*
X2678443Y400941D01*
X2678630Y399941D01*
X2678443Y398941D01*
X2677883Y398316D01*
X2677230Y397941D01*
X2674896D01*
G01X2677230D02*
X2678630Y394316D01*
G01X2683143Y401816D02*
X2685383D01*
G01X2684263D02*
Y394316D01*
G01X2683143D02*
X2685383D01*
G01X2689896Y401816D02*
Y394316D01*
X2693630D01*
G01X2697396Y401816D02*
Y394316D01*
X2701130D01*
G01X2712303Y395316D02*
X2713050Y394691D01*
X2713890Y394316D01*
X2714636D01*
X2715383Y394691D01*
X2715943Y395316D01*
X2716223Y396191D01*
X2716036Y397066D01*
X2715570Y397816D01*
X2714730Y398316D01*
X2713610Y398566D01*
X2712956Y399066D01*
X2712676Y399941D01*
X2712863Y400816D01*
X2713330Y401441D01*
X2713983Y401816D01*
X2714636D01*
X2715290Y401566D01*
X2715850Y400941D01*
G01X2720643Y401816D02*
X2722883D01*
G01X2721763D02*
Y394316D01*
G01X2720643D02*
X2722883D01*
G01X2727490Y401816D02*
X2731036D01*
X2727490Y394316D01*
X2731036D01*
G01X2738630D02*
X2734896D01*
Y401816D01*
X2738630D01*
G01X2737136Y398191D02*
X2734896D01*
G01X2749990Y394316D02*
Y401816D01*
X2753536D01*
G01X2752230Y398191D02*
X2749990D01*
G01X2759263Y394316D02*
X2758516Y394441D01*
X2757863Y394941D01*
X2757303Y395691D01*
X2756930Y396566D01*
X2756743Y397566D01*
Y398566D01*
X2756930Y399566D01*
X2757303Y400441D01*
X2757863Y401191D01*
X2758516Y401691D01*
X2759263Y401816D01*
X2760010Y401691D01*
X2760663Y401191D01*
X2761223Y400441D01*
X2761596Y399566D01*
X2761783Y398566D01*
Y397566D01*
X2761596Y396566D01*
X2761223Y395691D01*
X2760663Y394941D01*
X2760010Y394441D01*
X2759263Y394316D01*
G01X2764896D02*
Y401816D01*
X2767230D01*
X2767976Y401441D01*
X2768443Y400941D01*
X2768630Y399941D01*
X2768443Y398941D01*
X2767883Y398316D01*
X2767230Y397941D01*
X2764896D01*
G01X2767230D02*
X2768630Y394316D01*
G01X2781763D02*
Y401816D01*
X2780643Y400316D01*
G01Y394316D02*
X2782883D01*
G01X2789263Y394066D02*
X2789076Y394191D01*
Y394441D01*
X2789263Y394566D01*
X2789450Y394441D01*
Y394191D01*
X2789263Y394066D01*
G01X2796763Y401816D02*
X2796016Y401566D01*
X2795456Y400941D01*
X2795083Y400191D01*
X2794803Y399191D01*
X2794710Y398066D01*
X2794803Y396941D01*
X2795083Y395941D01*
X2795456Y395191D01*
X2796016Y394566D01*
X2796763Y394316D01*
X2797510Y394566D01*
X2798070Y395191D01*
X2798443Y395941D01*
X2798723Y396941D01*
X2798816Y398066D01*
X2798723Y399191D01*
X2798443Y400191D01*
X2798070Y400941D01*
X2797510Y401566D01*
X2796763Y401816D01*
G01X2802490Y400566D02*
X2803050Y401316D01*
X2803703Y401691D01*
X2804450Y401816D01*
X2805383Y401566D01*
X2806036Y400941D01*
X2806223Y400191D01*
X2806130Y399441D01*
X2805756Y398816D01*
X2803890Y397566D01*
X2803050Y396691D01*
X2802490Y395441D01*
X2802303Y394316D01*
X2806223D01*
G01X2809336D02*
Y401816D01*
X2811763Y395566D01*
X2814190Y401816D01*
Y394316D01*
G01X2816836D02*
Y401816D01*
X2819263Y395566D01*
X2821690Y401816D01*
Y394316D01*
G01X2832490D02*
Y401816D01*
X2836036D01*
G01X2834730Y398191D02*
X2832490D01*
G01X2840643Y401816D02*
X2842883D01*
G01X2841763D02*
Y394316D01*
G01X2840643D02*
X2842883D01*
G01X2847116D02*
Y401816D01*
X2851410Y394316D01*
Y401816D01*
G01X2855643D02*
X2857883D01*
G01X2856763D02*
Y394316D01*
G01X2855643D02*
X2857883D01*
G01X2862303Y395316D02*
X2863050Y394691D01*
X2863890Y394316D01*
X2864636D01*
X2865383Y394691D01*
X2865943Y395316D01*
X2866223Y396191D01*
X2866036Y397066D01*
X2865570Y397816D01*
X2864730Y398316D01*
X2863610Y398566D01*
X2862956Y399066D01*
X2862676Y399941D01*
X2862863Y400816D01*
X2863330Y401441D01*
X2863983Y401816D01*
X2864636D01*
X2865290Y401566D01*
X2865850Y400941D01*
G01X2869803Y394316D02*
Y401816D01*
G01X2873723D02*
Y394316D01*
G01Y398066D02*
X2869803D01*
G01X2881130Y394316D02*
X2877396D01*
Y401816D01*
X2881130D01*
G01X2879636Y398191D02*
X2877396D01*
G01X2884710Y394316D02*
Y401816D01*
X2886576D01*
X2887323Y401441D01*
X2887883Y400941D01*
X2888350Y400191D01*
X2888723Y399316D01*
X2888816Y398066D01*
X2888723Y396816D01*
X2888350Y395941D01*
X2887883Y395191D01*
X2887323Y394691D01*
X2886576Y394316D01*
X2884710D01*
G01X2899896D02*
Y401816D01*
X2902136D01*
X2902883Y401441D01*
X2903443Y400566D01*
X2903630Y399566D01*
X2903443Y398566D01*
X2902976Y397816D01*
X2902136Y397441D01*
X2899896D01*
G01X2909263Y401816D02*
Y394316D01*
G01X2907116Y401816D02*
X2911410D01*
G01X2914803Y394316D02*
Y401816D01*
G01X2918723D02*
Y394316D01*
G01Y398066D02*
X2914803D01*
G01X2930643Y401816D02*
X2932883D01*
G01X2931763D02*
Y394316D01*
G01X2930643D02*
X2932883D01*
G01X2937303Y395316D02*
X2938050Y394691D01*
X2938890Y394316D01*
X2939636D01*
X2940383Y394691D01*
X2940943Y395316D01*
X2941223Y396191D01*
X2941036Y397066D01*
X2940570Y397816D01*
X2939730Y398316D01*
X2938610Y398566D01*
X2937956Y399066D01*
X2937676Y399941D01*
X2937863Y400816D01*
X2938330Y401441D01*
X2938983Y401816D01*
X2939636D01*
X2940290Y401566D01*
X2940850Y400941D01*
G01X2954263Y394316D02*
Y401816D01*
X2953143Y400316D01*
G01Y394316D02*
X2955383D01*
G01X2961763Y394066D02*
X2961576Y394191D01*
Y394441D01*
X2961763Y394566D01*
X2961950Y394441D01*
Y394191D01*
X2961763Y394066D01*
G01X2969263Y394316D02*
Y401816D01*
X2968143Y400316D01*
G01Y394316D02*
X2970383D01*
G01X2974710Y395441D02*
X2975270Y394816D01*
X2975923Y394441D01*
X2976763Y394316D01*
X2977603Y394566D01*
X2978256Y395066D01*
X2978723Y395941D01*
X2978816Y396941D01*
X2978630Y397941D01*
X2978163Y398566D01*
X2977510Y399066D01*
X2976856Y399191D01*
X2976203Y399066D01*
X2975363Y398566D01*
X2975643Y401816D01*
X2978163D01*
G01X2983236Y396816D02*
X2985476D01*
G01X2984263Y398441D02*
Y395191D01*
G01X2990083Y394066D02*
X2993443Y401816D01*
G01X2998050Y396816D02*
X3000476D01*
G01X3006763Y401816D02*
X3006016Y401566D01*
X3005456Y400941D01*
X3005083Y400191D01*
X3004803Y399191D01*
X3004710Y398066D01*
X3004803Y396941D01*
X3005083Y395941D01*
X3005456Y395191D01*
X3006016Y394566D01*
X3006763Y394316D01*
X3007510Y394566D01*
X3008070Y395191D01*
X3008443Y395941D01*
X3008723Y396941D01*
X3008816Y398066D01*
X3008723Y399191D01*
X3008443Y400191D01*
X3008070Y400941D01*
X3007510Y401566D01*
X3006763Y401816D01*
G01X3014263Y394066D02*
X3014076Y394191D01*
Y394441D01*
X3014263Y394566D01*
X3014450Y394441D01*
Y394191D01*
X3014263Y394066D01*
G01X3021763Y401816D02*
X3021016Y401566D01*
X3020456Y400941D01*
X3020083Y400191D01*
X3019803Y399191D01*
X3019710Y398066D01*
X3019803Y396941D01*
X3020083Y395941D01*
X3020456Y395191D01*
X3021016Y394566D01*
X3021763Y394316D01*
X3022510Y394566D01*
X3023070Y395191D01*
X3023443Y395941D01*
X3023723Y396941D01*
X3023816Y398066D01*
X3023723Y399191D01*
X3023443Y400191D01*
X3023070Y400941D01*
X3022510Y401566D01*
X3021763Y401816D01*
G01X3027490Y400566D02*
X3028050Y401316D01*
X3028703Y401691D01*
X3029450Y401816D01*
X3030383Y401566D01*
X3031036Y400941D01*
X3031223Y400191D01*
X3031130Y399441D01*
X3030756Y398816D01*
X3028890Y397566D01*
X3028050Y396691D01*
X3027490Y395441D01*
X3027303Y394316D01*
X3031223D01*
G01X3034710Y395441D02*
X3035270Y394816D01*
X3035923Y394441D01*
X3036763Y394316D01*
X3037603Y394566D01*
X3038256Y395066D01*
X3038723Y395941D01*
X3038816Y396941D01*
X3038630Y397941D01*
X3038163Y398566D01*
X3037510Y399066D01*
X3036856Y399191D01*
X3036203Y399066D01*
X3035363Y398566D01*
X3035643Y401816D01*
X3038163D01*
G01X3041836Y394316D02*
Y401816D01*
X3044263Y395566D01*
X3046690Y401816D01*
Y394316D01*
G01X3049336D02*
Y401816D01*
X3051763Y395566D01*
X3054190Y401816D01*
Y394316D01*
G01X3059263Y394066D02*
X3059076Y394191D01*
Y394441D01*
X3059263Y394566D01*
X3059450Y394441D01*
Y394191D01*
X3059263Y394066D01*
G54D13*
X118111Y47244D03*
Y535433D03*
X511811Y47244D03*
X905512D03*
X988500Y228000D03*
X1030500Y542500D03*
X1911126Y133709D03*
G54D22*
X208071Y267204D03*
X200197D03*
X215945D03*
X231693D03*
X223819D03*
X239567D03*
X247441D03*
X357677D03*
X365551D03*
X373425D03*
X389173D03*
X381299D03*
X404921D03*
X397047D03*
X523032D03*
X515158D03*
X530906D03*
X538780D03*
X546654D03*
X562402D03*
X554528D03*
X680513D03*
X672639D03*
X688387D03*
X704135D03*
X696261D03*
X712009D03*
X719883D03*
X1911126Y473909D03*
G54D23*
X193819Y477204D03*
X223819D03*
X253819D03*
X351299D03*
X381299D03*
X411299D03*
X508780D03*
X538780D03*
X568780D03*
X666261D03*
X696261D03*
X726261D03*
X1911126Y247109D03*
G54D14*
X19922Y214173D03*
Y367716D03*
X1911126Y20309D03*
G54D15*
X38780Y232598D03*
Y239291D03*
Y252598D03*
Y259291D03*
Y272598D03*
Y279291D03*
Y292598D03*
Y299291D03*
X48780Y232598D03*
Y239291D03*
Y252598D03*
Y259291D03*
Y272598D03*
Y279291D03*
Y292598D03*
Y299291D03*
X1911126Y360509D03*
G54D24*
X249252Y129685D03*
X529252D03*
X665059Y149408D03*
X980059D03*
X1226024Y174429D03*
Y399429D03*
X1911126Y-55291D03*
G54D16*
X33780Y334724D03*
Y324724D03*
Y314724D03*
X38780Y319724D03*
Y329724D03*
Y339724D03*
X33780Y344724D03*
X38780Y349724D03*
X48780Y319724D03*
Y329724D03*
Y339724D03*
X43780Y314724D03*
Y324724D03*
Y334724D03*
X48780Y349724D03*
X43780Y344724D03*
X1911126Y511709D03*
G54D25*
X268000Y220315D03*
Y240000D03*
X312500Y220315D03*
Y240000D03*
X357000Y220315D03*
Y240000D03*
X428500Y220315D03*
Y240000D03*
X472500Y220315D03*
Y240000D03*
X516500Y220315D03*
Y240000D03*
X578500Y220315D03*
Y240000D03*
X622500Y220315D03*
Y240000D03*
X666500Y220315D03*
Y240000D03*
X735981Y220315D03*
Y240000D03*
X779981Y220315D03*
Y240000D03*
X823981Y220315D03*
Y240000D03*
X1911126Y436109D03*
G54D17*
X60630Y99724D03*
Y482205D03*
X82795Y99724D03*
Y482205D03*
X108858Y99724D03*
Y482205D03*
X1911126Y-93091D03*
G54D26*
X296752Y129685D03*
Y139685D03*
Y149685D03*
Y159685D03*
X331752Y129685D03*
X306752D03*
X331752Y139685D03*
Y149685D03*
Y159685D03*
X306752Y139685D03*
Y149685D03*
Y159685D03*
X341752Y129685D03*
Y139685D03*
Y149685D03*
Y159685D03*
X376752Y129685D03*
X366752D03*
X376752Y139685D03*
Y149685D03*
Y159685D03*
X366752Y139685D03*
Y149685D03*
Y159685D03*
X411752Y129685D03*
X401752D03*
X411752Y139685D03*
Y149685D03*
Y159685D03*
X401752Y139685D03*
Y149685D03*
Y159685D03*
X446752Y129685D03*
X436752D03*
X446752Y139685D03*
Y149685D03*
Y159685D03*
X436752Y139685D03*
Y149685D03*
Y159685D03*
X481752Y129685D03*
X471752D03*
X481752Y139685D03*
Y149685D03*
Y159685D03*
X471752Y139685D03*
Y149685D03*
Y159685D03*
X712559Y129408D03*
Y119408D03*
Y149408D03*
Y139408D03*
X722559Y129408D03*
Y119408D03*
X747559Y129408D03*
Y119408D03*
X722559Y149408D03*
Y139408D03*
X747559Y149408D03*
Y139408D03*
X757559Y129408D03*
Y119408D03*
Y149408D03*
Y139408D03*
X782559Y129408D03*
Y119408D03*
X792559Y129408D03*
Y119408D03*
X782559Y149408D03*
Y139408D03*
X792559Y149408D03*
Y139408D03*
X812559Y119408D03*
Y129408D03*
X822559Y119408D03*
Y129408D03*
X832559Y119408D03*
Y129408D03*
X812559Y139408D03*
Y149408D03*
X822559Y139408D03*
Y149408D03*
X832559Y139408D03*
Y149408D03*
X852559Y129408D03*
Y119408D03*
X862559Y129408D03*
Y119408D03*
X852559Y149408D03*
Y139408D03*
X862559Y149408D03*
Y139408D03*
X887559Y129408D03*
Y119408D03*
Y149408D03*
Y139408D03*
X897559Y129408D03*
Y119408D03*
X922559Y129408D03*
Y119408D03*
X897559Y149408D03*
Y139408D03*
X922559Y149408D03*
Y139408D03*
X932559Y129408D03*
Y119408D03*
Y149408D03*
Y139408D03*
X1226024Y221929D03*
X1236024D03*
X1246024D03*
X1226024Y231929D03*
X1236024D03*
X1246024D03*
X1226024Y256929D03*
X1236024D03*
X1246024D03*
X1226024Y266929D03*
X1236024D03*
X1246024D03*
X1226024Y286929D03*
X1236024D03*
X1246024D03*
X1226024Y306929D03*
X1236024D03*
X1246024D03*
X1226024Y316929D03*
X1236024D03*
X1246024D03*
X1226024Y341929D03*
X1236024D03*
X1246024D03*
X1226024Y351929D03*
X1236024D03*
X1246024D03*
X1256024Y221929D03*
Y231929D03*
Y256929D03*
Y266929D03*
Y286929D03*
Y306929D03*
Y316929D03*
Y341929D03*
Y351929D03*
X1911126Y398309D03*
G54D27*
X753314Y607542D03*
X766498Y602542D03*
X753420Y635687D03*
X766604Y630687D03*
X766498Y612542D03*
X766604Y640687D03*
X1096017Y607542D03*
X1082833Y602542D03*
Y612542D03*
X1096017Y635687D03*
X1082833Y630687D03*
Y640687D03*
X1911126Y209309D03*
G54D18*
X154840Y244730D03*
X178265Y213443D03*
X175976Y218775D03*
X166068Y238749D03*
X173869Y228168D03*
X160017Y237764D03*
X183539Y518000D03*
Y498000D03*
X171939D03*
Y518000D03*
X246000Y238500D03*
X231539Y518000D03*
Y498000D03*
X219939D03*
Y518000D03*
X267939Y498000D03*
Y518000D03*
X279539D03*
Y498000D03*
X329419D03*
Y518000D03*
X341019D03*
Y498000D03*
X389019Y518000D03*
Y498000D03*
X377419D03*
Y518000D03*
X402000Y238000D03*
X398500Y247000D03*
X437019Y518000D03*
Y498000D03*
X425419D03*
Y518000D03*
X498500Y498000D03*
Y518000D03*
X486900Y498000D03*
Y518000D03*
X534900Y498000D03*
Y518000D03*
X546500Y498000D03*
Y518000D03*
X594500Y498000D03*
Y518000D03*
X582900D03*
Y498000D03*
X647975Y37000D03*
X660200Y56800D03*
X652300D03*
X655981Y518000D03*
Y498000D03*
X644381Y518000D03*
Y498000D03*
X684525Y32500D03*
X690075Y39500D03*
X683600Y56800D03*
X676000D03*
X668100D03*
X680400Y310500D03*
X703740Y41000D03*
X707000Y32000D03*
X694425Y29500D03*
X693000Y56600D03*
X706000Y61975D03*
X703740Y54118D03*
X703981Y518000D03*
Y498000D03*
X692381Y518000D03*
Y498000D03*
X740381Y518000D03*
Y498000D03*
X761560Y38500D03*
Y30000D03*
Y55500D03*
Y47000D03*
Y64000D03*
X754000Y356957D03*
X751981Y498000D03*
Y518000D03*
X784855Y265184D03*
X790000Y259612D03*
X794900Y265979D03*
X806000Y265075D03*
X792000Y358000D03*
X833500Y268575D03*
X816000Y270525D03*
X827602Y283500D03*
X836500Y302500D03*
X819500Y318500D03*
X831750Y318250D03*
X827000Y352500D03*
X843500Y268575D03*
X853500D03*
X853000Y303500D03*
X845000Y303000D03*
X848500Y335800D03*
X843843Y354342D03*
X849000Y399000D03*
X870000Y304525D03*
X880000D03*
X870000Y312788D03*
X880000Y312855D03*
X875000Y347273D03*
X869000Y360500D03*
X905941Y320366D03*
X916260Y355000D03*
X910992Y361075D03*
X923740Y345500D03*
X940000Y283800D03*
X935516Y361075D03*
X933357Y344843D03*
X933196Y353360D03*
X1034500Y145000D03*
X1043936Y145745D03*
X1019040Y157310D03*
X1022168Y161783D03*
X1017909Y151424D03*
X1016614Y190267D03*
X1039016Y189075D03*
Y183027D03*
X1022000Y171200D03*
X1019700Y166600D03*
X1049356Y143900D03*
X1054500Y148500D03*
X1073154Y140800D03*
X1057500Y155877D03*
X1062500Y191500D03*
X1067701Y270442D03*
X1061600Y276242D03*
X1067679Y317942D03*
X1061600Y323742D03*
X1067707Y365442D03*
X1067531Y412942D03*
X1067730Y460352D03*
X1061600Y466242D03*
X1067866Y507629D03*
X1061600Y513742D03*
X1066500Y538000D03*
Y553000D03*
X1092000Y82500D03*
X1082000Y143600D03*
X1094500Y143144D03*
X1130125Y135940D03*
X1121238Y144500D03*
X1120524Y138457D03*
X1123500Y187000D03*
X1108000Y172000D03*
X1113368Y171619D03*
X1110800Y170000D03*
X1113129Y165719D03*
X1114500Y188700D03*
X1133000Y198000D03*
X1117206Y231741D03*
X1117290Y224241D03*
X1106106Y231741D03*
X1114452Y538000D03*
X1123669D03*
X1114452Y553000D03*
X1123669D03*
X1158200Y137700D03*
X1143490Y183560D03*
X1152500Y186500D03*
X1135203Y266860D03*
X1135403Y314360D03*
Y361979D03*
X1135190Y408965D03*
X1135404Y457228D03*
X1135622Y467732D03*
X1188600Y166000D03*
X1177521Y165952D03*
X1165070Y328750D03*
X1193411D03*
X1177836Y349234D03*
X1165190Y471250D03*
X1179500Y476750D03*
Y469750D03*
X1177925Y491734D03*
X1193840Y471250D03*
X1911126Y587309D03*
G54D28*
X1011000Y98000D03*
Y118000D03*
Y108000D03*
X1161000Y90400D03*
X1151000D03*
X1171000D03*
X1911126Y284909D03*
G54D19*
X175000Y100500D03*
X877510Y558620D03*
X964460Y16950D03*
X1911126Y-17491D03*
G54D29*
X1240158Y57480D03*
Y521260D03*
X1911126Y58109D03*
M02*
